G04 ================== begin FILE IDENTIFICATION RECORD ==================*
G04 Layout Name:  F:/<user>/2022/FB/R4006-TIMING/brd/gerber-3/R4006-B0001-02_R01.brd*
G04 Film Name:    R4006-B0001-02_R01_TAS*
G04 File Format:  Gerber RS274X*
G04 File Origin:  Cadence Allegro 17.2-S079*
G04 Origin Date:  Fri Feb 25 18:14:43 2022*
G04 *
G04 Layer:  PACKAGE GEOMETRY/ASSEMBLY_TOP*
G04 Layer:  BOARD GEOMETRY/OUTLINE*
G04 Layer:  REF DES/ASSEMBLY_TOP*
G04 Layer:  MANUFACTURING/CELESTICA_LEGEND*
G04 *
G04 Offset:    (0.00 0.00)*
G04 Mirror:    No*
G04 Mode:      Positive*
G04 Rotation:  0*
G04 FullContactRelief:  No*
G04 UndefLineWidth:     6.00*
G04 ================== end FILE IDENTIFICATION RECORD ====================*
%FSLAX55Y55*MOIN*%
%IR0*IPPOS*OFA0.00000B0.00000*MIA0B0*SFA1.00000B1.00000*%
%ADD10C,.01*%
%ADD11C,.005*%
%ADD12C,.006*%
G75*
%LPD*%
G75*
G36*
G01X-698Y93960D02*
X204Y95160D01*
Y94260D01*
X1104D01*
Y93660D01*
X204D01*
Y92760D01*
X-698Y93960D01*
G37*
G36*
G01X-781Y100466D02*
X121Y101666D01*
Y100766D01*
X1021D01*
Y100166D01*
X121D01*
Y99266D01*
X-781Y100466D01*
G37*
G36*
G01Y157553D02*
X121Y158753D01*
Y157853D01*
X1021D01*
Y157253D01*
X121D01*
Y156353D01*
X-781Y157553D01*
G37*
G36*
G01X-698Y151047D02*
X204Y152247D01*
Y151347D01*
X1104D01*
Y150747D01*
X204D01*
Y149847D01*
X-698Y151047D01*
G37*
G36*
G01X-781Y214640D02*
X121Y215840D01*
Y214940D01*
X1021D01*
Y214340D01*
X121D01*
Y213440D01*
X-781Y214640D01*
G37*
G36*
G01X-698Y208134D02*
X204Y209334D01*
Y208434D01*
X1104D01*
Y207834D01*
X204D01*
Y206934D01*
X-698Y208134D01*
G37*
G36*
G01Y265220D02*
X204Y266420D01*
Y265520D01*
X1104D01*
Y264920D01*
X204D01*
Y264020D01*
X-698Y265220D01*
G37*
G36*
G01X-781Y271726D02*
X121Y272926D01*
Y272026D01*
X1021D01*
Y271426D01*
X121D01*
Y270526D01*
X-781Y271726D01*
G37*
G36*
G01Y328813D02*
X121Y330013D01*
Y329113D01*
X1021D01*
Y328513D01*
X121D01*
Y327613D01*
X-781Y328813D01*
G37*
G36*
G01X-698Y322307D02*
X204Y323507D01*
Y322607D01*
X1104D01*
Y322007D01*
X204D01*
Y321107D01*
X-698Y322307D01*
G37*
G36*
G01X21300Y98500D02*
G02I-750J0D01*
G37*
G36*
G01Y212500D02*
G02I-750J0D01*
G37*
G36*
G01X59993Y78915D02*
G02I-1500J0D01*
G37*
G36*
G01X59493Y136001D02*
G02I-1500J0D01*
G37*
G36*
G01X61500Y193000D02*
G02I-1500J0D01*
G37*
G36*
G01Y250500D02*
G02I-1500J0D01*
G37*
G36*
G01X79900Y229800D02*
G03I-1500J0D01*
G37*
G36*
G01X68851Y343622D02*
G02I-591J0D01*
G37*
G36*
G01X83000Y89800D02*
G03I-1500J0D01*
G37*
G36*
G01X83675Y274501D02*
G02I-1999J0D01*
G37*
G36*
G01X100612Y72840D02*
G02I-590J0D01*
G37*
G36*
G01X130320Y365070D02*
G03I-2000J0D01*
G37*
G36*
G01X132584Y396500D02*
G03I-1500J0D01*
G37*
G36*
G01X157947Y305528D02*
G02I-1500J0D01*
G37*
G36*
G01X167543Y314343D02*
Y319657D01*
X165543D01*
Y314343D01*
X167543D01*
G37*
G36*
G01Y324343D02*
Y329657D01*
X165543D01*
Y324343D01*
X167543D01*
G37*
G36*
G01X182327Y59023D02*
G02I-1500J0D01*
G37*
G36*
G01X218700Y321400D02*
G03I-1500J0D01*
G37*
G36*
G01X272452Y63470D02*
G03I-1500J0D01*
G37*
G36*
G01X323738Y323854D02*
G03I-1576J1D01*
G37*
G36*
G01X352674Y184725D02*
G02I-1500J0D01*
G37*
G36*
G01X354109Y242203D02*
G02I-2000J0D01*
G37*
G36*
G01X373831Y258378D02*
G02I-591J0D01*
G37*
G36*
G01X382440Y126510D02*
G03I-2500J0D01*
G37*
G36*
G01X388672Y282947D02*
G02I-1500J0D01*
G37*
G36*
G01X403400Y352800D02*
G03I-1500J0D01*
G37*
G36*
G01X411113Y375146D02*
G03I-1575J-1D01*
G37*
G36*
G01X424513Y323246D02*
G03I-1575J-1D01*
G37*
G36*
G01X422900Y353000D02*
G03I-1500J0D01*
G37*
G36*
G01X431001Y393000D02*
G02I-2000J0D01*
G37*
G36*
G01X448500Y280501D02*
G02I-1999J0D01*
G37*
G36*
G01X440536Y347129D02*
G03I-1500J0D01*
G37*
G36*
G01X496113Y90646D02*
G03I-1575J-1D01*
G37*
G36*
G01X523853Y266672D02*
G02I-1500J0D01*
G37*
G36*
G01X555947Y72928D02*
G02I-1500J0D01*
G37*
G36*
G01X568203Y365826D02*
G02I-2001J0D01*
G37*
G36*
G01X594500Y200000D02*
G02I-2000J0D01*
G37*
G36*
G01X592520Y407480D02*
X588976D01*
Y409480D01*
X592520D01*
Y407480D01*
G37*
G36*
G01X604331D02*
X600787D01*
Y409480D01*
X604331D01*
Y407480D01*
G37*
G36*
G01X615100Y108200D02*
G03I-1500J0D01*
G37*
G36*
G01X616142Y407480D02*
X612598D01*
Y409480D01*
X616142D01*
Y407480D01*
G37*
G36*
G01X631320Y227212D02*
G02I-591J0D01*
G37*
G36*
G01X526528Y414654D02*
Y416654D01*
X530072D01*
Y414654D01*
X526528D01*
G37*
G36*
G01X541732Y407480D02*
Y409480D01*
X545276D01*
Y407480D01*
X541732D01*
G37*
G36*
G01Y421259D02*
Y423259D01*
X545276D01*
Y421259D01*
X541732D01*
G37*
G36*
G01X565354Y407480D02*
Y409480D01*
X568898D01*
Y407480D01*
X565354D01*
G37*
G36*
G01X557087Y409480D02*
Y407480D01*
X553543D01*
Y409480D01*
X557087D01*
G37*
G36*
G01X553543Y421259D02*
Y423259D01*
X557087D01*
Y421259D01*
X553543D01*
G37*
G36*
G01X565354D02*
Y423259D01*
X568898D01*
Y421259D01*
X565354D01*
G37*
G36*
G01X577165Y407480D02*
Y409480D01*
X580709D01*
Y407480D01*
X577165D01*
G37*
G36*
G01Y421259D02*
Y423259D01*
X580709D01*
Y421259D01*
X577165D01*
G37*
G36*
G01X600787D02*
Y423259D01*
X604331D01*
Y421259D01*
X600787D01*
G37*
G36*
G01X612598D02*
Y423259D01*
X616142D01*
Y421259D01*
X612598D01*
G37*
G54D10*
G01X136000Y-65500D02*
Y-158000D01*
X506000D01*
Y-65500D01*
X136000D01*
G01X316000D02*
Y-158000D01*
G54D11*
G01X329433Y-125500D02*
Y-133000D01*
X333167D01*
G01X340480D02*
Y-128000D01*
G01Y-128875D02*
X340107Y-128375D01*
X339547Y-128125D01*
X338893Y-128000D01*
X338240Y-128250D01*
X337680Y-128750D01*
X337307Y-129500D01*
X337120Y-130500D01*
X337307Y-131500D01*
X337680Y-132250D01*
X338240Y-132750D01*
X338893Y-133000D01*
X339547Y-132875D01*
X340107Y-132500D01*
X340480Y-132000D01*
G01X344340Y-135250D02*
X344900Y-135500D01*
X345647Y-135250D01*
X346113Y-134750D01*
X346487Y-134125D01*
X347047Y-132125D01*
X348260Y-128000D01*
G01X345273D02*
X347047Y-132125D01*
G01X352400Y-129625D02*
X355387D01*
X355107Y-128750D01*
X354640Y-128250D01*
X353987Y-128000D01*
X353333Y-128125D01*
X352773Y-128500D01*
X352400Y-129375D01*
X352213Y-130125D01*
Y-130875D01*
X352400Y-131625D01*
X352867Y-132375D01*
X353427Y-132875D01*
X354080Y-133000D01*
X354733Y-132750D01*
X355387Y-132000D01*
G01X359993Y-133000D02*
Y-128000D01*
G01Y-129000D02*
X360460Y-128500D01*
X360927Y-128125D01*
X361580Y-128000D01*
X362047Y-128125D01*
X362607Y-128500D01*
G01X368800Y-133250D02*
X368613Y-133125D01*
Y-132875D01*
X368800Y-132750D01*
X368987Y-132875D01*
Y-133125D01*
X368800Y-133250D01*
G01Y-129875D02*
X368613Y-129750D01*
Y-129500D01*
X368800Y-129375D01*
X368987Y-129500D01*
Y-129750D01*
X368800Y-129875D01*
G01X336747Y-120500D02*
Y-113000D01*
X338613D01*
X339360Y-113375D01*
X339920Y-113875D01*
X340387Y-114625D01*
X340760Y-115500D01*
X340853Y-116750D01*
X340760Y-118000D01*
X340387Y-118875D01*
X339920Y-119625D01*
X339360Y-120125D01*
X338613Y-120500D01*
X336747D01*
G01X347980D02*
Y-115500D01*
G01Y-116375D02*
X347607Y-115875D01*
X347047Y-115625D01*
X346393Y-115500D01*
X345740Y-115750D01*
X345180Y-116250D01*
X344807Y-117000D01*
X344620Y-118000D01*
X344807Y-119000D01*
X345180Y-119750D01*
X345740Y-120250D01*
X346393Y-120500D01*
X347047Y-120375D01*
X347607Y-120000D01*
X347980Y-119500D01*
G01X353800Y-113000D02*
Y-120500D01*
G01X352493Y-115500D02*
X355107D01*
G01X359900Y-117125D02*
X362887D01*
X362607Y-116250D01*
X362140Y-115750D01*
X361487Y-115500D01*
X360833Y-115625D01*
X360273Y-116000D01*
X359900Y-116875D01*
X359713Y-117625D01*
Y-118375D01*
X359900Y-119125D01*
X360367Y-119875D01*
X360927Y-120375D01*
X361580Y-120500D01*
X362233Y-120250D01*
X362887Y-119500D01*
G01X368800Y-120750D02*
X368613Y-120625D01*
Y-120375D01*
X368800Y-120250D01*
X368987Y-120375D01*
Y-120625D01*
X368800Y-120750D01*
G01Y-117375D02*
X368613Y-117250D01*
Y-117000D01*
X368800Y-116875D01*
X368987Y-117000D01*
Y-117250D01*
X368800Y-117375D01*
G01X382027Y-114250D02*
X382587Y-113500D01*
X383240Y-113125D01*
X383987Y-113000D01*
X384920Y-113250D01*
X385573Y-113875D01*
X385760Y-114625D01*
X385667Y-115375D01*
X385293Y-116000D01*
X383427Y-117250D01*
X382587Y-118125D01*
X382027Y-119375D01*
X381840Y-120500D01*
X385760D01*
G01X391300Y-113000D02*
X390553Y-113250D01*
X389993Y-113875D01*
X389620Y-114625D01*
X389340Y-115625D01*
X389247Y-116750D01*
X389340Y-117875D01*
X389620Y-118875D01*
X389993Y-119625D01*
X390553Y-120250D01*
X391300Y-120500D01*
X392047Y-120250D01*
X392607Y-119625D01*
X392980Y-118875D01*
X393260Y-117875D01*
X393353Y-116750D01*
X393260Y-115625D01*
X392980Y-114625D01*
X392607Y-113875D01*
X392047Y-113250D01*
X391300Y-113000D01*
G01X397027Y-114250D02*
X397587Y-113500D01*
X398240Y-113125D01*
X398987Y-113000D01*
X399920Y-113250D01*
X400573Y-113875D01*
X400760Y-114625D01*
X400667Y-115375D01*
X400293Y-116000D01*
X398427Y-117250D01*
X397587Y-118125D01*
X397027Y-119375D01*
X396840Y-120500D01*
X400760D01*
G01X404527Y-114250D02*
X405087Y-113500D01*
X405740Y-113125D01*
X406487Y-113000D01*
X407420Y-113250D01*
X408073Y-113875D01*
X408260Y-114625D01*
X408167Y-115375D01*
X407793Y-116000D01*
X405927Y-117250D01*
X405087Y-118125D01*
X404527Y-119375D01*
X404340Y-120500D01*
X408260D01*
G01X412587Y-118000D02*
X415013D01*
G01X421300Y-113000D02*
X420553Y-113250D01*
X419993Y-113875D01*
X419620Y-114625D01*
X419340Y-115625D01*
X419247Y-116750D01*
X419340Y-117875D01*
X419620Y-118875D01*
X419993Y-119625D01*
X420553Y-120250D01*
X421300Y-120500D01*
X422047Y-120250D01*
X422607Y-119625D01*
X422980Y-118875D01*
X423260Y-117875D01*
X423353Y-116750D01*
X423260Y-115625D01*
X422980Y-114625D01*
X422607Y-113875D01*
X422047Y-113250D01*
X421300Y-113000D01*
G01X427027Y-114250D02*
X427587Y-113500D01*
X428240Y-113125D01*
X428987Y-113000D01*
X429920Y-113250D01*
X430573Y-113875D01*
X430760Y-114625D01*
X430667Y-115375D01*
X430293Y-116000D01*
X428427Y-117250D01*
X427587Y-118125D01*
X427027Y-119375D01*
X426840Y-120500D01*
X430760D01*
G01X435087Y-118000D02*
X437513D01*
G01X442027Y-114250D02*
X442587Y-113500D01*
X443240Y-113125D01*
X443987Y-113000D01*
X444920Y-113250D01*
X445573Y-113875D01*
X445760Y-114625D01*
X445667Y-115375D01*
X445293Y-116000D01*
X443427Y-117250D01*
X442587Y-118125D01*
X442027Y-119375D01*
X441840Y-120500D01*
X445760D01*
G01X449247Y-119375D02*
X449807Y-120000D01*
X450460Y-120375D01*
X451300Y-120500D01*
X452140Y-120250D01*
X452793Y-119750D01*
X453260Y-118875D01*
X453353Y-117875D01*
X453167Y-116875D01*
X452700Y-116250D01*
X452047Y-115750D01*
X451393Y-115625D01*
X450740Y-115750D01*
X449900Y-116250D01*
X450180Y-113000D01*
X452700D01*
G01X336933Y-108000D02*
Y-100500D01*
X339267D01*
X340013Y-100875D01*
X340480Y-101375D01*
X340667Y-102375D01*
X340480Y-103375D01*
X339920Y-104000D01*
X339267Y-104375D01*
X336933D01*
G01X339267D02*
X340667Y-108000D01*
G01X344900Y-104625D02*
X347887D01*
X347607Y-103750D01*
X347140Y-103250D01*
X346487Y-103000D01*
X345833Y-103125D01*
X345273Y-103500D01*
X344900Y-104375D01*
X344713Y-105125D01*
Y-105875D01*
X344900Y-106625D01*
X345367Y-107375D01*
X345927Y-107875D01*
X346580Y-108000D01*
X347233Y-107750D01*
X347887Y-107000D01*
G01X352120Y-103000D02*
X353800Y-108000D01*
X355480Y-103000D01*
G01X368800Y-108250D02*
X368613Y-108125D01*
Y-107875D01*
X368800Y-107750D01*
X368987Y-107875D01*
Y-108125D01*
X368800Y-108250D01*
G01Y-104875D02*
X368613Y-104750D01*
Y-104500D01*
X368800Y-104375D01*
X368987Y-104500D01*
Y-104750D01*
X368800Y-104875D01*
G01X383800Y-100500D02*
X383053Y-100750D01*
X382493Y-101375D01*
X382120Y-102125D01*
X381840Y-103125D01*
X381747Y-104250D01*
X381840Y-105375D01*
X382120Y-106375D01*
X382493Y-107125D01*
X383053Y-107750D01*
X383800Y-108000D01*
X384547Y-107750D01*
X385107Y-107125D01*
X385480Y-106375D01*
X385760Y-105375D01*
X385853Y-104250D01*
X385760Y-103125D01*
X385480Y-102125D01*
X385107Y-101375D01*
X384547Y-100750D01*
X383800Y-100500D01*
G01X391300Y-108000D02*
Y-100500D01*
X390180Y-102000D01*
G01Y-108000D02*
X392420D01*
G01X336933Y-95500D02*
Y-88000D01*
X339173D01*
X339920Y-88375D01*
X340480Y-89250D01*
X340667Y-90250D01*
X340480Y-91250D01*
X340013Y-92000D01*
X339173Y-92375D01*
X336933D01*
G01X344620Y-95750D02*
X347980Y-88000D01*
G01X351653Y-95500D02*
Y-88000D01*
X355947Y-95500D01*
Y-88000D01*
G01X368800Y-95750D02*
X368613Y-95625D01*
Y-95375D01*
X368800Y-95250D01*
X368987Y-95375D01*
Y-95625D01*
X368800Y-95750D01*
G01Y-92375D02*
X368613Y-92250D01*
Y-92000D01*
X368800Y-91875D01*
X368987Y-92000D01*
Y-92250D01*
X368800Y-92375D01*
G01X381933Y-95500D02*
Y-88000D01*
X384267D01*
X385013Y-88375D01*
X385480Y-88875D01*
X385667Y-89875D01*
X385480Y-90875D01*
X384920Y-91500D01*
X384267Y-91875D01*
X381933D01*
G01X384267D02*
X385667Y-95500D01*
G01X392420D02*
Y-88000D01*
X388967Y-93375D01*
X393633D01*
G01X398800Y-88000D02*
X398053Y-88250D01*
X397493Y-88875D01*
X397120Y-89625D01*
X396840Y-90625D01*
X396747Y-91750D01*
X396840Y-92875D01*
X397120Y-93875D01*
X397493Y-94625D01*
X398053Y-95250D01*
X398800Y-95500D01*
X399547Y-95250D01*
X400107Y-94625D01*
X400480Y-93875D01*
X400760Y-92875D01*
X400853Y-91750D01*
X400760Y-90625D01*
X400480Y-89625D01*
X400107Y-88875D01*
X399547Y-88250D01*
X398800Y-88000D01*
G01X406300D02*
X405553Y-88250D01*
X404993Y-88875D01*
X404620Y-89625D01*
X404340Y-90625D01*
X404247Y-91750D01*
X404340Y-92875D01*
X404620Y-93875D01*
X404993Y-94625D01*
X405553Y-95250D01*
X406300Y-95500D01*
X407047Y-95250D01*
X407607Y-94625D01*
X407980Y-93875D01*
X408260Y-92875D01*
X408353Y-91750D01*
X408260Y-90625D01*
X407980Y-89625D01*
X407607Y-88875D01*
X407047Y-88250D01*
X406300Y-88000D01*
G01X412027Y-92375D02*
X412680Y-91500D01*
X413240Y-91000D01*
X413987Y-90750D01*
X414640Y-91000D01*
X415107Y-91500D01*
X415480Y-92250D01*
X415573Y-93125D01*
X415480Y-93875D01*
X415107Y-94625D01*
X414547Y-95250D01*
X413893Y-95500D01*
X413147Y-95250D01*
X412493Y-94500D01*
X412120Y-93375D01*
X412027Y-92125D01*
X412213Y-90500D01*
X412493Y-89625D01*
X412960Y-88750D01*
X413613Y-88125D01*
X414267Y-88000D01*
X414920Y-88250D01*
X415387Y-88875D01*
G01X420087Y-93000D02*
X422513D01*
G01X429547Y-91500D02*
X429920Y-91125D01*
X430200Y-90500D01*
X430387Y-89625D01*
X430200Y-88875D01*
X429827Y-88375D01*
X429173Y-88000D01*
X426653D01*
Y-95500D01*
X429733D01*
X430387Y-95000D01*
X430760Y-94250D01*
X430947Y-93375D01*
X430760Y-92500D01*
X430200Y-91750D01*
X429547Y-91500D01*
X426653D01*
G01X436300Y-88000D02*
X435553Y-88250D01*
X434993Y-88875D01*
X434620Y-89625D01*
X434340Y-90625D01*
X434247Y-91750D01*
X434340Y-92875D01*
X434620Y-93875D01*
X434993Y-94625D01*
X435553Y-95250D01*
X436300Y-95500D01*
X437047Y-95250D01*
X437607Y-94625D01*
X437980Y-93875D01*
X438260Y-92875D01*
X438353Y-91750D01*
X438260Y-90625D01*
X437980Y-89625D01*
X437607Y-88875D01*
X437047Y-88250D01*
X436300Y-88000D01*
G01X443800D02*
X443053Y-88250D01*
X442493Y-88875D01*
X442120Y-89625D01*
X441840Y-90625D01*
X441747Y-91750D01*
X441840Y-92875D01*
X442120Y-93875D01*
X442493Y-94625D01*
X443053Y-95250D01*
X443800Y-95500D01*
X444547Y-95250D01*
X445107Y-94625D01*
X445480Y-93875D01*
X445760Y-92875D01*
X445853Y-91750D01*
X445760Y-90625D01*
X445480Y-89625D01*
X445107Y-88875D01*
X444547Y-88250D01*
X443800Y-88000D01*
G01X451300D02*
X450553Y-88250D01*
X449993Y-88875D01*
X449620Y-89625D01*
X449340Y-90625D01*
X449247Y-91750D01*
X449340Y-92875D01*
X449620Y-93875D01*
X449993Y-94625D01*
X450553Y-95250D01*
X451300Y-95500D01*
X452047Y-95250D01*
X452607Y-94625D01*
X452980Y-93875D01*
X453260Y-92875D01*
X453353Y-91750D01*
X453260Y-90625D01*
X452980Y-89625D01*
X452607Y-88875D01*
X452047Y-88250D01*
X451300Y-88000D01*
G01X458800Y-95500D02*
Y-88000D01*
X457680Y-89500D01*
G01Y-95500D02*
X459920D01*
G01X465087Y-93000D02*
X467513D01*
G01X473800Y-88000D02*
X473053Y-88250D01*
X472493Y-88875D01*
X472120Y-89625D01*
X471840Y-90625D01*
X471747Y-91750D01*
X471840Y-92875D01*
X472120Y-93875D01*
X472493Y-94625D01*
X473053Y-95250D01*
X473800Y-95500D01*
X474547Y-95250D01*
X475107Y-94625D01*
X475480Y-93875D01*
X475760Y-92875D01*
X475853Y-91750D01*
X475760Y-90625D01*
X475480Y-89625D01*
X475107Y-88875D01*
X474547Y-88250D01*
X473800Y-88000D01*
G01X479527Y-89250D02*
X480087Y-88500D01*
X480740Y-88125D01*
X481487Y-88000D01*
X482420Y-88250D01*
X483073Y-88875D01*
X483260Y-89625D01*
X483167Y-90375D01*
X482793Y-91000D01*
X480927Y-92250D01*
X480087Y-93125D01*
X479527Y-94375D01*
X479340Y-95500D01*
X483260D01*
G01X380994Y-133267D02*
X383327Y-125767D01*
X385660Y-133267D01*
G01X384820Y-130642D02*
X381834D01*
G01X388867Y-132267D02*
X389614Y-132892D01*
X390454Y-133267D01*
X391200D01*
X391947Y-132892D01*
X392507Y-132267D01*
X392787Y-131392D01*
X392600Y-130517D01*
X392134Y-129767D01*
X391294Y-129267D01*
X390174Y-129017D01*
X389520Y-128517D01*
X389240Y-127642D01*
X389427Y-126767D01*
X389894Y-126142D01*
X390547Y-125767D01*
X391200D01*
X391854Y-126017D01*
X392414Y-126642D01*
G01X396367Y-132267D02*
X397114Y-132892D01*
X397954Y-133267D01*
X398700D01*
X399447Y-132892D01*
X400007Y-132267D01*
X400287Y-131392D01*
X400100Y-130517D01*
X399634Y-129767D01*
X398794Y-129267D01*
X397674Y-129017D01*
X397020Y-128517D01*
X396740Y-127642D01*
X396927Y-126767D01*
X397394Y-126142D01*
X398047Y-125767D01*
X398700D01*
X399354Y-126017D01*
X399914Y-126642D01*
G01X407694Y-133267D02*
X403960D01*
Y-125767D01*
X407694D01*
G01X406200Y-129392D02*
X403960D01*
G01X410900Y-133267D02*
Y-125767D01*
X413327Y-132017D01*
X415754Y-125767D01*
Y-133267D01*
G01X421574Y-129267D02*
X421947Y-128892D01*
X422227Y-128267D01*
X422414Y-127392D01*
X422227Y-126642D01*
X421854Y-126142D01*
X421200Y-125767D01*
X418680D01*
Y-133267D01*
X421760D01*
X422414Y-132767D01*
X422787Y-132017D01*
X422974Y-131142D01*
X422787Y-130267D01*
X422227Y-129517D01*
X421574Y-129267D01*
X418680D01*
G01X426460Y-125767D02*
Y-133267D01*
X430194D01*
G01X435827D02*
Y-129892D01*
X433960Y-125767D01*
G01X437694D02*
X435827Y-129892D01*
G01X450827Y-125767D02*
Y-133267D01*
G01X448680Y-125767D02*
X452974D01*
G01X458327Y-133267D02*
X457580Y-133142D01*
X456927Y-132642D01*
X456367Y-131892D01*
X455994Y-131017D01*
X455807Y-130017D01*
Y-129017D01*
X455994Y-128017D01*
X456367Y-127142D01*
X456927Y-126392D01*
X457580Y-125892D01*
X458327Y-125767D01*
X459074Y-125892D01*
X459727Y-126392D01*
X460287Y-127142D01*
X460660Y-128017D01*
X460847Y-129017D01*
Y-130017D01*
X460660Y-131017D01*
X460287Y-131892D01*
X459727Y-132642D01*
X459074Y-133142D01*
X458327Y-133267D01*
G01X463960D02*
Y-125767D01*
X466200D01*
X466947Y-126142D01*
X467507Y-127017D01*
X467694Y-128017D01*
X467507Y-129017D01*
X467040Y-129767D01*
X466200Y-130142D01*
X463960D01*
G54D12*
G01X-37898Y57087D02*
Y85433D01*
G01X30212Y57087D02*
X-37898D01*
G01Y85433D02*
X30212D01*
G01X-37898Y114173D02*
Y142519D01*
G01X30212Y114173D02*
X-37898D01*
G01Y142519D02*
X30212D01*
G01X-37898Y171260D02*
Y199606D01*
G01X30212Y171260D02*
X-37898D01*
G01Y199606D02*
X30212D01*
G01X-37898Y228347D02*
Y256693D01*
G01X30212Y228347D02*
X-37898D01*
G01Y256693D02*
X30212D01*
G01X658071Y284646D02*
G03X660039Y286614I0J1968D01*
G01Y433661D01*
G03X656102Y437598I-3937J0D01*
G01X3937D01*
G03X0Y433661I0J-3937D01*
G01Y21654D01*
G03X3937Y17717I3937J0D01*
G01X55118D01*
G03X59055Y21654I0J3937D01*
G01Y46260D01*
G02X62992Y50197I3937J0D01*
G01X127362D01*
G02X131299Y46260I0J-3937D01*
G01Y21654D01*
G03X135236Y17717I3937J0D01*
G01X158858D01*
G03X162795Y21654I0J3937D01*
G01Y43012D01*
G02X177165I7185J0D01*
G01Y1969D01*
X179134Y0D01*
X219291D01*
X221260Y1969D01*
Y29331D01*
G02X228740I3740J0D01*
G01Y1969D01*
X230709Y0D01*
X310236D01*
X312205Y1969D01*
Y46260D01*
G02X316142Y50197I3937J0D01*
G01X656102D01*
G03X660039Y54134I0J3937D01*
G01Y237500D01*
G03X658071Y239469I-1969J1D01*
G01X657211D01*
G02X655243Y241437I0J1968D01*
G01Y282677D01*
G02X657211Y284646I1968J0D01*
G01X658071D01*
G01X5610Y91633D02*
X8169D01*
G01X5610Y92421D02*
Y91633D01*
G01X3642Y92421D02*
X5610D01*
G01X3642Y101279D02*
Y92421D01*
G01X8169Y91633D02*
Y102067D01*
G01X5610Y101279D02*
X3642D01*
G01X5610Y102067D02*
Y101279D01*
G01X8169Y102067D02*
X5610D01*
G01Y148720D02*
X8169D01*
G01X5610Y149508D02*
Y148720D01*
G01X3642Y149508D02*
X5610D01*
G01X3642Y158366D02*
Y149508D01*
G01X5610Y158366D02*
X3642D01*
G01X5610Y159154D02*
Y158366D01*
G01X8169Y159154D02*
X5610D01*
G01X8169Y148720D02*
Y159154D01*
G01X5610Y205807D02*
X8169D01*
G01X5610Y206595D02*
Y205807D01*
G01X3642Y206595D02*
X5610D01*
G01X3642Y215453D02*
Y206595D01*
G01X5610Y215453D02*
X3642D01*
G01X5610Y216241D02*
Y215453D01*
G01X8169Y205807D02*
Y216241D01*
G01D02*
X5610D01*
G01Y262893D02*
X8169D01*
G01X5610Y263681D02*
Y262893D01*
G01X3642Y263681D02*
X5610D01*
G01X3642Y272539D02*
Y263681D01*
G01X8169Y262893D02*
Y273327D01*
G01X5610Y272539D02*
X3642D01*
G01X5610Y273327D02*
Y272539D01*
G01X8169Y273327D02*
X5610D01*
G01Y319980D02*
X8169D01*
G01X5610Y320768D02*
Y319980D01*
G01X8169D02*
Y330414D01*
G01X3642Y320768D02*
X5610D01*
G01X3642Y329626D02*
Y320768D01*
G01X5610Y329626D02*
X3642D01*
G01X5610Y330414D02*
Y329626D01*
G01X8169Y330414D02*
X5610D01*
G01X-7476Y333820D02*
Y349410D01*
G01X50594Y333820D02*
X-7476D01*
G01Y349410D02*
X50594D01*
G01X41328Y36811D02*
G02I-11800J0D01*
G01X29125Y97450D02*
X17875D01*
G01D02*
Y102550D01*
G01D02*
X29125D01*
G01X28150D02*
X26350D01*
G01D02*
Y104500D01*
G01D02*
X28150D01*
G01X20650Y102550D02*
X18850D01*
G01D02*
Y104500D01*
G01D02*
X20650D01*
G01D02*
Y102550D01*
G01X28150Y95500D02*
X26350D01*
G01D02*
Y97450D01*
G01D02*
X28150D01*
G01X22250Y95500D02*
X18850D01*
G01D02*
Y97450D01*
G01D02*
X22250D01*
G01D02*
Y95500D01*
G01X26900Y152798D02*
X29300D01*
G01X26900Y156798D02*
Y152798D01*
G01X29300Y156798D02*
X26900D01*
G01X22400Y152798D02*
X24800D01*
G01X22400Y156798D02*
Y152798D01*
G01X24800Y156798D02*
X22400D01*
G01X24800Y152798D02*
Y156798D01*
G01X17900Y152798D02*
X20300D01*
G01X17900Y156798D02*
Y152798D01*
G01X20300Y156798D02*
X17900D01*
G01X20300Y152798D02*
Y156798D01*
G01X22250Y211450D02*
Y209500D01*
G01X18850Y211450D02*
X22250D01*
G01X18850Y209500D02*
Y211450D01*
G01X22250Y209500D02*
X18850D01*
G01X26350Y211450D02*
X28150D01*
G01X26350Y209500D02*
Y211450D01*
G01X28150Y209500D02*
X26350D01*
G01X17875Y211450D02*
Y216550D01*
G01X29125Y211450D02*
X17875D01*
G01X20650Y218500D02*
Y216550D01*
G01X18850Y218500D02*
X20650D01*
G01X18850Y216550D02*
Y218500D01*
G01X20650Y216550D02*
X18850D01*
G01X26350Y218500D02*
X28150D01*
G01X26350Y216550D02*
Y218500D01*
G01X28150Y216550D02*
X26350D01*
G01X17875D02*
X29125D01*
G01X23000Y266508D02*
X25400D01*
G01X23000Y270508D02*
Y266508D01*
G01X25400D02*
Y270508D01*
G01X18500Y266508D02*
X20900D01*
G01X18500Y270508D02*
Y266508D01*
G01X20900D02*
Y270508D01*
G01X25400D02*
X23000D01*
G01X20900D02*
X18500D01*
G01X16800Y319000D02*
X19200D01*
G01X16800Y323000D02*
Y319000D01*
G01X19200D02*
Y323000D01*
G01X21800Y319000D02*
X24200D01*
G01X21800Y323000D02*
Y319000D01*
G01X24200D02*
Y323000D01*
G01X26800Y319000D02*
X29200D01*
G01X26800Y323000D02*
Y319000D01*
G01X19200Y323000D02*
X16800D01*
G01X24200D02*
X21800D01*
G01X29200D02*
X26800D01*
G01X41328Y373031D02*
G02I-11800J0D01*
G01X30212Y85433D02*
Y57087D01*
G01X45500Y68800D02*
X43100D01*
G01Y64800D02*
X45500D01*
G01X43100Y68800D02*
Y64800D01*
G01X29125Y102550D02*
Y97450D01*
G01X28150Y104500D02*
Y102550D01*
G01Y97450D02*
Y95500D01*
G01X44300Y108490D02*
X46700D01*
G01X44300Y112490D02*
Y108490D01*
G01X46700Y112490D02*
X44300D01*
G01X46700Y121900D02*
X44300D01*
G01Y117900D02*
X46700D01*
G01X44300Y121900D02*
Y117900D01*
G01X30212Y142519D02*
Y114173D01*
G01X31400Y152798D02*
X33800D01*
G01X31400Y156798D02*
Y152798D01*
G01X33800Y156798D02*
X31400D01*
G01X33800Y152798D02*
Y156798D01*
G01X35900Y152798D02*
X38300D01*
G01X35900Y156798D02*
Y152798D01*
G01X38300Y156798D02*
X35900D01*
G01X38300Y152798D02*
Y156798D01*
G01X40400Y152798D02*
X42800D01*
G01X40400Y156798D02*
Y152798D01*
G01X42800Y156798D02*
X40400D01*
G01X42800Y152798D02*
Y156798D01*
G01X29300Y152798D02*
Y156798D01*
G01X44300Y174000D02*
X46700D01*
G01X44300Y178000D02*
Y174000D01*
G01X46700Y178000D02*
X44300D01*
G01Y164500D02*
X46700D01*
G01X44300Y168500D02*
Y164500D01*
G01X46700Y168500D02*
X44300D01*
G01X30212Y199606D02*
Y171260D01*
G01X28150Y211450D02*
Y209500D01*
G01X29125Y216550D02*
Y211450D01*
G01X28150Y218500D02*
Y216550D01*
G01X44000Y232700D02*
X46400D01*
G01X44000Y236700D02*
Y232700D01*
G01X30212Y256693D02*
Y228347D01*
G01X46400Y236700D02*
X44000D01*
G01X36500Y266508D02*
X38900D01*
G01X36500Y270508D02*
Y266508D01*
G01X38900D02*
Y270508D01*
G01X41000Y266508D02*
X43400D01*
G01X41000Y270508D02*
Y266508D01*
G01X43400D02*
Y270508D01*
G01X32000Y266508D02*
X34400D01*
G01X32000Y270508D02*
Y266508D01*
G01X34400D02*
Y270508D01*
G01X27500Y266508D02*
X29900D01*
G01X27500Y270508D02*
Y266508D01*
G01X29900D02*
Y270508D01*
G01X38900D02*
X36500D01*
G01X43400D02*
X41000D01*
G01X34400D02*
X32000D01*
G01X29900D02*
X27500D01*
G01X41800Y319000D02*
X44200D01*
G01X41800Y323000D02*
Y319000D01*
G01X44200D02*
Y323000D01*
G01X36800Y319000D02*
X39200D01*
G01X36800Y323000D02*
Y319000D01*
G01X39200D02*
Y323000D01*
G01X29200Y319000D02*
Y323000D01*
G01X31800Y319000D02*
X34200D01*
G01X31800Y323000D02*
Y319000D01*
G01X34200D02*
Y323000D01*
G01X44200D02*
X41800D01*
G01X39200D02*
X36800D01*
G01X34200D02*
X31800D01*
G01X45500Y64800D02*
Y68800D01*
G01X58858Y66536D02*
Y75984D01*
G01X50590Y66536D02*
X58858D01*
G01X50590Y75984D02*
Y66536D01*
G01X58858Y75984D02*
X50590D01*
G01X59200Y92500D02*
X56800D01*
G01X59200Y88500D02*
Y92500D01*
G01X56800Y88500D02*
X59200D01*
G01X56800Y92500D02*
Y88500D01*
G01X47300D02*
X49700D01*
G01X47300Y92500D02*
Y88500D01*
G01X49700Y92500D02*
X47300D01*
G01X49700Y88500D02*
Y92500D01*
G01X54700D02*
X52300D01*
G01X54700Y88500D02*
Y92500D01*
G01X52300Y88500D02*
X54700D01*
G01X52300Y92500D02*
Y88500D01*
G01X61300Y108500D02*
X63700D01*
G01X61300Y112500D02*
Y108500D01*
G01X52640Y100650D02*
X50160D01*
G01X52640Y99350D02*
Y100650D01*
G01X50160Y99350D02*
X52640D01*
G01X50160Y100650D02*
Y99350D01*
G01X49300Y108490D02*
X51700D01*
G01X49300Y112490D02*
Y108490D01*
G01X51700D02*
Y112490D01*
G01X46700Y108490D02*
Y112490D01*
G01X63700Y112500D02*
X61300D01*
G01X51700Y112490D02*
X49300D01*
G01X46700Y117900D02*
Y121900D01*
G01X58858Y123622D02*
Y133070D01*
G01X50590Y123622D02*
X58858D01*
G01X50590Y133070D02*
Y123622D01*
G01X59200Y144500D02*
Y148500D01*
G01X56800Y144500D02*
X59200D01*
G01X56800Y148500D02*
Y144500D01*
G01X46800D02*
X49200D01*
G01X46800Y148500D02*
Y144500D01*
G01X49200D02*
Y148500D01*
G01X54200Y144500D02*
Y148500D01*
G01X51800Y144500D02*
X54200D01*
G01X51800Y148500D02*
Y144500D01*
G01X58858Y133070D02*
X50590D01*
G01X48760Y156350D02*
X51240D01*
G01X48760Y157650D02*
Y156350D01*
G01X51240Y157650D02*
X48760D01*
G01X51240Y156350D02*
Y157650D01*
G01X59200Y148500D02*
X56800D01*
G01X49200D02*
X46800D01*
G01X54200D02*
X51800D01*
G01X61800Y168845D02*
X59400D01*
G01X61800Y164845D02*
Y168845D01*
G01X59400Y164845D02*
X61800D01*
G01X59400Y168845D02*
Y164845D01*
G01X51500Y166200D02*
Y163800D01*
G01X55500D02*
Y166200D01*
G01X51500Y163800D02*
X55500D01*
G01Y166200D02*
X51500D01*
G01X46700Y174000D02*
Y178000D01*
G01Y164500D02*
Y168500D01*
G01X58858Y180709D02*
Y190157D01*
G01X50590Y180709D02*
X58858D01*
G01X50590Y190157D02*
Y180709D01*
G01X58858Y190157D02*
X50590D01*
G01X58700Y209000D02*
X56300D01*
G01X58700Y205000D02*
Y209000D01*
G01X56300Y205000D02*
X58700D01*
G01X56300Y209000D02*
Y205000D01*
G01X46800D02*
X49200D01*
G01X46800Y209000D02*
Y205000D01*
G01X49200Y209000D02*
X46800D01*
G01X49200Y205000D02*
Y209000D01*
G01X54200D02*
X51800D01*
G01X54200Y205000D02*
Y209000D01*
G01X51800Y205000D02*
X54200D01*
G01X51800Y209000D02*
Y205000D01*
G01X49360Y215950D02*
X51840D01*
G01X49360Y217250D02*
Y215950D01*
G01X51840D02*
Y217250D01*
G01D02*
X49360D01*
G01X50252Y223400D02*
X52652D01*
G01X50252Y227400D02*
Y223400D01*
G01X52652Y227400D02*
X50252D01*
G01X52652Y223400D02*
Y227400D01*
G01X47652D02*
X45252D01*
G01X47652Y223400D02*
Y227400D01*
G01X45252Y223400D02*
X47652D01*
G01X45252Y227400D02*
Y223400D01*
G01X46400Y232700D02*
Y236700D01*
G01X58858Y237796D02*
Y247244D01*
G01X50590Y237796D02*
X58858D01*
G01X50590Y247244D02*
Y237796D01*
G01X58858Y247244D02*
X50590D01*
G01X51940Y267350D02*
Y268650D01*
G01X49460Y267350D02*
X51940D01*
G01X49460Y268650D02*
Y267350D01*
G01X59000Y261000D02*
X56600D01*
G01X59000Y257000D02*
Y261000D01*
G01X56600Y257000D02*
X59000D01*
G01X56600Y261000D02*
Y257000D01*
G01X46600D02*
X49000D01*
G01X46600Y261000D02*
Y257000D01*
G01X49000Y261000D02*
X46600D01*
G01X49000Y257000D02*
Y261000D01*
G01X54200Y262500D02*
X51800D01*
G01X54200Y258500D02*
Y262500D01*
G01X51800Y258500D02*
X54200D01*
G01X51800Y262500D02*
Y258500D01*
G01X51940Y268650D02*
X49460D01*
G01X62000Y277800D02*
X66000D01*
G01X62000Y280200D02*
Y277800D01*
G01X66000Y280200D02*
X62000D01*
G01X59000Y330200D02*
Y327800D01*
G01X63000Y330200D02*
X59000D01*
G01Y327800D02*
X63000D01*
G01X50594Y349410D02*
Y333820D01*
G01X58300Y355500D02*
X60700D01*
G01X58300Y359500D02*
Y355500D01*
G01X60700D02*
Y359500D01*
G01D02*
X58300D01*
G01X58900Y384000D02*
X55300D01*
G01X58900Y390400D02*
Y384000D01*
G01X55300D02*
Y390400D01*
G01D02*
X58900D01*
G01X71400Y73950D02*
Y91650D01*
G01X83600Y73950D02*
X71400D01*
G01Y91650D02*
X83600D01*
G01X63700Y108500D02*
Y112500D01*
G01X78000Y108800D02*
X82000D01*
G01X78000Y111200D02*
Y108800D01*
G01Y103800D02*
X82000D01*
G01X78000Y106200D02*
Y103800D01*
G01X82000Y106200D02*
X78000D01*
G01Y118800D02*
X82000D01*
G01X78000Y121200D02*
Y118800D01*
G01X82000Y121200D02*
X78000D01*
G01Y123800D02*
X82000D01*
G01X78000Y126200D02*
Y123800D01*
G01X82000Y126200D02*
X78000D01*
G01Y113800D02*
X82000D01*
G01X78000Y116200D02*
Y113800D01*
G01X82000Y116200D02*
X78000D01*
G01X82000Y111200D02*
X78000D01*
G01Y128800D02*
X82000D01*
G01X78000Y131200D02*
Y128800D01*
G01X82000Y131200D02*
X78000D01*
G01X66307Y142894D02*
X84693D01*
G01X66307Y162106D02*
Y142894D01*
G01X84693Y162106D02*
X66307D01*
G01X78647Y178300D02*
Y180700D01*
G01X74647Y178300D02*
X78647D01*
G01X74647Y180700D02*
Y178300D01*
G01X78647Y180700D02*
X74647D01*
G01X78647Y173800D02*
Y176200D01*
G01X74647Y173800D02*
X78647D01*
G01X74647Y176200D02*
Y173800D01*
G01X78647Y176200D02*
X74647D01*
G01X78647Y191800D02*
Y194200D01*
G01X74647Y191800D02*
X78647D01*
G01X74647Y194200D02*
Y191800D01*
G01X78647Y194200D02*
X74647D01*
G01X78647Y196300D02*
Y198700D01*
G01X74647Y196300D02*
X78647D01*
G01X74647Y198700D02*
Y196300D01*
G01X78647Y187300D02*
Y189700D01*
G01X74647Y187300D02*
X78647D01*
G01X74647Y189700D02*
Y187300D01*
G01X78647Y189700D02*
X74647D01*
G01X78647Y182800D02*
Y185200D01*
G01X74647Y182800D02*
X78647D01*
G01X74647Y185200D02*
Y182800D01*
G01X78647Y185200D02*
X74647D01*
G01X78924Y215694D02*
X81876D01*
G01X78924Y214710D02*
Y215694D01*
G01X74790Y214710D02*
X78924D01*
G01X74790Y203490D02*
Y214710D01*
G01X86010Y203490D02*
X74790D01*
G01X78647Y198700D02*
X74647D01*
G01X72600Y229300D02*
X70200D01*
G01X72600Y225300D02*
Y229300D01*
G01X70200Y225300D02*
X72600D01*
G01X70200Y229300D02*
Y225300D01*
G01X65200Y227000D02*
X62800D01*
G01X65200Y223000D02*
Y227000D01*
G01X62800Y223000D02*
X65200D01*
G01X62800Y227000D02*
Y223000D01*
G01X88100Y227700D02*
X76100D01*
G01D02*
Y239700D01*
G01X70300Y240300D02*
X72700D01*
G01X70300Y244300D02*
Y240300D01*
G01X72700Y244300D02*
X70300D01*
G01X72700Y240300D02*
Y244300D01*
G01X76100Y239700D02*
X88100D01*
G01X64348Y267600D02*
Y265200D01*
G01X68348Y267600D02*
X64348D01*
G01X68348Y265200D02*
Y267600D01*
G01X64348Y265200D02*
X68348D01*
G01X78148Y256600D02*
X75748D01*
G01X78148Y252600D02*
Y256600D01*
G01X75748Y252600D02*
X78148D01*
G01X75748Y256600D02*
Y252600D01*
G01X68348Y260200D02*
Y262600D01*
G01X64348Y260200D02*
X68348D01*
G01X64348Y262600D02*
Y260200D01*
G01X68348Y262600D02*
X64348D01*
G01X74814Y261966D02*
Y270234D01*
G01X83082Y261966D02*
X74814D01*
G01X75500Y277800D02*
Y280200D01*
G01X71500Y277800D02*
X75500D01*
G01X71500Y280200D02*
Y277800D01*
G01X75500Y280200D02*
X71500D01*
G01X79448Y279000D02*
X81848D01*
G01X79448Y283000D02*
Y279000D01*
G01X81848Y283000D02*
X79448D01*
G01X68348Y269700D02*
Y272100D01*
G01X64348Y269700D02*
X68348D01*
G01X64348Y272100D02*
Y269700D01*
G01X68348Y272100D02*
X64348D01*
G01X66000Y277800D02*
Y280200D01*
G01X74814Y270234D02*
X83082D01*
G01X74500Y318800D02*
Y321200D01*
G01X70500Y318800D02*
X74500D01*
G01X70500Y321200D02*
Y318800D01*
G01X63000Y327800D02*
Y330200D01*
G01X74500Y323300D02*
Y325700D01*
G01X70500Y323300D02*
X74500D01*
G01X70500Y325700D02*
Y323300D01*
G01X74500Y325700D02*
X70500D01*
G01X74500Y321200D02*
X70500D01*
G01X66291Y348150D02*
X67276D01*
G01X66291Y341850D02*
Y348150D01*
G01X67276Y341850D02*
X66291D01*
G01X69244D02*
X71016D01*
G01X72984D02*
X74756D01*
G01X72984Y348150D02*
X74756D01*
G01X72984Y347756D02*
Y348150D01*
G01X71016Y347756D02*
X72984D01*
G01X71016Y348150D02*
Y347756D01*
G01X69244Y348150D02*
X71016D01*
G01X77709D02*
X76724D01*
G01X77709Y341850D02*
Y348150D01*
G01X76724Y341850D02*
X77709D01*
G01D02*
X76921Y342638D01*
G01X77709Y348150D02*
X76921Y347362D01*
G01X67079D02*
X66291Y348150D01*
G01X67079Y342638D02*
X66291Y341850D01*
G01X76724Y347756D02*
X74756D01*
G01D02*
Y350906D01*
G01D02*
X76724D01*
G01D02*
Y347756D01*
G01X69244D02*
X67276D01*
G01D02*
Y350906D01*
G01D02*
X69244D01*
G01D02*
Y347756D01*
G01X72984D02*
X71016D01*
G01D02*
Y350906D01*
G01D02*
X72984D01*
G01D02*
Y347756D01*
G01Y339094D02*
X71016D01*
G01D02*
Y342244D01*
G01D02*
X72984D01*
G01D02*
Y339094D01*
G01X69244D02*
X67276D01*
G01D02*
Y342244D01*
G01D02*
X69244D01*
G01D02*
Y339094D01*
G01X76724D02*
X74756D01*
G01D02*
Y342244D01*
G01D02*
X76724D01*
G01D02*
Y339094D01*
G01X76921Y342638D02*
X67079D01*
G01D02*
Y347362D01*
G01D02*
X76921D01*
G01D02*
Y342638D01*
G01X71050Y370350D02*
Y373350D01*
G01X67550Y370350D02*
X71050D01*
G01X67550Y373350D02*
Y370350D01*
G01X65050Y381850D02*
Y406350D01*
G01X91550Y381850D02*
X65050D01*
G01X76550Y377850D02*
X80050D01*
G01X76550Y381850D02*
Y377850D01*
G01X71050D02*
Y381850D01*
G01X71550Y377850D02*
X71050D01*
G01X71550Y373350D02*
Y377850D01*
G01X71050Y373350D02*
X71550D01*
G01X67050D02*
X67550D01*
G01X67050Y377850D02*
Y373350D01*
G01X67550Y377850D02*
X67050D01*
G01X67550Y381850D02*
Y377850D01*
G01X65050Y406350D02*
X91550D01*
G01X67550Y392850D02*
X89050D01*
G01X67550Y408350D02*
Y392850D01*
G01X70550Y411350D02*
X67550Y408350D01*
G01X86050Y411350D02*
X70550D01*
G01X95494Y68116D02*
Y70084D01*
G01D02*
X98644D01*
G01Y68116D02*
X95494D01*
G01Y71856D02*
Y73824D01*
G01D02*
X98644D01*
G01Y71856D02*
X95494D01*
G01Y64376D02*
Y66344D01*
G01D02*
X98644D01*
G01Y64376D02*
X95494D01*
G01X83600Y91650D02*
Y73950D01*
G01X82000Y108800D02*
Y111200D01*
G01Y103800D02*
Y106200D01*
G01Y118800D02*
Y121200D01*
G01Y123800D02*
Y126200D01*
G01Y113800D02*
Y116200D01*
G01Y128800D02*
Y131200D01*
G01X84693Y142894D02*
Y162106D01*
G01X86010Y214710D02*
Y203490D01*
G01X81876Y214710D02*
X86010D01*
G01X81876Y215694D02*
Y214710D01*
G01X88100Y239700D02*
Y227700D01*
G01X94800Y256848D02*
Y259248D01*
G01X90800Y256848D02*
X94800D01*
G01X90800Y259248D02*
Y256848D01*
G01X94800Y259248D02*
X90800D01*
G01X90948Y269500D02*
Y267100D01*
G01X94948D02*
Y269500D01*
G01X90948Y267100D02*
X94948D01*
G01X84700Y256500D02*
X82300D01*
G01X84700Y252500D02*
Y256500D01*
G01X82300Y252500D02*
X84700D01*
G01X82300Y256500D02*
Y252500D01*
G01X83082Y270234D02*
Y261966D01*
G01X95748Y265000D02*
Y261400D01*
G01X89348Y265000D02*
X95748D01*
G01X89348Y261400D02*
Y265000D01*
G01X95748Y261400D02*
X89348D01*
G01X91000Y274000D02*
Y271600D01*
G01X95000Y274000D02*
X91000D01*
G01X95000Y271600D02*
Y274000D01*
G01X91000Y271600D02*
X95000D01*
G01X94948Y269500D02*
X90948D01*
G01X81848Y279000D02*
Y283000D01*
G01X92600Y315200D02*
X132000D01*
G01X92600Y354600D02*
Y315200D01*
G01X132000Y354600D02*
X92600D01*
G01X89050Y370350D02*
Y373350D01*
G01X85550Y370350D02*
X89050D01*
G01X85550Y373350D02*
Y370350D01*
G01X91550Y406350D02*
Y381850D01*
G01X80050Y377850D02*
Y381850D01*
G01X89050Y377850D02*
Y381850D01*
G01X89550Y377850D02*
X89050D01*
G01X89550Y373350D02*
Y377850D01*
G01X89050Y373350D02*
X89550D01*
G01X85050D02*
X85550D01*
G01X85050Y377850D02*
Y373350D01*
G01X85550Y377850D02*
X85050D01*
G01X85550Y381850D02*
Y377850D01*
G01X89050Y392850D02*
Y408350D01*
G01D02*
X86050Y411350D01*
G01X104550Y74809D02*
Y73824D01*
G01X98250Y74809D02*
X104550D01*
G01X98250Y73824D02*
Y74809D01*
G01Y71856D02*
Y70084D01*
G01Y68116D02*
Y66344D01*
G01X104550Y71856D02*
Y66344D01*
G01Y63391D02*
Y64376D01*
G01X98250Y63391D02*
X104550D01*
G01X98250Y64376D02*
Y63391D01*
G01D02*
X99038Y64179D01*
G01X104550Y63391D02*
X103762Y64179D01*
G01Y74021D02*
X104550Y74809D01*
G01X99038Y74021D02*
X98250Y74809D01*
G01X99038Y64179D02*
Y74021D01*
G01D02*
X103762D01*
G01D02*
Y64179D01*
G01D02*
X99038D01*
G01X104156Y64376D02*
Y66344D01*
G01D02*
X107306D01*
G01D02*
Y64376D01*
G01D02*
X104156D01*
G01Y71856D02*
Y73824D01*
G01D02*
X107306D01*
G01D02*
Y71856D01*
G01D02*
X104156D01*
G01X98644Y70084D02*
Y68116D01*
G01Y73824D02*
Y71856D01*
G01Y66344D02*
Y64376D01*
G01X108700Y298000D02*
X106300D01*
G01X108700Y294000D02*
Y298000D01*
G01X106300Y294000D02*
X108700D01*
G01X106300Y298000D02*
Y294000D01*
G01X113700Y298000D02*
X111300D01*
G01X113700Y294000D02*
Y298000D01*
G01X111300Y294000D02*
X113700D01*
G01X111300Y298000D02*
Y294000D01*
G01X101300D02*
X103700D01*
G01X101300Y298000D02*
Y294000D01*
G01X103700Y298000D02*
X101300D01*
G01X103700Y294000D02*
Y298000D01*
G01X111700Y369000D02*
Y373000D01*
G01X109300Y369000D02*
X111700D01*
G01X109300Y373000D02*
Y369000D01*
G01X114300D02*
X116700D01*
G01X114300Y373000D02*
Y369000D01*
G01X106700D02*
Y373000D01*
G01X104300Y369000D02*
X106700D01*
G01X104300Y373000D02*
Y369000D01*
G01X111700Y373000D02*
X109300D01*
G01X116700D02*
X114300D01*
G01X106700D02*
X104300D01*
G01X117470Y62560D02*
Y60160D01*
G01X121470Y62560D02*
X117470D01*
G01X121470Y60160D02*
Y62560D01*
G01X117470Y60160D02*
X121470D01*
G01Y64660D02*
Y67060D01*
G01X117470Y64660D02*
X121470D01*
G01X117470Y67060D02*
Y64660D01*
G01X121470Y67060D02*
X117470D01*
G01X121470Y74160D02*
Y76560D01*
G01X117470Y74160D02*
X121470D01*
G01X117470Y76560D02*
Y74160D01*
G01X121470Y69660D02*
Y72060D01*
G01X117470Y69660D02*
X121470D01*
G01X117470Y72060D02*
Y69660D01*
G01X121470Y72060D02*
X117470D01*
G01X130950Y64600D02*
X134950D01*
G01X130950Y67000D02*
Y64600D01*
G01X134950Y67000D02*
X130950D01*
G01Y60100D02*
X134950D01*
G01X130950Y62500D02*
Y60100D01*
G01X134950Y62500D02*
X130950D01*
G01X130970Y69600D02*
X134970D01*
G01X130970Y72000D02*
Y69600D01*
G01X134970Y72000D02*
X130970D01*
G01Y74100D02*
X134970D01*
G01X130970Y76500D02*
Y74100D01*
G01X121470Y76560D02*
X117470D01*
G01X134970Y76500D02*
X130970D01*
G01X130667Y104043D02*
G02I-4600J0D01*
G01X155567Y106043D02*
G02I-12000J0D01*
G01X130667Y184043D02*
G02I-4600J0D01*
G01Y264043D02*
G02I-4600J0D01*
G01X118700Y298000D02*
X116300D01*
G01X118700Y294000D02*
Y298000D01*
G01X116300Y294000D02*
X118700D01*
G01X116300Y298000D02*
Y294000D01*
G01X116700Y369000D02*
Y373000D01*
G01X119004Y383382D02*
Y393618D01*
G01X131996Y383382D02*
X119004D01*
G01X123740Y379650D02*
X121260D01*
G01X123740Y378350D02*
Y379650D01*
G01X121260Y378350D02*
X123740D01*
G01X121260Y379650D02*
Y378350D01*
G01X126760D02*
X129240D01*
G01X126760Y379650D02*
Y378350D01*
G01X129240Y379650D02*
X126760D01*
G01X129240Y378350D02*
Y379650D01*
G01X127000Y373800D02*
Y376200D01*
G01X123000Y373800D02*
X127000D01*
G01X123000Y376200D02*
Y373800D01*
G01X127000Y376200D02*
X123000D01*
G01X119004Y393618D02*
X131996D01*
G01X145964Y-110118D02*
G03I-634J0D01*
G01X149695D02*
G03I-1038J0D01*
G01X134950Y64600D02*
Y67000D01*
G01Y60100D02*
Y62500D01*
G01X134970Y69600D02*
Y72000D01*
G01Y74100D02*
Y76500D01*
G01X158067Y268043D02*
G02I-12000J0D01*
G01X148500Y300000D02*
Y308000D01*
G01X143500Y300000D02*
X148500D01*
G01X143500Y308000D02*
Y300000D01*
G01X148500Y293800D02*
X152500D01*
G01X148500Y296200D02*
Y293800D01*
G01X152500Y296200D02*
X148500D01*
G01Y308000D02*
X143500D01*
G01X143700Y319700D02*
X147300D01*
G01X143700Y313300D02*
Y319700D01*
G01X147300Y313300D02*
X143700D01*
G01X147300Y319700D02*
Y313300D01*
G01X132000Y315200D02*
Y354600D01*
G01X145700Y370500D02*
Y374500D01*
G01X143300Y370500D02*
X145700D01*
G01X143300Y374500D02*
Y370500D01*
G01X131996Y393618D02*
Y383382D01*
G01X145700Y374500D02*
X143300D01*
G01X147340Y389450D02*
Y390750D01*
G01X144860Y389450D02*
X147340D01*
G01X144860Y390750D02*
Y389450D01*
G01X146600Y383900D02*
Y386300D01*
G01X142600Y383900D02*
X146600D01*
G01X142600Y386300D02*
Y383900D01*
G01X146600Y386300D02*
X142600D01*
G01X147600Y397900D02*
Y400300D01*
G01X143600Y397900D02*
X147600D01*
G01X143600Y400300D02*
Y397900D01*
G01X147600Y400300D02*
X143600D01*
G01X147600Y393400D02*
Y395800D01*
G01X143600Y393400D02*
X147600D01*
G01X143600Y395800D02*
Y393400D01*
G01X147600Y395800D02*
X143600D01*
G01X147340Y390750D02*
X144860D01*
G01Y402450D02*
X147340D01*
G01X144860Y403750D02*
Y402450D01*
G01X147340Y403750D02*
X144860D01*
G01X147340Y402450D02*
Y403750D01*
G01X146840Y407950D02*
Y409250D01*
G01X144360Y407950D02*
X146840D01*
G01X144360Y409250D02*
Y407950D01*
G01X146840Y409250D02*
X144360D01*
G01X139700Y412500D02*
X137300D01*
G01X139700Y408500D02*
Y412500D01*
G01X137300Y408500D02*
X139700D01*
G01X137300Y412500D02*
Y408500D01*
G01X143600Y415400D02*
Y413000D01*
G01X147600Y415400D02*
X143600D01*
G01X147600Y413000D02*
Y415400D01*
G01X143600Y413000D02*
X147600D01*
G01X168013Y-137456D02*
G03I-634J0D01*
G01X155900Y-133655D02*
G03I-632J0D01*
G01X161735Y-128639D02*
G03I-1458J0D01*
G01X158530Y-131428D02*
G03I-1041J0D01*
G01X158461Y-119126D02*
G03I-1283J0D01*
G01X162690Y-117490D02*
G03I-1584J0D01*
G01X169809Y-121292D02*
G03I-2180J0D01*
G01X165531Y-125255D02*
G03I-1869J0D01*
G01X167813Y-115513D02*
G03I-1971J0D01*
G01X154775Y-120500D02*
G03I-892J0D01*
G01X162681Y-102774D02*
G03I-1584J0D01*
G01X158451Y-101149D02*
G03I-1283J0D01*
G01X159258Y-110118D02*
G03I-1868J0D01*
G01X169812Y-98951D02*
G03I-2180J0D01*
G01X167802Y-104739D02*
G03I-1971J0D01*
G01X165183Y-110118D02*
G03I-2180J0D01*
G01X171881D02*
G03I-2642J0D01*
G01X152135Y-98681D02*
G03I-632J0D01*
G01X154064Y-110118D02*
G03I-1460J0D01*
G01X154764Y-99775D02*
G03I-892J0D01*
G01X158530Y-88809D02*
G03I-1041J0D01*
G01X161742Y-91601D02*
G03I-1458J0D01*
G01X165531Y-94981D02*
G03I-1869J0D01*
G01X165470Y58200D02*
Y59800D01*
G01X169570Y58200D02*
X165470D01*
G01X153600Y62220D02*
X156000D01*
G01X153600Y66220D02*
Y62220D01*
G01X156000Y66220D02*
X153600D01*
G01X156000Y62220D02*
Y66220D01*
G01X165470Y59800D02*
X169570D01*
G01X165470Y64800D02*
X169570D01*
G01X165470Y63200D02*
Y64800D01*
G01X169570Y63200D02*
X165470D01*
G01Y69800D02*
X169570D01*
G01X165470Y68200D02*
Y69800D01*
G01X169570Y68200D02*
X165470D01*
G01Y74800D02*
X169570D01*
G01X165470Y73200D02*
Y74800D01*
G01X169570Y73200D02*
X165470D01*
G01X152500Y293800D02*
Y296200D01*
G01X154200Y300500D02*
Y304500D01*
G01X151800Y300500D02*
X154200D01*
G01X151800Y304500D02*
Y300500D01*
G01X161996Y295496D02*
Y307504D01*
G01X174004Y295496D02*
X161996D01*
G01X149800Y316500D02*
X152200D01*
G01X149800Y320500D02*
Y316500D01*
G01X152200D02*
Y320500D01*
G01X154200Y304500D02*
X151800D01*
G01X161996Y307504D02*
X174004D01*
G01X160457Y319657D02*
X167543D01*
G01X160457Y314343D02*
Y319657D01*
G01X167543Y314343D02*
X160457D01*
G01X152200Y320500D02*
X149800D01*
G01X160457Y329657D02*
X167543D01*
G01X160457Y324343D02*
Y329657D01*
G01X167543Y324343D02*
X160457D01*
G01X162690Y384458D02*
G02I-2000J0D01*
G01X171687Y389513D02*
X157513D01*
G01D02*
Y403687D01*
G01X152900Y375800D02*
Y379400D01*
G01X159300Y375800D02*
X152900D01*
G01X159300Y379400D02*
Y375800D01*
G01X152900Y379400D02*
X159300D01*
G01X157513Y403687D02*
X171687D01*
G01X165100Y410300D02*
Y407900D01*
G01D02*
X169100D01*
G01Y410300D02*
X165100D01*
G01X172100Y417600D02*
X164100D01*
G01Y412600D02*
X172100D01*
G01X164100Y417600D02*
Y412600D01*
G01X156800Y412100D02*
Y416100D01*
G01D02*
X154400D01*
G01D02*
Y412100D01*
G01D02*
X156800D01*
G01X171080Y-131739D02*
G03I-1282J0D01*
G01X169322Y-135033D02*
G03I-892J0D01*
G01X180669Y-131528D02*
G03I-1870J0D01*
G01X180255Y-136311D02*
G03I-1456J0D01*
G01X179841Y-140261D02*
G03I-1042J0D01*
G01X179433Y-143587D02*
G03I-634J0D01*
G01X181439Y-119680D02*
G03I-2640J0D01*
G01X175373Y-123081D02*
G03I-1968J0D01*
G01X173018Y-127816D02*
G03I-1584J0D01*
G01X174681Y-116876D02*
G03I-2640J0D01*
G01X180979Y-125917D02*
G03I-2180J0D01*
G01X186177Y-123075D02*
G03I-1971J0D01*
G01X188199Y-116876D02*
G03I-2640J0D01*
G01X175452Y-97124D02*
G03I-1968J0D01*
G01X186225Y-97178D02*
G03I-1971J0D01*
G01X181439Y-100556D02*
G03I-2640J0D01*
G01X174681Y-103361D02*
G03I-2640J0D01*
G01X188199D02*
G03I-2640J0D01*
G01X179841Y-79975D02*
G03I-1042J0D01*
G01X171217Y-88444D02*
G03I-1282J0D01*
G01X173123Y-92378D02*
G03I-1584J0D01*
G01X180255Y-83924D02*
G03I-1456J0D01*
G01X180669Y-88708D02*
G03I-1870J0D01*
G01X180979Y-94320D02*
G03I-2180J0D01*
G01X179433Y-76648D02*
G03I-634J0D01*
G01X177200Y1981D02*
Y36281D01*
G01X179200Y-19D02*
X177200Y1981D01*
G01X219250Y-19D02*
X179200D01*
G01X169570Y56850D02*
Y76150D01*
G01X184970Y56850D02*
X169570D01*
G01Y76150D02*
X184970D01*
G01X182500Y305200D02*
Y302800D01*
G01D02*
X186500D01*
G01X171260Y289350D02*
X173740D01*
G01X171260Y290650D02*
Y289350D01*
G01X173740Y290650D02*
X171260D01*
G01X173740Y289350D02*
Y290650D01*
G01X184700Y298000D02*
X182300D01*
G01Y294000D02*
X184700D01*
G01X182300Y298000D02*
Y294000D01*
G01X174004Y307504D02*
Y295496D01*
G01X186500Y305200D02*
X182500D01*
G01X182000Y320200D02*
Y317800D01*
G01X186000Y320200D02*
X182000D01*
G01Y317800D02*
X186000D01*
G01X189500Y313000D02*
X181500D01*
G01Y308000D02*
X189500D01*
G01X181500Y313000D02*
Y308000D01*
G01X174200Y319200D02*
X177800D01*
G01X174200Y312800D02*
Y319200D01*
G01X177800Y312800D02*
X174200D01*
G01X177800Y319200D02*
Y312800D01*
G01X167543Y319657D02*
Y314343D01*
G01X185500Y328500D02*
X177500D01*
G01Y323500D02*
X185500D01*
G01X177500Y328500D02*
Y323500D01*
G01X167543Y329657D02*
Y324343D01*
G01X167100Y385300D02*
Y382900D01*
G01X171100Y385300D02*
X167100D01*
G01X171100Y382900D02*
Y385300D01*
G01X167100Y382900D02*
X171100D01*
G01X175100Y380100D02*
X167100D01*
G01X175100Y375100D02*
Y380100D01*
G01X167100Y375100D02*
X175100D01*
G01X167100Y380100D02*
Y375100D01*
G01X181139Y383624D02*
Y411576D01*
G01X211061Y383624D02*
X181139D01*
G01X171687Y403687D02*
Y389513D01*
G01X169100Y407900D02*
Y410300D01*
G01X172100Y412600D02*
Y417600D01*
G01X181139Y411576D02*
X211061D01*
G01X191096Y-134658D02*
G03I-892J0D01*
G01X192135Y-136781D02*
G03I-631J0D01*
G01X198775Y-128635D02*
G03I-1458J0D01*
G01X195808Y-125255D02*
G03I-1869J0D01*
G01X200547Y-113952D02*
G03X203345Y-117196I7247J3422D01*
G01X192148Y-121285D02*
G03I-2180J0D01*
G01X187928Y-127802D02*
G03I-1584J0D01*
G01X189667Y-131511D02*
G03I-1283J0D01*
G01X200699Y-105836D02*
G03X200547Y-113953I8974J-4228D01*
G01X208284Y-101612D02*
G03X200698Y-105835I-219J-8531D01*
G01X192148Y-98951D02*
G03I-2180J0D01*
G01X191108Y-82727D02*
G03I-634J0D01*
G01X190184Y-85250D02*
G03I-893J0D01*
G01X195808Y-94981D02*
G03I-1869J0D01*
G01X187839Y-92457D02*
G03I-1584J0D01*
G01X189190Y-88538D02*
G03I-1283J0D01*
G01X184970Y76150D02*
Y56850D01*
G01X189070Y58200D02*
Y59800D01*
G01X184970Y58200D02*
X189070D01*
G01X200970Y59100D02*
Y63100D01*
G01X198570Y59100D02*
X200970D01*
G01X198570Y63100D02*
Y59100D01*
G01X200970Y63100D02*
X198570D01*
G01X189070Y74800D02*
X184970D01*
G01X189070Y73200D02*
Y74800D01*
G01X184970Y73200D02*
X189070D01*
G01Y69800D02*
X184970D01*
G01X189070Y68200D02*
Y69800D01*
G01X184970Y68200D02*
X189070D01*
G01Y64800D02*
X184970D01*
G01X189070Y63200D02*
Y64800D01*
G01X184970Y63200D02*
X189070D01*
G01Y59800D02*
X184970D01*
G01X186500Y302800D02*
Y305200D01*
G01X187300Y294000D02*
X189700D01*
G01X187300Y298000D02*
Y294000D01*
G01X189700Y298000D02*
X187300D01*
G01X189700Y294000D02*
Y298000D01*
G01X184700Y294000D02*
Y298000D01*
G01X186000Y317800D02*
Y320200D01*
G01X189500Y308000D02*
Y313000D01*
G01X185500Y323500D02*
Y328500D01*
G01X197100Y328800D02*
X194700D01*
G01X197100Y324800D02*
Y328800D01*
G01X194700Y324800D02*
X197100D01*
G01X194700Y328800D02*
Y324800D01*
G01X214259Y-115661D02*
G03X213314Y-114453I-714J415D01*
G01X202049Y-108260D02*
G03X205722Y-116181I7039J-1548D01*
G01X218075Y-112869D02*
G03X219083Y-115752I4343J-99D01*
G01X208854Y-116658D02*
G03X213313Y-114452I-2485J10632D01*
G01X208470Y-118462D02*
G03X214261Y-115663I-1122J9711D01*
G01X203346Y-117195D02*
G03X208470Y-118461I4545J7394D01*
G01X205721Y-116179D02*
G03X208853Y-116659I2561J6250D01*
G01X215903Y-114020D02*
G03X219079Y-118061I6190J1597D01*
G01X215904Y-114020D02*
Y-111835D01*
G01X227413Y-112869D02*
X218074D01*
G01X214175Y-103951D02*
G03X208283Y-101613I-6403J-7542D01*
G01X213150Y-105147D02*
G03X214175Y-103951I410J686D01*
G01X213152Y-105146D02*
G03X208030Y-103430I-5122J-6786D01*
G01X208029Y-103429D02*
G03X202049Y-108259I-48J-6058D01*
G01X225189Y-111399D02*
G03X218071I-3559J159D01*
G01X218070Y-111418D02*
Y-111399D01*
G01X225188Y-111418D02*
X218070D01*
G01X227412Y-111835D02*
G03X215906I-5753J223D01*
G01X209300Y59500D02*
X211700D01*
G01X209300Y63500D02*
Y59500D01*
G01X211700Y63500D02*
X209300D01*
G01X211700Y59500D02*
Y63500D01*
G01X213800Y59500D02*
X216200D01*
G01X213800Y63500D02*
Y59500D01*
G01X216200Y63500D02*
X213800D01*
G01X216200Y59500D02*
Y63500D01*
G01X205970Y59100D02*
Y63100D01*
G01X203570Y59100D02*
X205970D01*
G01X203570Y63100D02*
Y59100D01*
G01X205970Y63100D02*
X203570D01*
G01X216100Y293200D02*
X218500D01*
G01X216100Y297200D02*
Y293200D01*
G01X218500Y297200D02*
X216100D01*
G01X218500Y293200D02*
Y297200D01*
G01X211600Y293200D02*
X214000D01*
G01X211600Y297200D02*
Y293200D01*
G01X214000Y297200D02*
X211600D01*
G01X214000Y293200D02*
Y297200D01*
G01X207100Y293200D02*
X209500D01*
G01X207100Y297200D02*
Y293200D01*
G01X209500Y297200D02*
X207100D01*
G01X209500Y293200D02*
Y297200D01*
G01X207500Y311500D02*
Y323500D01*
G01X219500Y311500D02*
X207500D01*
G01Y323500D02*
X219500D01*
G01X218800Y388600D02*
X216400D01*
G01X218800Y384600D02*
Y388600D01*
G01X216400Y384600D02*
X218800D01*
G01X216400Y388600D02*
Y384600D01*
G01X211061Y411576D02*
Y383624D01*
G01X216100Y411100D02*
Y403100D01*
G01D02*
X221100D01*
G01Y411100D02*
X216100D01*
G01X230059Y-117625D02*
Y-102034D01*
G01X230060Y-117626D02*
G03X232080I1010J239D01*
G01X226590Y-116472D02*
G03X225311Y-115210I-817J451D01*
G01X234673Y-114020D02*
G03X237849Y-118061I6190J1597D01*
G01X232081Y-102041D02*
Y-117625D01*
G01X219083Y-115753D02*
G03X225311Y-115211I2844J3371D01*
G01X219079Y-118060D02*
G03X226591Y-116473I2662J5972D01*
G01X227413Y-111835D02*
Y-112869D01*
G01X232080Y-102041D02*
G03X230060Y-102034I-1011J-236D01*
G01X225188Y-111399D02*
Y-111418D01*
G01X234675Y-114020D02*
Y-111835D01*
G01X246181D02*
G03X234675I-5753J223D01*
G01X221250Y1981D02*
X219250Y-19D01*
G01X221250Y29331D02*
Y1981D01*
G01X228750D02*
Y29331D01*
G01X230750Y-19D02*
X228750Y1981D01*
G01X310200Y-19D02*
X230750D01*
G01X225000Y33081D02*
G03X221250Y29331I0J-3750D01*
G01X228750D02*
G03X225000Y33081I-3750J0D01*
G01X220600Y293200D02*
X223000D01*
G01X220600Y297200D02*
Y293200D01*
G01X223000Y297200D02*
X220600D01*
G01X223000Y293200D02*
Y297200D01*
G01X219500Y323500D02*
Y311500D01*
G01X225080Y324600D02*
X227480D01*
G01X225080Y328600D02*
Y324600D01*
G01X227480Y328600D02*
X225080D01*
G01X227480Y324600D02*
Y328600D01*
G01X226100Y382100D02*
Y390100D01*
G01X221100Y382100D02*
X226100D01*
G01X221100Y390100D02*
Y382100D01*
G01X226100Y390100D02*
X221100D01*
G01X223600Y411100D02*
Y403100D01*
G01X228600D02*
Y411100D01*
G01X223600Y403100D02*
X228600D01*
G01X221100D02*
Y411100D01*
G01X228600D02*
X223600D01*
G01X252849Y-116771D02*
G03X254892Y-115895I-74J2994D01*
G01X236844Y-112869D02*
G03X237852Y-115752I4343J-99D01*
G01X237848Y-118060D02*
G03X245360Y-116473I2662J5972D01*
G01X245358Y-116472D02*
G03X244079Y-115210I-817J451D01*
G01X237852Y-115753D02*
G03X244080Y-115211I2844J3371D01*
G01X249566Y-115529D02*
G03X252307Y-116760I2985J2980D01*
G01Y-116761D02*
G03X252849Y-116772I366J4691D01*
G01X250282Y-118087D02*
G03X254318Y-118340I2605J9244D01*
G01X247897Y-116444D02*
G03X250283Y-118086I3752J2898D01*
G01X249568Y-115529D02*
G03X247898Y-116443I-748J-616D01*
G01X255608Y-108618D02*
G03X253612Y-107689I-3116J-4086D01*
G01X246181Y-111835D02*
Y-112869D01*
G01D02*
X236844D01*
G01X255002Y-114328D02*
G03X252723Y-112986I-3540J-3405D01*
G01X249955Y-112030D02*
G03X252723Y-112985I8208J19302D01*
G01X243957Y-111399D02*
Y-111418D01*
G01X243958Y-111399D02*
G03X236840I-3559J159D01*
G01X236841Y-111418D02*
Y-111399D01*
G01X243957Y-111418D02*
X236841D01*
G01X248537Y-109748D02*
G03X249956Y-112031I2652J66D01*
G01X248537Y-108250D02*
Y-109748D01*
G01X250179Y-106359D02*
G03X248537Y-108249I2747J-4045D01*
G01X256884Y-107368D02*
G03X250178Y-106359I-4153J-4811D01*
G01X253611Y-107689D02*
G03X251080Y-107949I-869J-3992D01*
G01X251081Y-107948D02*
G03X250837Y-110104I805J-1183D01*
G01Y-110106D02*
G03X254306Y-111513I5270J8013D01*
G01X252322Y58500D02*
Y62500D01*
G01X249922Y58500D02*
X252322D01*
G01X249922Y62500D02*
Y58500D01*
G01X252322Y62500D02*
X249922D01*
G01X258567Y93443D02*
G02I-4600J0D01*
G01X267106Y309646D02*
G02I-11200J0D01*
G01Y412008D02*
G02I-11200J0D01*
G01X260954Y-116041D02*
Y-107954D01*
G01X254892Y-115895D02*
G03X255001Y-114328I-764J840D01*
G01X269619Y-117484D02*
Y-106797D01*
G01X269620Y-117484D02*
G03X271926I1153J198D01*
G01X266864Y-117375D02*
G03X266002Y-116329I-764J249D01*
G01X262978Y-115462D02*
G03X266002Y-116329I2046J1428D01*
G01X260955Y-116043D02*
G03X264164Y-118351I2956J725D01*
G01X265463Y-118350D02*
X264165D01*
G01X265464Y-118352D02*
G03X266864Y-117374I-24J1525D01*
G01X256906Y-116470D02*
G03X257054Y-113728I-3143J1545D01*
G01X254317Y-118340D02*
G03X256906Y-116470I-1259J4470D01*
G01X262978Y-107954D02*
Y-115463D01*
G01X257054Y-113729D02*
G03X254307Y-111513I-3470J-1490D01*
G01X271969Y-102342D02*
G03I-1194J0D01*
G01X271926Y-106797D02*
G03X269620I-1153J-409D01*
G01X266003Y-107954D02*
X262978D01*
G01X266004Y-107955D02*
G03X266008Y-105932I-177J1012D01*
G01X262978D02*
X266008D01*
G01X262971Y-103419D02*
X262978Y-105932D01*
G01X262972Y-103418D02*
G03X260954Y-103491I-1005J-141D01*
G01Y-105932D02*
Y-103492D01*
G01X259930Y-105932D02*
X260954D01*
G01X259930D02*
G03X259981Y-107955I298J-1005D01*
G01X260954Y-107954D02*
X259982D01*
G01X255606Y-108620D02*
G03X256885Y-107367I599J667D01*
G01X259600Y61700D02*
Y59300D01*
G01X263600D02*
Y61700D01*
G01X259600Y59300D02*
X263600D01*
G01Y61700D02*
X259600D01*
G01X263600Y64300D02*
Y66700D01*
G01X259600Y64300D02*
X263600D01*
G01X259600Y66700D02*
Y64300D01*
G01X263600Y66700D02*
X259600D01*
G01X270567Y93443D02*
G02I-4600J0D01*
G01X280567Y112143D02*
G02I-12000J0D01*
G01Y255943D02*
G02I-12000J0D01*
G01X290671Y-110842D02*
G03X290703Y-118351I860J-3751D01*
G01X276837Y-114305D02*
G03X278891Y-116297I4069J2141D01*
G01X274529Y-113568D02*
G03X275888Y-116443I5718J944D01*
G01X275887D02*
G03X279572Y-118352I4392J3967D01*
G01X281425Y-118350D02*
X279571D01*
G01X281425D02*
G03X284525Y-117161I0J4636D01*
G01X285201Y-116508D02*
X284524Y-117161D01*
G01X285201Y-116508D02*
G03X283966Y-115211I-695J574D01*
G01X281510Y-116675D02*
G03X283966Y-115212I-989J4453D01*
G01X278889Y-116297D02*
G03X281508Y-116677I1946J4197D01*
G01X271926Y-106797D02*
Y-117484D01*
G01X274529Y-113566D02*
Y-111839D01*
G01X276446Y-112943D02*
G03X276837Y-114305I4162J458D01*
G01X276445Y-112066D02*
Y-112943D01*
G01X283833Y-109274D02*
G03X285403Y-108106I585J852D01*
G01X285402D02*
G03X280919Y-105777I-4776J-3714D01*
G01X279541D02*
X280919D01*
G01X279540D02*
G03X274999Y-109274I1260J-6333D01*
G01X274998D02*
G03X274529Y-111839I9988J-3152D01*
G01X276849Y-109932D02*
G03X276446Y-112066I5467J-2137D01*
G01X280036Y-107542D02*
G03X276849Y-109933I664J-4205D01*
G01X282662Y-108199D02*
G03X280037Y-107539I-2313J-3650D01*
G01X283833Y-109275D02*
G03X282662Y-108202I-9277J-8949D01*
G01X282850Y57449D02*
Y58433D01*
X284819D01*
Y57449D01*
X282850D01*
G01X275381D02*
Y58433D01*
X277350D01*
Y57449D01*
X275381D01*
G01X277349Y60008D02*
Y58433D01*
G01X282851Y62567D02*
Y58433D01*
G01Y56270D02*
Y57449D01*
G01X277349Y56270D02*
X282851D01*
G01X277349Y57449D02*
Y56270D01*
G01X278328D02*
Y64730D01*
G01X281872D02*
Y56270D01*
G01X275381Y60008D02*
Y60992D01*
X277350D01*
Y60008D01*
X275381D01*
G01Y62567D02*
Y63551D01*
X277350D01*
Y62567D01*
X275381D01*
G01X282850D02*
Y63551D01*
X284819D01*
Y62567D01*
X282850D01*
G01X277349D02*
Y60992D01*
G01X282851Y64730D02*
Y63551D01*
G01X277349Y64730D02*
X282851D01*
G01X277349Y63551D02*
Y64730D01*
G01X282467Y93443D02*
G02I-4600J0D01*
G01X290667Y104043D02*
G02I-4600J0D01*
G01X295884Y166325D02*
X273836D01*
G01D02*
Y199847D01*
G01X275747Y201759D02*
X295884D01*
G01X273836Y199847D02*
X275747Y201759D01*
G01X290667Y264043D02*
G02I-4600J0D01*
G01X294457Y-116619D02*
G03Y-112289I-51J2165D01*
G01X291853Y-116620D02*
X294456D01*
G01X291853Y-112289D02*
G03Y-116619I195J-2165D01*
G01X294165Y-118350D02*
X290701D01*
G01X294165D02*
G03X296471Y-117226I-1088J5161D01*
G01X296473Y-117625D02*
Y-117226D01*
G01X296474Y-117627D02*
G03X298494I1010J185D01*
G01X298495Y-109394D02*
Y-117625D01*
G01X301067Y-108534D02*
Y-106508D01*
G01X301615Y-108534D02*
X301067D01*
G01X301615Y-106508D02*
Y-108534D01*
G01X302461Y-106508D02*
X301615D01*
G01X302461Y-106001D02*
Y-106508D01*
G01X300223Y-106001D02*
X302461D01*
G01X300223Y-106508D02*
Y-106001D01*
G01X301067Y-106508D02*
X300223D01*
G01X305164Y-106001D02*
X304731D01*
G01X305713Y-108544D02*
X305164Y-106001D01*
G01X305171Y-108544D02*
X305713D01*
G01X304889Y-106871D02*
X305171Y-108544D01*
G01X304309D02*
X304889Y-106871D01*
G01X304086Y-108544D02*
X304309D01*
G01X303501Y-106887D02*
X304086Y-108544D01*
G01X303226D02*
X303501Y-106887D01*
G01X302698Y-108544D02*
X303226D01*
G01X303243Y-106001D02*
X302698Y-108544D01*
G01X303648Y-106001D02*
X303243D01*
G01X304192Y-107632D02*
X303648Y-106001D01*
G01X304731D02*
X304192Y-107632D01*
G01X294456Y-112288D02*
X291853D01*
G01X296473Y-110841D02*
Y-109686D01*
G01X296472Y-110841D02*
G03X292878Y-110536I-3256J-17043D01*
G01X292879Y-110535D02*
G03X290670Y-110842I280J-10112D01*
G01X298496Y-109394D02*
G03X295031Y-105933I-3962J-501D01*
G01X291563Y-105932D02*
X295031D01*
G01X291562D02*
G03X289112Y-107085I584J-4421D01*
G01Y-107086D02*
G03X289820Y-108520I585J-603D01*
G01X290987Y-107954D02*
G03X289821Y-108520I1446J-4464D01*
G01X294740Y-107954D02*
X290987D01*
G01X296473Y-109686D02*
G03X294742Y-107955I-1598J133D01*
G01X295500Y58641D02*
Y56241D01*
G01X299500Y58641D02*
X295500D01*
G01X299500Y56241D02*
Y58641D01*
G01X295500Y56241D02*
X299500D01*
G01X295620Y67980D02*
Y65580D01*
G01X299620Y67980D02*
X295620D01*
G01X299620Y65580D02*
Y67980D01*
G01X295620Y65580D02*
X299620D01*
G01X295600Y63300D02*
Y60900D01*
G01X299600Y63300D02*
X295600D01*
G01X299600Y60900D02*
Y63300D01*
G01X295600Y60900D02*
X299600D01*
G01X295884Y201759D02*
Y166325D01*
G01X293600Y319400D02*
Y321800D01*
G01X289600Y319400D02*
X293600D01*
G01X289600Y321800D02*
Y319400D01*
G01X293600Y321800D02*
X289600D01*
G01Y327100D02*
Y324700D01*
G01X293600Y327100D02*
X289600D01*
G01X293600Y324700D02*
Y327100D01*
G01X289600Y324700D02*
X293600D01*
G01X289700Y334400D02*
Y332000D01*
G01X293700Y334400D02*
X289700D01*
G01X293700Y332000D02*
Y334400D01*
G01X289700Y332000D02*
X293700D01*
G01X291024Y371539D02*
Y401461D01*
G01X318976Y371539D02*
X291024D01*
G01Y401461D02*
X318976D01*
G01X312200Y1981D02*
X310200Y-19D01*
G01X312200Y36281D02*
Y1981D01*
G01X316500Y163300D02*
Y165700D01*
G01X312500Y163300D02*
X316500D01*
G01X312500Y165700D02*
Y163300D01*
G01X316400Y178800D02*
Y181200D01*
G01X312400Y178800D02*
X316400D01*
G01X312400Y181200D02*
Y178800D01*
G01X316500Y165700D02*
X312500D01*
G01Y170700D02*
Y168300D01*
G01X316500Y170700D02*
X312500D01*
G01X316500Y168300D02*
Y170700D01*
G01X312500Y168300D02*
X316500D01*
G01X316400Y173800D02*
Y176200D01*
G01X312400Y173800D02*
X316400D01*
G01X312400Y176200D02*
Y173800D01*
G01X316400Y176200D02*
X312400D01*
G01X320900Y195300D02*
Y197700D01*
G01X316900Y195300D02*
X320900D01*
G01X316900Y197700D02*
Y195300D01*
G01X320900Y197700D02*
X316900D01*
G01X316400Y181200D02*
X312400D01*
G01X312000Y190700D02*
Y188300D01*
G01X316000Y190700D02*
X312000D01*
G01X316000Y188300D02*
Y190700D01*
G01X312000Y188300D02*
X316000D01*
G01X312000Y186200D02*
Y183800D01*
G01X316000Y186200D02*
X312000D01*
G01X316000Y183800D02*
Y186200D01*
G01X312000Y183800D02*
X316000D01*
G01X320900Y200300D02*
Y202700D01*
G01X316900Y200300D02*
X320900D01*
G01X316900Y202700D02*
Y200300D01*
G01X320900Y202700D02*
X316900D01*
G01X320900Y204800D02*
Y207200D01*
G01X316900Y204800D02*
X320900D01*
G01X316900Y207200D02*
Y204800D01*
G01X320900Y207200D02*
X316900D01*
G01X320900Y209800D02*
Y212200D01*
G01X316900Y209800D02*
X320900D01*
G01X316900Y212200D02*
Y209800D01*
G01X320900Y212200D02*
X316900D01*
G01X320000Y215200D02*
Y217600D01*
G01X316000Y215200D02*
X320000D01*
G01X316000Y217600D02*
Y215200D01*
G01X320000Y217600D02*
X316000D01*
G01X320000Y219700D02*
Y222100D01*
G01X316000Y219700D02*
X320000D01*
G01X316000Y222100D02*
Y219700D01*
G01X320000Y222100D02*
X316000D01*
G01X320000Y228700D02*
Y231100D01*
G01X316000Y228700D02*
X320000D01*
G01X316000Y231100D02*
Y228700D01*
G01X320000Y231100D02*
X316000D01*
G01Y226600D02*
Y224200D01*
G01X320000Y226600D02*
X316000D01*
G01X320000Y224200D02*
Y226600D01*
G01X316000Y224200D02*
X320000D01*
G01Y246700D02*
Y249100D01*
G01X316000Y246700D02*
X320000D01*
G01X316000Y249100D02*
Y246700D01*
G01X320000Y249100D02*
X316000D01*
G01X320000Y233200D02*
Y235600D01*
G01X316000Y233200D02*
X320000D01*
G01X316000Y235600D02*
Y233200D01*
G01X320000Y235600D02*
X316000D01*
G01Y240100D02*
Y237700D01*
G01X320000Y240100D02*
X316000D01*
G01X320000Y237700D02*
Y240100D01*
G01X316000Y237700D02*
X320000D01*
G01X316000Y244600D02*
Y242200D01*
G01X320000Y244600D02*
X316000D01*
G01X320000Y242200D02*
Y244600D01*
G01X316000Y242200D02*
X320000D01*
G01Y251200D02*
Y253600D01*
G01X316000Y251200D02*
X320000D01*
G01X316000Y253600D02*
Y251200D01*
G01X320000Y253600D02*
X316000D01*
G01X320000Y255700D02*
Y258100D01*
G01X316000Y255700D02*
X320000D01*
G01X316000Y258100D02*
Y255700D01*
G01X320000Y258100D02*
X316000D01*
G01X307550Y321650D02*
Y341350D01*
G01X324850Y321650D02*
X307550D01*
G01Y341350D02*
X324850D01*
G01X318976Y401461D02*
Y371539D01*
G01X327100Y197000D02*
Y201000D01*
G01X324700Y197000D02*
X327100D01*
G01X324700Y201000D02*
Y197000D01*
G01X325500Y217700D02*
Y215300D01*
G01X329500D02*
Y217700D01*
G01X325500Y215300D02*
X329500D01*
G01X327100Y201000D02*
X324700D01*
G01X327100Y210500D02*
X324700D01*
G01X327100Y206500D02*
Y210500D01*
G01X324700Y206500D02*
X327100D01*
G01X324700Y210500D02*
Y206500D01*
G01X329500Y217700D02*
X325500D01*
G01X331520Y221164D02*
Y241636D01*
G01X346480Y221164D02*
X331520D01*
G01Y241636D02*
X346480D01*
G01X337284Y251200D02*
X339684D01*
G01X337284Y255200D02*
Y251200D01*
G01X339684Y255200D02*
X337284D01*
G01X339684Y251200D02*
Y255200D01*
G01X334700D02*
X332300D01*
G01X334700Y251200D02*
Y255200D01*
G01X332300Y251200D02*
X334700D01*
G01X332300Y255200D02*
Y251200D01*
G01X327300D02*
X329700D01*
G01X327300Y255200D02*
Y251200D01*
G01X329700Y255200D02*
X327300D01*
G01X329700Y251200D02*
Y255200D01*
G01X324394Y272307D02*
X343606D01*
G01X324394Y290693D02*
Y272307D01*
G01X343606Y290693D02*
X324394D01*
G01X324850Y341350D02*
Y321650D01*
G01X324300Y366500D02*
X326700D01*
G01X324300Y370500D02*
Y366500D01*
G01X326700Y370500D02*
X324300D01*
G01X326700Y366500D02*
Y370500D01*
G01X337500Y372500D02*
Y364500D01*
G01X342500Y372500D02*
X337500D01*
G01Y364500D02*
X342500D01*
G01X329500Y372500D02*
Y364500D01*
G01X334500Y372500D02*
X329500D01*
G01X334500Y364500D02*
Y372500D01*
G01X329500Y364500D02*
X334500D01*
G01X334800Y387500D02*
Y389900D01*
G01X330800Y387500D02*
X334800D01*
G01X330800Y389900D02*
Y387500D01*
G01X334800Y389900D02*
X330800D01*
G01X327800Y380200D02*
X335800D01*
G01X327800Y385200D02*
Y380200D01*
G01X335800Y385200D02*
X327800D01*
G01X335800Y380200D02*
Y385200D01*
G01X328213Y394113D02*
Y408287D01*
G01X342387Y394113D02*
X328213D01*
G01X332800Y412500D02*
Y414900D01*
G01X328800Y412500D02*
X332800D01*
G01X328800Y414900D02*
Y412500D01*
G01X332800Y414900D02*
X328800D01*
G01X324800Y417700D02*
X332800D01*
G01X324800Y422700D02*
Y417700D01*
G01X332800Y422700D02*
X324800D01*
G01X332800Y417700D02*
Y422700D01*
G01X341821Y410919D02*
G02I-2000J0D01*
G01X328213Y408287D02*
X342387D01*
G01X340600Y422000D02*
X347000D01*
G01X340600Y418400D02*
Y422000D01*
G01X347000Y418400D02*
X340600D01*
G01X356300Y158000D02*
X358700D01*
G01X356300Y162000D02*
Y158000D01*
G01X358700Y162000D02*
X356300D01*
G01X349000Y165500D02*
Y157500D01*
G01X354000D02*
Y165500D01*
G01X349000Y157500D02*
X354000D01*
G01Y165500D02*
X349000D01*
G01X354200Y174649D02*
X356600D01*
G01X354200Y178649D02*
Y174649D01*
G01X356600Y178649D02*
X354200D01*
G01X356600Y174649D02*
Y178649D01*
G01X350661Y187809D02*
X358141D01*
G01X350661Y195289D02*
Y187809D01*
G01X358141Y195289D02*
X350661D01*
G01X358141Y187809D02*
Y195289D01*
G01X359559Y231766D02*
X354441D01*
G01D02*
Y240034D01*
G01X346480Y241636D02*
Y221164D01*
G01X354441Y240034D02*
X359559D01*
G01X350900Y250400D02*
X347300D01*
G01X350900Y256800D02*
Y250400D01*
G01X347300D02*
Y256800D01*
G01X355800Y255400D02*
X353400D01*
G01X355800Y251400D02*
Y255400D01*
G01X353400Y251400D02*
X355800D01*
G01X353400Y255400D02*
Y251400D01*
G01X342300Y251200D02*
X344700D01*
G01X342300Y255200D02*
Y251200D01*
G01X344700Y255200D02*
X342300D01*
G01X344700Y251200D02*
Y255200D01*
G01X347300Y256800D02*
X350900D01*
G01X359400Y280200D02*
X357000D01*
G01Y276200D02*
X359400D01*
G01X357000Y280200D02*
Y276200D01*
G01X343606Y272307D02*
Y290693D01*
G01X357000Y285700D02*
X359400D01*
G01X357000Y289700D02*
Y285700D01*
G01X359400Y289700D02*
X357000D01*
G01X351693Y320193D02*
X373307D01*
G01X351693Y341807D02*
Y320193D01*
G01X373307Y341807D02*
X351693D01*
G01X342500Y364500D02*
Y372500D01*
G01X345500D02*
Y364500D01*
G01X350500Y372500D02*
X345500D01*
G01X350500Y364500D02*
Y372500D01*
G01X345500Y364500D02*
X350500D01*
G01X352560Y388550D02*
X355040D01*
G01X352560Y389850D02*
Y388550D01*
G01X355040Y389850D02*
X352560D01*
G01X355040Y388550D02*
Y389850D01*
G01X356300Y382100D02*
Y384500D01*
G01X352300Y382100D02*
X356300D01*
G01X352300Y384500D02*
Y382100D01*
G01X356300Y384500D02*
X352300D01*
G01X353500Y376800D02*
Y379200D01*
G01X349500Y376800D02*
X353500D01*
G01X349500Y379200D02*
Y376800D01*
G01X353500Y379200D02*
X349500D01*
G01X345500Y385700D02*
X343100D01*
G01X345500Y381700D02*
Y385700D01*
G01X343100Y381700D02*
X345500D01*
G01X343100Y385700D02*
Y381700D01*
G01X352300Y404400D02*
Y402000D01*
G01X356300Y404400D02*
X352300D01*
G01X356300Y402000D02*
Y404400D01*
G01X352300Y402000D02*
X356300D01*
G01X352300Y399900D02*
Y397500D01*
G01X356300Y399900D02*
X352300D01*
G01X356300Y397500D02*
Y399900D01*
G01X352300Y397500D02*
X356300D01*
G01X355040Y395350D02*
X352560D01*
G01X355040Y394050D02*
Y395350D01*
G01X352560Y394050D02*
X355040D01*
G01X352560Y395350D02*
Y394050D01*
G01X352300Y408900D02*
Y406500D01*
G01X356300D02*
Y408900D01*
G01X352300Y406500D02*
X356300D01*
G01X342387Y408287D02*
Y394113D01*
G01X355300Y420900D02*
Y418500D01*
G01X359300Y420900D02*
X355300D01*
G01Y418500D02*
X359300D01*
G01X352460Y411450D02*
X354940D01*
G01X352460Y412750D02*
Y411450D01*
G01X354940Y412750D02*
X352460D01*
G01X354940Y411450D02*
Y412750D01*
G01X356300Y408900D02*
X352300D01*
G01X347000Y422000D02*
Y418400D01*
G01X378200Y91500D02*
X375800D01*
G01Y87500D02*
X378200D01*
G01X375800Y91500D02*
Y87500D01*
G01X380500Y108500D02*
X372500D01*
G01Y103500D02*
X380500D01*
G01X372500Y108500D02*
Y103500D01*
G01X367700Y148800D02*
Y145200D01*
G01X361300D02*
Y148800D01*
G01X367700Y145200D02*
X361300D01*
G01X358700Y158000D02*
Y162000D01*
G01X368000Y165500D02*
Y157500D01*
G01X373000D02*
Y165500D01*
G01X368000Y157500D02*
X373000D01*
G01X361300Y148800D02*
X367700D01*
G01X373000Y165500D02*
X368000D01*
G01X361600Y178649D02*
X359200D01*
G01X361600Y174649D02*
Y178649D01*
G01X359200Y174649D02*
X361600D01*
G01X359200Y178649D02*
Y174649D01*
G01X364323Y232360D02*
Y234840D01*
G01X363023Y232360D02*
X364323D01*
G01X363023Y234840D02*
Y232360D01*
G01X359559Y240034D02*
Y231766D01*
G01X368700Y222300D02*
Y218700D01*
G01X362300Y222300D02*
X368700D01*
G01X362300Y218700D02*
Y222300D01*
G01X368700Y218700D02*
X362300D01*
G01X371700Y242500D02*
X369300D01*
G01X371700Y238500D02*
Y242500D01*
G01X369300Y238500D02*
X371700D01*
G01X369300Y242500D02*
Y238500D01*
G01X364323Y234840D02*
X363023D01*
G01Y241440D02*
Y238960D01*
G01X364323Y241440D02*
X363023D01*
G01X364323Y238960D02*
Y241440D01*
G01X363023Y238960D02*
X364323D01*
G01X374800Y238500D02*
X377200D01*
G01X374800Y242500D02*
Y238500D01*
G01X377200Y242500D02*
X374800D01*
G01X368516Y251094D02*
Y254244D01*
G01X370484Y251094D02*
X368516D01*
G01X370484Y254244D02*
Y251094D01*
G01X372256D02*
Y254244D01*
G01X374224Y251094D02*
X372256D01*
G01X374224Y254244D02*
Y251094D01*
G01X364776D02*
Y254244D01*
G01X366744Y251094D02*
X364776D01*
G01X366744Y254244D02*
Y251094D01*
G01X364579Y254638D02*
Y259362D01*
G01X374421Y254638D02*
X364579D01*
G01X374421Y259362D02*
Y254638D01*
G01X364579Y259362D02*
X374421D01*
G01X364776Y259756D02*
Y262906D01*
G01X366744Y259756D02*
X364776D01*
G01X366744Y262906D02*
Y259756D01*
G01X364776Y262906D02*
X366744D01*
G01X372256Y259756D02*
Y262906D01*
G01X374224Y259756D02*
X372256D01*
G01X374224Y262906D02*
Y259756D01*
G01X372256Y262906D02*
X374224D01*
G01X368516Y259756D02*
Y262906D01*
G01X370484Y259756D02*
X368516D01*
G01X370484Y262906D02*
Y259756D01*
G01X368516Y262906D02*
X370484D01*
G01X368516Y254244D02*
X370484D01*
G01X372256D02*
X374224D01*
G01X364776D02*
X366744D01*
G01X374421Y259362D02*
X375209Y260150D01*
G01X374421Y254638D02*
X375209Y253850D01*
G01X363791D02*
X364579Y254638D01*
G01X363791Y260150D02*
X364579Y259362D01*
G01X363791Y253850D02*
X364776D01*
G01X363791Y260150D02*
Y253850D01*
G01X364776Y260150D02*
X363791D01*
G01X368516Y253850D02*
X366744D01*
G01X368516Y254244D02*
Y253850D01*
G01X370484Y254244D02*
X368516D01*
G01X370484Y253850D02*
Y254244D01*
G01X372256Y253850D02*
X370484D01*
G01X368516Y260150D02*
X366744D01*
G01X372256D02*
X370484D01*
G01X375209Y253850D02*
X374224D01*
G01X375209Y260150D02*
Y253850D01*
G01X374224Y260150D02*
X375209D01*
G01X370400Y287700D02*
Y279700D01*
G01X375400D02*
Y287700D01*
G01X370400Y279700D02*
X375400D01*
G01X369000Y272200D02*
Y269800D01*
G01X373000Y272200D02*
X369000D01*
G01X373000Y269800D02*
Y272200D01*
G01X369000Y269800D02*
X373000D01*
G01X359400Y276200D02*
Y280200D01*
G01Y285700D02*
Y289700D01*
G01X367400Y301700D02*
X365000D01*
G01X367400Y297700D02*
Y301700D01*
G01X365000Y297700D02*
X367400D01*
G01X365000Y301700D02*
Y297700D01*
G01X375700Y294500D02*
Y302500D01*
G01X370700Y294500D02*
X375700D01*
G01X370700Y302500D02*
Y294500D01*
G01X375700Y302500D02*
X370700D01*
G01X375400Y287700D02*
X370400D01*
G01X373307Y320193D02*
Y341807D01*
G01X364900Y308100D02*
Y311700D01*
G01X371300Y308100D02*
X364900D01*
G01X371300Y311700D02*
Y308100D01*
G01X364900Y311700D02*
X371300D01*
G01X361100Y383700D02*
X363500D01*
G01X361100Y387700D02*
Y383700D01*
G01X363500Y387700D02*
X361100D01*
G01X363500Y383700D02*
Y387700D01*
G01X359300Y418500D02*
Y420900D01*
G01X411976Y72461D02*
X384024D01*
G01D02*
Y92539D01*
G01X378200Y87500D02*
Y91500D01*
G01X384024Y92539D02*
X411976D01*
G01X387000Y98200D02*
Y95800D01*
G01X391000Y98200D02*
X387000D01*
G01X391000Y95800D02*
Y98200D01*
G01X387000Y95800D02*
X391000D01*
G01X381000D02*
Y98200D01*
G01X377000Y95800D02*
X381000D01*
G01X377000Y98200D02*
Y95800D01*
G01X381000Y98200D02*
X377000D01*
G01X380500Y103500D02*
Y108500D01*
G01X385224Y129224D02*
X475776D01*
G01X385224Y219776D02*
Y129224D01*
G01X475776Y219776D02*
X385224D01*
G01X377200Y238500D02*
Y242500D01*
G01X393100Y251100D02*
Y255100D01*
G01X390700Y251100D02*
X393100D01*
G01X390700Y255100D02*
Y251100D01*
G01X393100Y255100D02*
X390700D01*
G01X392700Y266800D02*
X396700D01*
G01X392700Y269200D02*
Y266800D01*
G01X381700Y269200D02*
Y266800D01*
G01X385700D02*
Y269200D01*
G01X381700Y266800D02*
X385700D01*
G01X387200Y251100D02*
Y255100D01*
G01X384800Y251100D02*
X387200D01*
G01X384800Y255100D02*
Y251100D01*
G01X387200Y255100D02*
X384800D01*
G01X381300Y251100D02*
Y255100D01*
G01X378900Y251100D02*
X381300D01*
G01X378900Y255100D02*
Y251100D01*
G01X381300Y255100D02*
X378900D01*
G01X378500Y285000D02*
X380900D01*
G01X378500Y289000D02*
Y285000D01*
G01X380900D02*
Y289000D01*
G01X381700Y278700D02*
Y276300D01*
G01X385700Y278700D02*
X381700D01*
G01X385700Y276300D02*
Y278700D01*
G01X381700Y276300D02*
X385700D01*
G01X396700Y269200D02*
X392700D01*
G01Y273700D02*
Y271300D01*
G01X396700Y273700D02*
X392700D01*
G01Y271300D02*
X396700D01*
G01X385700Y269200D02*
X381700D01*
G01Y273700D02*
Y271300D01*
G01X385700Y273700D02*
X381700D01*
G01X385700Y271300D02*
Y273700D01*
G01X381700Y271300D02*
X385700D01*
G01X380900Y301000D02*
X378500D01*
G01X380900Y297000D02*
Y301000D01*
G01X378500Y297000D02*
X380900D01*
G01X378500Y301000D02*
Y297000D01*
G01X380900Y289000D02*
X378500D01*
G01X397204Y288496D02*
X385196D01*
G01Y300504D02*
X397204D01*
G01X385196Y288496D02*
Y300504D01*
G01X389200Y310400D02*
Y308000D01*
G01X393200Y310400D02*
X389200D01*
G01X393200Y308000D02*
Y310400D01*
G01X389200Y308000D02*
X393200D01*
G01X379400Y310400D02*
Y308000D01*
G01X383400Y310400D02*
X379400D01*
G01X383400Y308000D02*
Y310400D01*
G01X379400Y308000D02*
X383400D01*
G01X380273Y321590D02*
G02I-1500J0D01*
G01X385800Y342500D02*
X388200D01*
G01X385800Y346500D02*
Y342500D01*
G01X388200Y346500D02*
X385800D01*
G01X388200Y342500D02*
Y346500D01*
G01X388000Y379800D02*
Y382200D01*
G01X384000Y379800D02*
X388000D01*
G01X384000Y382200D02*
Y379800D01*
G01X388000Y382200D02*
X384000D01*
G01X388000Y374600D02*
Y377000D01*
G01X384000Y374600D02*
X388000D01*
G01X384000Y377000D02*
Y374600D01*
G01X388000Y377000D02*
X384000D01*
G01X399800Y103000D02*
X402200D01*
G01X399800Y107000D02*
Y103000D01*
G01X402200Y107000D02*
X399800D01*
G01X402200Y103000D02*
Y107000D01*
G01X404300Y103000D02*
X406700D01*
G01X404300Y107000D02*
Y103000D01*
G01X406700Y107000D02*
X404300D01*
G01X406700Y103000D02*
Y107000D01*
G01X406000Y98200D02*
Y95800D01*
G01X410000Y98200D02*
X406000D01*
G01X410000Y95800D02*
Y98200D01*
G01X406000Y95800D02*
X410000D01*
G01X400500D02*
Y98200D01*
G01X396500Y95800D02*
X400500D01*
G01X396500Y98200D02*
Y95800D01*
G01X400500Y98200D02*
X396500D01*
G01X404900Y251100D02*
Y255100D01*
G01X402500Y251100D02*
X404900D01*
G01X402500Y255100D02*
Y251100D01*
G01X404900Y255100D02*
X402500D01*
G01X399000Y251100D02*
Y255100D01*
G01X396600Y251100D02*
X399000D01*
G01X396600Y255100D02*
Y251100D01*
G01X399000Y255100D02*
X396600D01*
G01X396700Y266800D02*
Y269200D01*
G01X410500Y251100D02*
Y255100D01*
G01X408100Y251100D02*
X410500D01*
G01X408100Y255100D02*
Y251100D01*
G01X410500Y255100D02*
X408100D01*
G01X396440Y278050D02*
X393960D01*
G01X396440Y276750D02*
Y278050D01*
G01X393960Y276750D02*
X396440D01*
G01X393960Y278050D02*
Y276750D01*
G01X396700Y271300D02*
Y273700D01*
G01X397204Y300504D02*
Y288496D01*
G01X397550Y310240D02*
Y307760D01*
G01X398850Y310240D02*
X397550D01*
G01X398850Y307760D02*
Y310240D01*
G01X397550Y307760D02*
X398850D01*
G01X397400Y330300D02*
Y327900D01*
G01X401400Y330300D02*
X397400D01*
G01X401400Y327900D02*
Y330300D01*
G01X397400Y327900D02*
X401400D01*
G01X397400Y325100D02*
Y322700D01*
G01X401400Y325100D02*
X397400D01*
G01X401400Y322700D02*
Y325100D01*
G01X397400Y322700D02*
X401400D01*
G01X406800Y343000D02*
X409200D01*
G01X406800Y347000D02*
Y343000D01*
G01X409200Y347000D02*
X406800D01*
G01X409200Y343000D02*
Y347000D01*
G01X393669Y346957D02*
X402331D01*
G01X393669Y341643D02*
Y346957D01*
G01X402331Y341643D02*
X393669D01*
G01X402331Y346957D02*
Y341643D01*
G01X406850Y357650D02*
Y377350D01*
G01X424150Y357650D02*
X406850D01*
G01X404557Y389357D02*
X424243D01*
G01X404557Y409043D02*
Y389357D01*
G01X406850Y377350D02*
X424150D01*
G01X424243Y409043D02*
X404557D01*
G01X411976Y92539D02*
Y72461D01*
G01X421700Y92000D02*
X419300D01*
G01X421700Y88000D02*
Y92000D01*
G01X419300Y88000D02*
X421700D01*
G01X419300Y92000D02*
Y88000D01*
G01X446439Y80004D02*
X426361D01*
G01Y92996D02*
X446439D01*
G01X426361Y80004D02*
Y92996D01*
G01X422100Y251100D02*
Y255100D01*
G01X419700Y251100D02*
X422100D01*
G01X419700Y255100D02*
Y251100D01*
G01X422100Y255100D02*
X419700D01*
G01X416200Y251100D02*
Y255100D01*
G01X413800Y251100D02*
X416200D01*
G01X413800Y255100D02*
Y251100D01*
G01X416200Y255100D02*
X413800D01*
G01X418600Y278000D02*
Y280400D01*
G01X414600Y278000D02*
X418600D01*
G01X414600Y280400D02*
Y278000D01*
G01X418600Y280400D02*
X414600D01*
G01X412700Y283000D02*
X420700D01*
G01X412700Y288000D02*
Y283000D01*
G01X420700D02*
Y288000D01*
G01D02*
X412700D01*
G01Y291100D02*
X420700D01*
G01X412700Y296100D02*
Y291100D01*
G01X420700Y296100D02*
X412700D01*
G01X420700Y291100D02*
Y296100D01*
G01X420250Y305750D02*
Y325450D01*
G01X437550Y305750D02*
X420250D01*
G01Y325450D02*
X437550D01*
G01X413169Y347157D02*
X421831D01*
G01X413169Y341843D02*
Y347157D01*
G01X421831Y341843D02*
X413169D01*
G01X421831Y347157D02*
Y341843D01*
G01X424150Y377350D02*
Y357650D01*
G01X424243Y389357D02*
Y409043D01*
G01X435700Y103200D02*
X438100D01*
G01X435700Y107200D02*
Y103200D01*
G01X438100Y107200D02*
X435700D01*
G01X438100Y103200D02*
Y107200D01*
G01X440200Y103200D02*
X442600D01*
G01X440200Y107200D02*
Y103200D01*
G01X442600Y107200D02*
X440200D01*
G01X442600Y103200D02*
Y107200D01*
G01X436300Y96100D02*
Y98500D01*
G01X432300Y96100D02*
X436300D01*
G01X432300Y98500D02*
Y96100D01*
G01X436300Y98500D02*
X432300D01*
G01X441900D02*
Y96100D01*
G01X445900Y98500D02*
X441900D01*
G01Y96100D02*
X445900D01*
G01X436550Y111100D02*
Y113500D01*
G01X432550Y111100D02*
X436550D01*
G01X432550Y113500D02*
Y111100D01*
G01X441750Y113500D02*
Y111100D01*
G01D02*
X445750D01*
G01X436550Y113500D02*
X432550D01*
G01X445750D02*
X441750D01*
G01X440700Y246000D02*
X438300D01*
G01X440700Y242000D02*
Y246000D01*
G01X438300Y242000D02*
X440700D01*
G01X438300Y246000D02*
Y242000D01*
G01X442800D02*
X445200D01*
G01X442800Y246000D02*
Y242000D01*
G01X445200Y246000D02*
X442800D01*
G01X445200Y242000D02*
Y246000D01*
G01X443000Y266500D02*
X448000D01*
G01X443000Y274500D02*
Y266500D01*
G01X440200Y274000D02*
X437800D01*
G01X440200Y270000D02*
Y274000D01*
G01X437800Y270000D02*
X440200D01*
G01X437800Y274000D02*
Y270000D01*
G01X448000Y274500D02*
X443000D01*
G01X441506Y281694D02*
Y293506D01*
G01X429694Y281694D02*
X441506D01*
G01X429694Y293506D02*
Y281694D01*
G01X441506Y293506D02*
X429694D01*
G01X437550Y325450D02*
Y305750D01*
G01X435200Y349500D02*
X432800D01*
G01X435200Y345500D02*
Y349500D01*
G01X432800Y345500D02*
X435200D01*
G01X432800Y349500D02*
Y345500D01*
G01X449200Y354900D02*
X437800D01*
G01D02*
Y360100D01*
G01X440700Y353000D02*
X438900D01*
G01X440700Y354900D02*
Y353000D01*
G01X438900Y354900D02*
X440700D01*
G01X438900Y353000D02*
Y354900D01*
G01X437800D02*
X438100Y355200D01*
G01X438900Y353900D02*
X440700D01*
G01X438500Y371200D02*
Y368800D01*
G01X442500Y371200D02*
X438500D01*
G01X442500Y368800D02*
Y371200D01*
G01X438500Y368800D02*
X442500D01*
G01X448900Y355200D02*
X438100D01*
G01D02*
Y359800D01*
G01X437800Y360100D02*
X449200D01*
G01X438100Y359800D02*
X448900D01*
G01X444400Y360100D02*
X442600D01*
G01X444400Y362000D02*
Y360100D01*
G01X442600Y362000D02*
X444400D01*
G01X442600Y360100D02*
Y362000D01*
G01X437800Y360100D02*
X438100Y359800D01*
G01X442600Y361100D02*
X444400D01*
G01X438500Y380200D02*
Y377800D01*
G01X442500Y380200D02*
X438500D01*
G01X442500Y377800D02*
Y380200D01*
G01X438500Y377800D02*
X442500D01*
G01X439500Y385300D02*
Y387700D01*
G01X435500Y385300D02*
X439500D01*
G01X435500Y387700D02*
Y385300D01*
G01X439500Y387700D02*
X435500D01*
G01X438500Y375700D02*
Y373300D01*
G01X442500Y375700D02*
X438500D01*
G01X442500Y373300D02*
Y375700D01*
G01X438500Y373300D02*
X442500D01*
G01X435500Y397700D02*
Y395300D01*
G01X439500Y397700D02*
X435500D01*
G01X439500Y395300D02*
Y397700D01*
G01X435500Y395300D02*
X439500D01*
G01X435500Y402700D02*
Y400300D01*
G01X439500Y402700D02*
X435500D01*
G01X439500Y400300D02*
Y402700D01*
G01X435500Y400300D02*
X439500D01*
G01Y390300D02*
Y392700D01*
G01X435500Y390300D02*
X439500D01*
G01X435500Y392700D02*
Y390300D01*
G01X439500Y392700D02*
X435500D01*
G01X439500Y405300D02*
Y407700D01*
G01X435500Y405300D02*
X439500D01*
G01X435500Y407700D02*
Y405300D01*
G01X439500Y407700D02*
X435500D01*
G01X439500Y410300D02*
Y412700D01*
G01X435500Y410300D02*
X439500D01*
G01X435500Y412700D02*
Y410300D01*
G01X439500Y412700D02*
X435500D01*
G01X446439Y92996D02*
Y80004D01*
G01X445900Y96100D02*
Y98500D01*
G01X445750Y111100D02*
Y113500D01*
G01X459700Y118000D02*
X457300D01*
G01X459700Y114000D02*
Y118000D01*
G01X457300Y114000D02*
X459700D01*
G01X457300Y118000D02*
Y114000D01*
G01X454200Y118000D02*
X451800D01*
G01X454200Y114000D02*
Y118000D01*
G01X451800Y114000D02*
X454200D01*
G01X451800Y118000D02*
Y114000D01*
G01X452300Y232500D02*
X454700D01*
G01X452300Y236500D02*
Y232500D01*
G01X454700D02*
Y236500D01*
G01X456300Y242000D02*
X458700D01*
G01X456300Y246000D02*
Y242000D01*
G01X458700Y246000D02*
X456300D01*
G01X458700Y242000D02*
Y246000D01*
G01X447300Y242000D02*
X449700D01*
G01X447300Y246000D02*
Y242000D01*
G01X449700Y246000D02*
X447300D01*
G01X449700Y242000D02*
Y246000D01*
G01X454700Y236500D02*
X452300D01*
G01X451800Y242000D02*
X454200D01*
G01X451800Y246000D02*
Y242000D01*
G01X454200Y246000D02*
X451800D01*
G01X454200Y242000D02*
Y246000D01*
G01X460800Y242000D02*
X463200D01*
G01X460800Y246000D02*
Y242000D01*
G01X463200Y246000D02*
X460800D01*
G01X448000Y266500D02*
Y274500D01*
G01X452500Y285700D02*
Y283300D01*
G01X456500D02*
Y285700D01*
G01X452500Y283300D02*
X456500D01*
G01X452500Y290700D02*
Y288300D01*
G01X456500Y290700D02*
X452500D01*
G01X456500Y288300D02*
Y290700D01*
G01X452500Y288300D02*
X456500D01*
G01X452500Y295700D02*
Y293300D01*
G01X456500Y295700D02*
X452500D01*
G01X456500Y293300D02*
Y295700D01*
G01X452500Y293300D02*
X456500D01*
G01Y298300D02*
Y300700D01*
G01X452500Y298300D02*
X456500D01*
G01X452500Y300700D02*
Y298300D01*
G01X456500Y300700D02*
X452500D01*
G01X456500Y285700D02*
X452500D01*
G01X451000Y328200D02*
Y325800D01*
G01X455000Y328200D02*
X451000D01*
G01X455000Y325800D02*
Y328200D01*
G01X451000Y325800D02*
X455000D01*
G01X455300Y320800D02*
Y323200D01*
G01X451300Y320800D02*
X455300D01*
G01X451300Y323200D02*
Y320800D01*
G01X455300Y323200D02*
X451300D01*
G01X449200Y360100D02*
Y354900D01*
G01X448100Y353000D02*
X446300D01*
G01X448100Y354900D02*
Y353000D01*
G01X446300Y354900D02*
X448100D01*
G01X446300Y353000D02*
Y354900D01*
G01X448900Y355200D02*
X449200Y354900D01*
G01X446300Y353900D02*
X448100D01*
G01X448900Y359800D02*
Y355200D01*
G01Y359800D02*
X449200Y360100D01*
G01X451800Y385000D02*
X454200D01*
G01X451800Y389000D02*
Y385000D01*
G01X454200Y389000D02*
X451800D01*
G01X454200Y385000D02*
Y389000D01*
G01X459300Y387800D02*
X465700D01*
G01X459300Y384200D02*
Y387800D01*
G01X465700Y384200D02*
X459300D01*
G01X458100Y390200D02*
X466100D01*
G01X458100Y395200D02*
Y390200D01*
G01X466100Y395200D02*
X458100D01*
G01X469500Y87700D02*
Y85300D01*
G01X473500Y87700D02*
X469500D01*
G01X473500Y85300D02*
Y87700D01*
G01X469500Y85300D02*
X473500D01*
G01X469500Y79700D02*
Y77300D01*
G01X473500Y79700D02*
X469500D01*
G01X473500Y77300D02*
Y79700D01*
G01X469500Y77300D02*
X473500D01*
G01X469500Y92700D02*
Y90300D01*
G01X473500Y92700D02*
X469500D01*
G01X473500Y90300D02*
Y92700D01*
G01X469500Y90300D02*
X473500D01*
G01X469500Y97700D02*
Y95300D01*
G01X473500Y97700D02*
X469500D01*
G01X473500Y95300D02*
Y97700D01*
G01X469500Y95300D02*
X473500D01*
G01X475776Y129224D02*
Y219776D01*
G01X463800Y230000D02*
X466200D01*
G01X463800Y234000D02*
Y230000D01*
G01X466200D02*
Y234000D01*
G01X463200Y242000D02*
Y246000D01*
G01X466200Y234000D02*
X463800D01*
G01X478900Y242600D02*
Y255200D01*
G01X469100Y242600D02*
X478900D01*
G01X469100Y255200D02*
Y242600D01*
G01X478900Y255200D02*
X469100D01*
G01X474700Y354500D02*
X472300D01*
G01X474700Y350500D02*
Y354500D01*
G01X472300Y350500D02*
X474700D01*
G01X472300Y354500D02*
Y350500D01*
G01X479700Y354500D02*
X477300D01*
G01X479700Y350500D02*
Y354500D01*
G01X477300Y350500D02*
X479700D01*
G01X477300Y354500D02*
Y350500D01*
G01X493232Y362191D02*
X476972D01*
G01D02*
Y395841D01*
G01X465700Y387800D02*
Y384200D01*
G01X466100Y390200D02*
Y395200D01*
G01X476972Y395841D02*
X493232D01*
G01X491850Y73150D02*
Y92850D01*
G01X509150Y73150D02*
X491850D01*
G01Y92850D02*
X509150D01*
G01X492600Y123900D02*
X500600D01*
G01X492600Y128900D02*
Y123900D01*
G01X500600Y128900D02*
X492600D01*
G01X496000Y137300D02*
X500000D01*
G01X496000Y139700D02*
Y137300D01*
G01X500000Y139700D02*
X496000D01*
G01Y144200D02*
Y141800D01*
G01X500000Y144200D02*
X496000D01*
G01Y141800D02*
X500000D01*
G01X496000Y132300D02*
X500000D01*
G01X496000Y134700D02*
Y132300D01*
G01X500000Y134700D02*
X496000D01*
G01X492500Y161800D02*
Y164200D01*
G01X488500Y161800D02*
X492500D01*
G01X488500Y164200D02*
Y161800D01*
G01X492500Y166300D02*
Y168700D01*
G01X488500Y166300D02*
X492500D01*
G01X488500Y168700D02*
Y166300D01*
G01X492500Y168700D02*
X488500D01*
G01X492500Y164200D02*
X488500D01*
G01X492500Y175300D02*
Y177700D01*
G01X488500Y175300D02*
X492500D01*
G01X488500Y177700D02*
Y175300D01*
G01X492500Y177700D02*
X488500D01*
G01Y173200D02*
Y170800D01*
G01X492500Y173200D02*
X488500D01*
G01X492500Y170800D02*
Y173200D01*
G01X488500Y170800D02*
X492500D01*
G01Y196300D02*
Y198700D01*
G01X488500Y196300D02*
X492500D01*
G01X488500Y198700D02*
Y196300D01*
G01X492500Y210300D02*
Y212700D01*
G01X488500Y210300D02*
X492500D01*
G01X488500Y212700D02*
Y210300D01*
G01X492500Y212700D02*
X488500D01*
G01X492500Y201300D02*
Y203700D01*
G01X488500Y201300D02*
X492500D01*
G01X488500Y203700D02*
Y201300D01*
G01X492500Y203700D02*
X488500D01*
G01X492500Y198700D02*
X488500D01*
G01X492500Y205800D02*
Y208200D01*
G01X488500Y205800D02*
X492500D01*
G01X488500Y208200D02*
Y205800D01*
G01X492500Y208200D02*
X488500D01*
G01X495100Y246100D02*
X491500D01*
G01X495100Y252500D02*
Y246100D01*
G01X491500D02*
Y252500D01*
G01X494800Y259500D02*
X497200D01*
G01X494800Y263500D02*
Y259500D01*
G01X497200Y263500D02*
X494800D01*
G01X497200Y259500D02*
Y263500D01*
G01X491500Y252500D02*
X495100D01*
G01X494900Y268700D02*
X497300D01*
G01X494900Y272700D02*
Y268700D01*
G01X497300Y272700D02*
X494900D01*
G01X497300Y268700D02*
Y272700D01*
G01X495060Y277050D02*
X497540D01*
G01X495060Y278350D02*
Y277050D01*
G01X497540Y278350D02*
X495060D01*
G01X497540Y277050D02*
Y278350D01*
G01X490100Y272700D02*
X487700D01*
G01X490100Y268700D02*
Y272700D01*
G01X487700Y268700D02*
X490100D01*
G01X487700Y272700D02*
Y268700D01*
G01X505294Y309646D02*
G02I-11200J0D01*
G01X487300Y350500D02*
X489700D01*
G01X487300Y354500D02*
Y350500D01*
G01X489700Y354500D02*
X487300D01*
G01X489700Y350500D02*
Y354500D01*
G01X484700D02*
X482300D01*
G01X484700Y350500D02*
Y354500D01*
G01X482300Y350500D02*
X484700D01*
G01X482300Y354500D02*
Y350500D01*
G01X497300D02*
X499700D01*
G01X497300Y354500D02*
Y350500D01*
G01X499700Y354500D02*
X497300D01*
G01X492300Y350500D02*
X494700D01*
G01X492300Y354500D02*
Y350500D01*
G01X494700Y354500D02*
X492300D01*
G01X494700Y350500D02*
Y354500D01*
G01X493232Y395841D02*
Y362191D01*
G01X505294Y412008D02*
G02I-11200J0D01*
G01X509150Y92850D02*
Y73150D01*
G01X500600Y123900D02*
Y128900D01*
G01X500000Y137300D02*
Y139700D01*
G01Y141800D02*
Y144200D01*
G01Y132300D02*
Y134700D01*
G01X501500Y248600D02*
Y246200D01*
G01X505500Y248600D02*
X501500D01*
G01X505500Y246200D02*
Y248600D01*
G01X501500Y246200D02*
X505500D01*
G01X504300Y260900D02*
Y258500D01*
G01X508300Y260900D02*
X504300D01*
G01X508300Y258500D02*
Y260900D01*
G01X504300Y258500D02*
X508300D01*
G01X508700Y250900D02*
Y255900D01*
G01X500700Y250900D02*
X508700D01*
G01X500700Y255900D02*
Y250900D01*
G01X508700Y255900D02*
X500700D01*
G01X504796Y264696D02*
Y276704D01*
G01X516804Y264696D02*
X504796D01*
G01Y276704D02*
X516804D01*
G01X499700Y350500D02*
Y354500D01*
G01X513000Y376300D02*
Y378700D01*
G01X509000Y376300D02*
X513000D01*
G01X509000Y378700D02*
Y376300D01*
G01X513000Y378700D02*
X509000D01*
G01X507500Y383000D02*
Y391000D01*
G01X502500Y383000D02*
X507500D01*
G01X502500Y391000D02*
Y383000D01*
G01X513800Y384800D02*
X510200D01*
G01X513800Y391200D02*
Y384800D01*
G01X510200D02*
Y391200D01*
G01X507500Y391000D02*
X502500D01*
G01X510200Y391200D02*
X513800D01*
G01X529000Y74800D02*
Y77200D01*
G01X525000Y74800D02*
X529000D01*
G01X525000Y77200D02*
Y74800D01*
G01Y93200D02*
Y90800D01*
G01X529000Y93200D02*
X525000D01*
G01X529000Y90800D02*
Y93200D01*
G01X525000Y90800D02*
X529000D01*
G01Y77200D02*
X525000D01*
G01X529000Y80800D02*
Y83200D01*
G01X525000Y80800D02*
X529000D01*
G01X525000Y83200D02*
Y80800D01*
G01X529000Y83200D02*
X525000D01*
G01X529000Y85800D02*
Y88200D01*
G01X525000Y85800D02*
X529000D01*
G01X525000Y88200D02*
Y85800D01*
G01X529000Y88200D02*
X525000D01*
G01X528000Y126500D02*
X520000D01*
G01X528000Y121500D02*
Y126500D01*
G01X520000Y121500D02*
X528000D01*
G01X520000Y126500D02*
Y121500D01*
G01X530800Y142100D02*
Y151900D01*
G01X518200Y142100D02*
X530800D01*
G01X518200Y151900D02*
Y142100D01*
G01X530800Y129600D02*
Y139400D01*
G01X518200Y129600D02*
X530800D01*
G01X518200Y139400D02*
Y129600D01*
G01X530800Y139400D02*
X518200D01*
G01X530800Y151900D02*
X518200D01*
G01X530800Y154600D02*
Y164400D01*
G01X518200Y154600D02*
X530800D01*
G01X518200Y164400D02*
Y154600D01*
G01X532500Y186000D02*
Y178000D01*
G01D02*
X537500D01*
G01X530800Y164400D02*
X518200D01*
G01X517800Y170700D02*
Y174300D01*
G01X524200Y170700D02*
X517800D01*
G01X524200Y174300D02*
Y170700D01*
G01X517800Y174300D02*
X524200D01*
G01X537500Y186000D02*
X532500D01*
G01X534300Y227900D02*
X531900D01*
G01Y223900D02*
X534300D01*
G01X531900Y227900D02*
Y223900D01*
G01X515500Y249600D02*
X523500D01*
G01X515500Y254600D02*
Y249600D01*
G01X523500D02*
Y254600D01*
G01X520300Y258000D02*
Y260400D01*
G01X516300Y258000D02*
X520300D01*
G01X516300Y260400D02*
Y258000D01*
G01X520300Y260400D02*
X516300D01*
G01X523500Y254600D02*
X515500D01*
G01X526600Y261200D02*
X529000D01*
G01X526600Y265200D02*
Y261200D01*
G01X529000Y265200D02*
X526600D01*
G01X529000Y261200D02*
Y265200D01*
G01X531600Y261200D02*
X534000D01*
G01X531600Y265200D02*
Y261200D01*
G01X534000Y265200D02*
X531600D01*
G01X516804Y276704D02*
Y264696D01*
G01X529240Y273150D02*
X526760D01*
G01X529240Y271850D02*
Y273150D01*
G01X526760Y271850D02*
X529240D01*
G01X526760Y273150D02*
Y271850D01*
G01X528200Y281000D02*
X525800D01*
G01X528200Y277000D02*
Y281000D01*
G01X525800Y277000D02*
X528200D01*
G01X525800Y281000D02*
Y277000D01*
G01X530300D02*
X532700D01*
G01X530300Y281000D02*
Y277000D01*
G01X532700Y281000D02*
X530300D01*
G01X532700Y277000D02*
Y281000D01*
G01X528104Y318356D02*
Y342844D01*
G01X556096Y318356D02*
X528104D01*
G01X523752Y336069D02*
Y341069D01*
G01X528104Y342844D02*
X556096D01*
G01X521252Y338569D02*
X526252D01*
G01X522900Y374500D02*
Y366500D01*
G01X527900D02*
Y374500D01*
G01X522900Y366500D02*
X527900D01*
G01X531100Y374500D02*
Y366500D01*
G01D02*
X536100D01*
G01X529100Y380200D02*
X537100D01*
G01X529100Y385200D02*
Y380200D01*
G01X537100Y385200D02*
X529100D01*
G01X527900Y374500D02*
X522900D01*
G01X536100D02*
X531100D01*
G01X530900Y388400D02*
Y392000D01*
G01X537300Y388400D02*
X530900D01*
G01X532100Y396900D02*
Y394500D01*
G01X536100Y396900D02*
X532100D01*
G01Y394500D02*
X536100D01*
G01X530900Y392000D02*
X537300D01*
G01X530072Y414654D02*
Y421348D01*
G01X526528Y414654D02*
X530072D01*
G01X526528Y421348D02*
Y414654D01*
G01X530072Y421348D02*
X526528D01*
G01X528000Y426701D02*
Y431701D01*
G01X530500Y429201D02*
X525500D01*
G01X543760Y62850D02*
X546240D01*
G01X543760Y64150D02*
Y62850D01*
G01X546240Y64150D02*
X543760D01*
G01X546240Y62850D02*
Y64150D01*
G01X540500Y70200D02*
Y67800D01*
G01X544500Y70200D02*
X540500D01*
G01X544500Y67800D02*
Y70200D01*
G01X540500Y67800D02*
X544500D01*
G01X555700Y88800D02*
X547700D01*
G01Y83800D02*
X555700D01*
G01X547700Y88800D02*
Y83800D01*
G01X541500Y159000D02*
Y167000D01*
G01X536500Y159000D02*
X541500D01*
G01X536500Y167000D02*
Y159000D01*
G01X539800Y179500D02*
X542200D01*
G01X539800Y183500D02*
Y179500D01*
G01X542200D02*
Y183500D01*
G01X537500Y178000D02*
Y186000D01*
G01X541500Y167000D02*
X536500D01*
G01X546117Y168840D02*
X573283D01*
G01X546117Y198760D02*
Y168840D01*
G01X542200Y183500D02*
X539800D01*
G01X546200Y213000D02*
X543800D01*
G01X546200Y209000D02*
Y213000D01*
G01X543800Y209000D02*
X546200D01*
G01X543800Y213000D02*
Y209000D01*
G01X541000Y205000D02*
Y213000D01*
G01X536000Y205000D02*
X541000D01*
G01X536000Y213000D02*
Y205000D01*
G01X541000Y213000D02*
X536000D01*
G01X573283Y198760D02*
X546117D01*
G01X534300Y223900D02*
Y227900D01*
G01X547700Y232500D02*
Y236500D01*
G01X545300Y232500D02*
X547700D01*
G01X545300Y236500D02*
Y232500D01*
G01X549240Y219830D02*
G02I-2000J0D01*
G01X537700Y228800D02*
X541300D01*
G01X537700Y222400D02*
Y228800D01*
G01X541300Y222400D02*
X537700D01*
G01X541300Y228800D02*
Y222400D01*
G01X547700Y236500D02*
X545300D01*
G01X546200Y260788D02*
Y263308D01*
G01X551206Y260788D02*
X546200D01*
G01Y263308D02*
X551206D01*
G01X534000Y261200D02*
Y265200D01*
G01X546200Y280788D02*
Y283308D01*
G01X551206Y280788D02*
X546200D01*
G01Y283308D02*
X551206D01*
G01X546200Y270788D02*
Y273308D01*
G01X551206Y270788D02*
X546200D01*
G01Y273308D02*
X551206D01*
G01X546200Y300788D02*
Y303308D01*
G01X551206Y300788D02*
X546200D01*
G01Y290888D02*
Y293408D01*
G01X551206Y290888D02*
X546200D01*
G01Y293408D02*
X551206D01*
G01X546200Y303308D02*
X551206D01*
G01X547400Y355100D02*
Y358700D01*
G01X553800Y355100D02*
X547400D01*
G01X536100Y366500D02*
Y374500D01*
G01X547498Y363661D02*
X559702D01*
G01X547498Y383739D02*
Y363661D01*
G01X547400Y358700D02*
X553800D01*
G01X537100Y380200D02*
Y385200D01*
G01X559702Y383739D02*
X547498D01*
G01X537300Y392000D02*
Y388400D01*
G01X548360Y390550D02*
X550840D01*
G01X548360Y391850D02*
Y390550D01*
G01X550840Y391850D02*
X548360D01*
G01X545276Y407480D02*
Y414174D01*
G01X541732Y407480D02*
X545276D01*
G01X541732Y414174D02*
Y407480D01*
G01X546543Y395500D02*
X550543D01*
G01X546543Y397900D02*
Y395500D01*
G01X550543Y397900D02*
X546543D01*
G01X536100Y394500D02*
Y396900D01*
G01X552015Y417027D02*
X547015D01*
G01X549515Y414527D02*
Y419527D01*
G01X545276Y421259D02*
Y427953D01*
G01X541732Y421259D02*
X545276D01*
G01X541732Y427953D02*
Y421259D01*
G01X545276Y414174D02*
X541732D01*
G01X540204Y418027D02*
X535204D01*
G01X537704Y415527D02*
Y420527D01*
G01X553515Y433306D02*
X548515D01*
G01X539204Y429806D02*
Y434806D01*
G01X541704Y432306D02*
X536704D01*
G01X545276Y427953D02*
X541732D01*
G01X556496Y61896D02*
Y73904D01*
G01X568504Y61896D02*
X556496D01*
G01Y73904D02*
X568504D01*
G01X565000Y78000D02*
X569000D01*
G01X565000Y80400D02*
Y78000D01*
G01X569000Y80400D02*
X565000D01*
G01X552800D02*
Y78000D01*
G01X556800Y80400D02*
X552800D01*
G01X556800Y78000D02*
Y80400D01*
G01X552800Y78000D02*
X556800D01*
G01X560000Y92500D02*
Y100500D01*
G01X555000Y92500D02*
X560000D01*
G01X555000Y100500D02*
Y92500D01*
G01X562500Y83400D02*
X570500D01*
G01X562500Y88400D02*
Y83400D01*
G01X570500Y88400D02*
X562500D01*
G01X555700Y83800D02*
Y88800D01*
G01X565200Y98500D02*
X562800D01*
G01X565200Y94500D02*
Y98500D01*
G01X562800Y94500D02*
X565200D01*
G01X562800Y98500D02*
Y94500D01*
G01X560000Y100500D02*
X555000D01*
G01X565000Y158500D02*
X573000D01*
G01X565000Y163500D02*
Y158500D01*
G01X573000Y163500D02*
X565000D01*
G01X550413Y208413D02*
Y222587D01*
G01X564587Y208413D02*
X550413D01*
G01X564587Y222587D02*
Y208413D01*
G01X554300Y232500D02*
X556700D01*
G01X554300Y236500D02*
Y232500D01*
G01X556700D02*
Y236500D01*
G01X558800Y232500D02*
X561200D01*
G01X558800Y236500D02*
Y232500D01*
G01X561200D02*
Y236500D01*
G01X563350Y235240D02*
Y232760D01*
G01X564650D02*
Y235240D01*
G01X563350Y232760D02*
X564650D01*
G01X550350D02*
X551650D01*
G01X550350Y235240D02*
Y232760D01*
G01X551650D02*
Y235240D01*
G01X550413Y222587D02*
X564587D01*
G01X556700Y236500D02*
X554300D01*
G01X561200D02*
X558800D01*
G01X564650Y235240D02*
X563350D01*
G01X551650D02*
X550350D01*
G01X565500Y241200D02*
Y238800D01*
G01X569500Y241200D02*
X565500D01*
G01Y238800D02*
X569500D01*
G01X551206Y263308D02*
Y260788D01*
G01X551200Y257907D02*
Y306293D01*
G01X570400Y257907D02*
X551200D01*
G01X551206Y283308D02*
Y280788D01*
G01Y273308D02*
Y270788D01*
G01Y303308D02*
Y300788D01*
G01Y293408D02*
Y290888D01*
G01X551200Y306293D02*
X570400D01*
G01X556096Y342844D02*
Y318356D01*
G01X553800Y358700D02*
Y355100D01*
G01X559600Y358100D02*
Y355700D01*
G01X563600D02*
Y358100D01*
G01X559600Y355700D02*
X563600D01*
G01Y358100D02*
X559600D01*
G01X559702Y363661D02*
Y383739D01*
G01X550840Y390550D02*
Y391850D01*
G01X565354Y407480D02*
X568898D01*
G01X565354Y414174D02*
Y407480D01*
G01X557087D02*
Y414174D01*
G01X553543Y407480D02*
X557087D01*
G01X553543Y414174D02*
Y407480D01*
G01X556000Y392700D02*
Y390300D01*
G01X560000D02*
Y392700D01*
G01X556000Y390300D02*
X560000D01*
G01Y392700D02*
X556000D01*
G01X550543Y395500D02*
Y397900D01*
G01X560000Y394800D02*
Y397200D01*
G01X556000Y394800D02*
X560000D01*
G01X556000Y397200D02*
Y394800D01*
G01X560000Y397200D02*
X556000D01*
G01X557087Y421259D02*
Y427953D01*
G01X553543Y421259D02*
X557087D01*
G01X553543Y427953D02*
Y421259D01*
G01X568898Y414174D02*
X565354D01*
G01X565326Y416027D02*
X560326D01*
G01X562826Y413527D02*
Y418527D01*
G01X557087Y414174D02*
X553543D01*
G01X565354Y421259D02*
X568898D01*
G01X565354Y427953D02*
Y421259D01*
G01X551015Y430806D02*
Y435806D01*
G01X557087Y427953D02*
X553543D01*
G01X563326Y429806D02*
Y434806D01*
G01X565826Y432306D02*
X560826D01*
G01X568898Y427953D02*
X565354D01*
G01X578400Y69900D02*
X576000D01*
G01X578400Y65900D02*
Y69900D01*
G01X576000Y65900D02*
X578400D01*
G01X576000Y69900D02*
Y65900D01*
G01X578240Y61550D02*
X575760D01*
G01X578240Y60250D02*
Y61550D01*
G01X575760Y60250D02*
X578240D01*
G01X575760Y61550D02*
Y60250D01*
G01X578700Y75500D02*
Y79500D01*
G01X576300Y75500D02*
X578700D01*
G01X576300Y79500D02*
Y75500D01*
G01X568504Y73904D02*
Y61896D01*
G01X569000Y78000D02*
Y80400D01*
G01X570500Y83400D02*
Y88400D01*
G01X578700Y79500D02*
X576300D01*
G01X568200Y92800D02*
Y99200D01*
G01X571800Y92800D02*
X568200D01*
G01X571800Y99200D02*
Y92800D01*
G01X568200Y99200D02*
X571800D01*
G01X573000Y158500D02*
Y163500D01*
G01X573283Y168840D02*
Y198760D01*
G01X571200Y215000D02*
X568800D01*
G01X571200Y211000D02*
Y215000D01*
G01X568800Y211000D02*
X571200D01*
G01X568800Y215000D02*
Y211000D01*
G01X578500Y208000D02*
Y216000D01*
G01X573500Y208000D02*
X578500D01*
G01X573500Y216000D02*
Y208000D01*
G01X578500Y216000D02*
X573500D01*
G01X576600Y232500D02*
Y236500D01*
G01X574200Y232500D02*
X576600D01*
G01X574200Y236500D02*
Y232500D01*
G01X573000Y225700D02*
Y223300D01*
G01X577000Y225700D02*
X573000D01*
G01X577000Y223300D02*
Y225700D01*
G01X573000Y223300D02*
X577000D01*
G01X570150Y233260D02*
Y235740D01*
G01X568850Y233260D02*
X570150D01*
G01X568850Y235740D02*
Y233260D01*
G01X570150Y235740D02*
X568850D01*
G01X576600Y236500D02*
X574200D01*
G01X569500Y238800D02*
Y241200D01*
G01X570400Y260888D02*
Y263408D01*
G01X575406Y260888D02*
X570400D01*
G01X575406Y263408D02*
Y260888D01*
G01X570400Y263408D02*
X575406D01*
G01X570400Y306293D02*
Y257907D01*
G01Y270788D02*
Y273308D01*
G01X575406Y270788D02*
X570400D01*
G01X575406Y273308D02*
Y270788D01*
G01X570400Y273308D02*
X575406D01*
G01X570400Y280788D02*
Y283308D01*
G01X575406Y280788D02*
X570400D01*
G01X575406Y283308D02*
Y280788D01*
G01X570400Y283308D02*
X575406D01*
G01X570400Y290788D02*
Y293308D01*
G01X575406Y290788D02*
X570400D01*
G01X575406Y293308D02*
Y290788D01*
G01X570400Y293308D02*
X575406D01*
G01X570400Y300788D02*
Y303308D01*
G01X575406Y300788D02*
X570400D01*
G01X575406Y303308D02*
Y300788D01*
G01X570400Y303308D02*
X575406D01*
G01X572100Y352900D02*
Y350500D01*
G01X576100Y352900D02*
X572100D01*
G01X576100Y350500D02*
Y352900D01*
G01X572100Y350500D02*
X576100D01*
G01Y345500D02*
Y347900D01*
G01X572100Y345500D02*
X576100D01*
G01X572100Y347900D02*
Y345500D01*
G01X576100Y347900D02*
X572100D01*
G01Y357900D02*
Y355500D01*
G01X576100D02*
Y357900D01*
G01X572100Y355500D02*
X576100D01*
G01Y357900D02*
X572100D01*
G01X570860Y370550D02*
X573340D01*
G01X570860Y371850D02*
Y370550D01*
G01X573340Y371850D02*
X570860D01*
G01X573340Y370550D02*
Y371850D01*
G01X576100Y365500D02*
Y367900D01*
G01X572100Y365500D02*
X576100D01*
G01X572100Y367900D02*
Y365500D01*
G01X576100Y367900D02*
X572100D01*
G01X576100Y360500D02*
Y362900D01*
G01X572100Y360500D02*
X576100D01*
G01X572100Y362900D02*
Y360500D01*
G01X576100Y362900D02*
X572100D01*
G01Y386900D02*
Y384500D01*
G01X576100Y386900D02*
X572100D01*
G01X576100Y384500D02*
Y386900D01*
G01X572100Y384500D02*
X576100D01*
G01X572100Y381900D02*
Y379500D01*
G01X576100Y381900D02*
X572100D01*
G01X576100Y379500D02*
Y381900D01*
G01X572100Y379500D02*
X576100D01*
G01Y389500D02*
Y391900D01*
G01X572100Y389500D02*
X576100D01*
G01X572100Y391900D02*
Y389500D01*
G01X576100Y374500D02*
Y376900D01*
G01X572100Y374500D02*
X576100D01*
G01X572100Y376900D02*
Y374500D01*
G01X576100Y376900D02*
X572100D01*
G01X568898Y407480D02*
Y414174D01*
G01X580709Y407480D02*
Y414174D01*
G01X577165Y407480D02*
X580709D01*
G01X577165Y414174D02*
Y407480D01*
G01X576100Y391900D02*
X572100D01*
G01X580709Y414174D02*
X577165D01*
G01X577637Y417027D02*
X572637D01*
G01X575137Y414527D02*
Y419527D01*
G01X580709Y421259D02*
Y427953D01*
G01X577165Y421259D02*
X580709D01*
G01X577165Y427953D02*
Y421259D01*
G01X568898D02*
Y427953D01*
G01X575137Y430306D02*
Y435306D01*
G01X577637Y432806D02*
X572637D01*
G01X580709Y427953D02*
X577165D01*
G01X591500Y109200D02*
Y106800D01*
G01X595500D02*
Y109200D01*
G01X591500Y106800D02*
X595500D01*
G01Y109200D02*
X591500D01*
G01Y97700D02*
Y95300D01*
G01X595500Y97700D02*
X591500D01*
G01X595500Y95300D02*
Y97700D01*
G01X591500Y95300D02*
X595500D01*
G01X591500Y103700D02*
Y101300D01*
G01X595500Y103700D02*
X591500D01*
G01X595500Y101300D02*
Y103700D01*
G01X591500Y101300D02*
X595500D01*
G01Y111300D02*
Y113700D01*
G01X591500Y111300D02*
X595500D01*
G01Y113700D02*
X591500D01*
G01D02*
Y111300D01*
G01X590702Y190965D02*
X593102D01*
G01X590702Y194965D02*
Y190965D01*
G01X593102Y194965D02*
X590702D01*
G01X593102Y190965D02*
Y194965D01*
G01X595702Y190965D02*
X598102D01*
G01X595702Y194965D02*
Y190965D01*
G01X598102Y194965D02*
X595702D01*
G01X598102Y190965D02*
Y194965D01*
G01X603102D02*
X600702D01*
G01Y190965D02*
X603102D01*
G01X600702Y194965D02*
Y190965D01*
G01X593882Y204282D02*
X604118D01*
G01X593882Y214518D02*
Y204282D01*
G01X604118Y214518D02*
X593882D01*
G01X590053Y225100D02*
Y222700D01*
G01X594053Y225100D02*
X590053D01*
G01X594053Y222700D02*
Y225100D01*
G01X590053Y222700D02*
X594053D01*
G01Y227202D02*
Y229602D01*
G01X590053Y227202D02*
X594053D01*
G01X590053Y229602D02*
Y227202D01*
G01X594053Y229602D02*
X590053D01*
G01X594053Y231800D02*
Y234200D01*
G01X590053Y231800D02*
X594053D01*
G01X590053Y234200D02*
Y231800D01*
G01X594053Y234200D02*
X590053D01*
G01X597500Y260188D02*
Y262708D01*
G01X602506Y260188D02*
X597500D01*
G01X602506Y262708D02*
Y260188D01*
G01X597500Y262708D02*
X602506D01*
G01X602500Y257307D02*
Y305693D01*
G01X621700Y257307D02*
X602500D01*
G01X597500Y280188D02*
Y282708D01*
G01X602506Y280188D02*
X597500D01*
G01X602506Y282708D02*
Y280188D01*
G01X597500Y282708D02*
X602506D01*
G01X597500Y270188D02*
Y272708D01*
G01X602506Y270188D02*
X597500D01*
G01X602506Y272708D02*
Y270188D01*
G01X597500Y272708D02*
X602506D01*
G01X597500Y300188D02*
Y302708D01*
G01X602506Y300188D02*
X597500D01*
G01X602506Y302708D02*
Y300188D01*
G01X597500Y302708D02*
X602506D01*
G01X597500Y290288D02*
Y292808D01*
G01X602506Y290288D02*
X597500D01*
G01X602506Y292808D02*
Y290288D01*
G01X597500Y292808D02*
X602506D01*
G01X602500Y305693D02*
X621700D01*
G01X592520Y407480D02*
Y414174D01*
G01X588976Y407480D02*
X592520D01*
G01X588976Y414174D02*
Y407480D01*
G01X600787D02*
X604331D01*
G01X600787Y414174D02*
Y407480D01*
G01Y421259D02*
X604331D01*
G01X600787Y427953D02*
Y421259D01*
G01X590448Y420527D02*
Y425527D01*
G01X592948Y423027D02*
X587948D01*
G01X592520Y414174D02*
X588976D01*
G01X597259Y416527D02*
Y421527D01*
G01X599759Y419027D02*
X594759D01*
G01X604331Y414174D02*
X600787D01*
G01X604331Y427953D02*
X600787D01*
G01X600259Y431306D02*
X595259D01*
G01X597759Y428806D02*
Y433806D01*
G01X611500Y98500D02*
Y110500D01*
G01X623500Y98500D02*
X611500D01*
G01Y110500D02*
X623500D01*
G01X605702Y190965D02*
X608102D01*
G01X605702Y194965D02*
Y190965D01*
G01X608102Y194965D02*
X605702D01*
G01X608102Y190965D02*
Y194965D01*
G01X603102Y190965D02*
Y194965D01*
G01X604118Y204282D02*
Y214518D01*
G01X603000Y228200D02*
Y225800D01*
G01X607000Y228200D02*
X603000D01*
G01X607000Y225800D02*
Y228200D01*
G01X603000Y225800D02*
X607000D01*
G01X603000Y223700D02*
Y221300D01*
G01X607000Y223700D02*
X603000D01*
G01X607000Y221300D02*
Y223700D01*
G01X603000Y221300D02*
X607000D01*
G01X615300Y231900D02*
X612900D01*
G01X615300Y227900D02*
Y231900D01*
G01X612900Y227900D02*
X615300D01*
G01X612900Y231900D02*
Y227900D01*
G01X602800Y230600D02*
Y234200D01*
G01X609200Y230600D02*
X602800D01*
G01X609200Y234200D02*
Y230600D01*
G01X602800Y234200D02*
X609200D01*
G01X608898Y323071D02*
Y378897D01*
G01X660787Y323071D02*
X608898D01*
G01Y378897D02*
X660787D01*
G01X604331Y407480D02*
Y414174D01*
G01X616142Y407480D02*
Y414174D01*
G01X612598Y407480D02*
X616142D01*
G01X612598Y414174D02*
Y407480D01*
G01X604331Y421259D02*
Y427953D01*
G01X616142Y421259D02*
Y427953D01*
G01X612598Y421259D02*
X616142D01*
G01X612598Y427953D02*
Y421259D01*
G01X609070Y414527D02*
Y419527D01*
G01X611570Y417027D02*
X606570D01*
G01X616142Y414174D02*
X612598D01*
G01X616142Y427953D02*
X612598D01*
G01X612070Y431806D02*
X607070D01*
G01X609570Y429306D02*
Y434306D01*
G01X651839Y65354D02*
G02I-11800J0D01*
G01X623500Y110500D02*
Y98500D01*
G01X660297Y120567D02*
X626281D01*
G01D02*
Y183559D01*
G01X630100Y197174D02*
Y201174D01*
G01X627700Y197174D02*
X630100D01*
G01X627700Y201174D02*
Y197174D01*
G01X620000Y196374D02*
X625000D01*
G01X620000Y204374D02*
Y196374D01*
G01X625000D02*
Y204374D01*
G01X626281Y183559D02*
X660297D01*
G01X630100Y201174D02*
X627700D01*
G01X625000Y204374D02*
X620000D01*
G01X622068Y223472D02*
Y228196D01*
G01X631910Y223472D02*
X622068D01*
G01X631910Y228196D02*
Y223472D01*
G01X622068Y228196D02*
X631910D01*
G01X622265Y228590D02*
Y231740D01*
G01X624233Y228590D02*
X622265D01*
G01X624233Y231740D02*
Y228590D01*
G01X622265Y231740D02*
X624233D01*
G01X629745Y228590D02*
Y231740D01*
G01X631713Y228590D02*
X629745D01*
G01X631713Y231740D02*
Y228590D01*
G01X629745Y231740D02*
X631713D01*
G01X626005Y228590D02*
Y231740D01*
G01X627973Y228590D02*
X626005D01*
G01X627973Y231740D02*
Y228590D01*
G01X626005Y231740D02*
X627973D01*
G01X626005Y219928D02*
Y223078D01*
G01X627973Y219928D02*
X626005D01*
G01X627973Y223078D02*
Y219928D01*
G01X626005Y223078D02*
X627973D01*
G01X629745Y219928D02*
Y223078D01*
G01X631713Y219928D02*
X629745D01*
G01X631713Y223078D02*
Y219928D01*
G01X629745Y223078D02*
X631713D01*
G01X622265Y219928D02*
Y223078D01*
G01X624233Y219928D02*
X622265D01*
G01X624233Y223078D02*
Y219928D01*
G01X622265Y223078D02*
X624233D01*
G01X631910Y228196D02*
X632698Y228984D01*
G01X631910Y223472D02*
X632698Y222684D01*
G01X621280D02*
X622068Y223472D01*
G01X621280Y228984D02*
X622068Y228196D01*
G01X621280Y222684D02*
X622265D01*
G01X621280Y228984D02*
Y222684D01*
G01X622265Y228984D02*
X621280D01*
G01X626005Y222684D02*
X624233D01*
G01X626005Y223078D02*
Y222684D01*
G01X627973Y223078D02*
X626005D01*
G01X627973Y222684D02*
Y223078D01*
G01X629745Y222684D02*
X627973D01*
G01X626005Y228984D02*
X624233D01*
G01X629745D02*
X627973D01*
G01X632698Y222684D02*
X631713D01*
G01X632698Y228984D02*
Y222684D01*
G01X631713Y228984D02*
X632698D01*
G01X621700Y260288D02*
Y262808D01*
G01X626706Y260288D02*
X621700D01*
G01X626706Y262808D02*
Y260288D01*
G01X621700Y262808D02*
X626706D01*
G01X621700Y305693D02*
Y257307D01*
G01Y270188D02*
Y272708D01*
G01X626706Y270188D02*
X621700D01*
G01X626706Y272708D02*
Y270188D01*
G01X621700Y272708D02*
X626706D01*
G01X621700Y280188D02*
Y282708D01*
G01X626706Y280188D02*
X621700D01*
G01X626706Y282708D02*
Y280188D01*
G01X621700Y282708D02*
X626706D01*
G01X621700Y290188D02*
Y292708D01*
G01X626706Y290188D02*
X621700D01*
G01X626706Y292708D02*
Y290188D01*
G01X621700Y292708D02*
X626706D01*
G01X621700Y300188D02*
Y302708D01*
G01X626706Y300188D02*
X621700D01*
G01X626706Y302708D02*
Y300188D01*
G01X621700Y302708D02*
X626706D01*
G01X651839Y417835D02*
G02I-11800J0D01*
G01X642000Y95300D02*
Y97700D01*
G01X638000Y95300D02*
X642000D01*
G01X638000Y97700D02*
Y95300D01*
G01X642000Y97700D02*
X638000D01*
G01X642000Y100800D02*
Y103200D01*
G01X638000Y100800D02*
X642000D01*
G01X638000Y103200D02*
Y100800D01*
G01X642000Y103200D02*
X638000D01*
G01X642000Y106800D02*
Y109200D01*
G01X638000Y106800D02*
X642000D01*
G01X638000Y109200D02*
Y106800D01*
G01X642000Y109200D02*
X638000D01*
G01X642000Y112300D02*
Y114700D01*
G01X638000Y112300D02*
X642000D01*
G01X638000Y114700D02*
Y112300D01*
G01X642000Y114700D02*
X638000D01*
G01X660637Y195867D02*
X639771D01*
G01D02*
Y226181D01*
G01D02*
X660637D01*
G01X660297Y183559D02*
Y120567D01*
G01X660637Y226181D02*
Y195867D01*
G01X660787Y378897D02*
Y323071D01*
G01X2130Y54928D02*
X2897D01*
Y53998D01*
X2667Y53688D01*
X2398Y53481D01*
X2015Y53378D01*
X1632Y53481D01*
X1363Y53688D01*
X1133Y53998D01*
X980Y54360D01*
X903Y54773D01*
Y55135D01*
X980Y55445D01*
X1133Y55806D01*
X1363Y56116D01*
X1593Y56323D01*
X1900Y56478D01*
X2168D01*
X2475Y56375D01*
X2705Y56168D01*
G01X4195Y53378D02*
Y56478D01*
G01X5805D02*
Y53378D01*
G01Y54928D02*
X4195D01*
G01X7257Y53998D02*
X7487Y53636D01*
X7793Y53430D01*
X8138Y53378D01*
X8445Y53430D01*
X8752Y53688D01*
X8943Y53998D01*
X8982Y54308D01*
X8905Y54670D01*
X8637Y54928D01*
X8368Y55031D01*
X8023D01*
G01X8368D02*
X8598Y55186D01*
X8790Y55445D01*
X8867Y55755D01*
X8790Y56065D01*
X8598Y56323D01*
X8253Y56478D01*
X7908Y56426D01*
X7563Y56220D01*
G01X7550Y92007D02*
X4450D01*
Y92773D01*
X4605Y93080D01*
X4812Y93310D01*
X5122Y93502D01*
X5483Y93655D01*
X6000Y93693D01*
X6517Y93655D01*
X6878Y93502D01*
X7188Y93310D01*
X7395Y93080D01*
X7550Y92773D01*
Y92007D01*
G01X7137Y95145D02*
X7395Y95452D01*
X7550Y95797D01*
Y96103D01*
X7395Y96410D01*
X7137Y96640D01*
X6775Y96755D01*
X6413Y96678D01*
X6103Y96487D01*
X5897Y96142D01*
X5793Y95682D01*
X5587Y95413D01*
X5225Y95298D01*
X4863Y95375D01*
X4605Y95567D01*
X4450Y95835D01*
Y96103D01*
X4553Y96372D01*
X4812Y96602D01*
G01X7550Y99050D02*
X4450D01*
X5070Y98590D01*
G01X7550D02*
Y99510D01*
G01X7085Y101307D02*
X7343Y101537D01*
X7498Y101805D01*
X7550Y102150D01*
X7447Y102495D01*
X7240Y102763D01*
X6878Y102955D01*
X6465Y102993D01*
X6052Y102917D01*
X5793Y102725D01*
X5587Y102457D01*
X5535Y102188D01*
X5587Y101920D01*
X5793Y101575D01*
X4450Y101690D01*
Y102725D01*
G01X4130Y87500D02*
X4897D01*
Y86570D01*
X4667Y86260D01*
X4398Y86053D01*
X4015Y85950D01*
X3632Y86053D01*
X3363Y86260D01*
X3133Y86570D01*
X2980Y86932D01*
X2903Y87345D01*
Y87707D01*
X2980Y88017D01*
X3133Y88378D01*
X3363Y88688D01*
X3593Y88895D01*
X3900Y89050D01*
X4168D01*
X4475Y88947D01*
X4705Y88740D01*
G01X6195Y85950D02*
Y89050D01*
G01X7805D02*
Y85950D01*
G01Y87500D02*
X6195D01*
G01X10100Y85950D02*
Y89050D01*
X9640Y88430D01*
G01Y85950D02*
X10560D01*
G01X2130Y111959D02*
X2897D01*
Y111029D01*
X2667Y110719D01*
X2398Y110512D01*
X2015Y110409D01*
X1632Y110512D01*
X1363Y110719D01*
X1133Y111029D01*
X980Y111391D01*
X903Y111804D01*
Y112166D01*
X980Y112476D01*
X1133Y112837D01*
X1363Y113147D01*
X1593Y113354D01*
X1900Y113509D01*
X2168D01*
X2475Y113406D01*
X2705Y113199D01*
G01X4195Y110409D02*
Y113509D01*
G01X5805D02*
Y110409D01*
G01Y111959D02*
X4195D01*
G01X7257Y111029D02*
X7487Y110667D01*
X7793Y110461D01*
X8138Y110409D01*
X8445Y110461D01*
X8752Y110719D01*
X8943Y111029D01*
X8982Y111339D01*
X8905Y111701D01*
X8637Y111959D01*
X8368Y112062D01*
X8023D01*
G01X8368D02*
X8598Y112217D01*
X8790Y112476D01*
X8867Y112786D01*
X8790Y113096D01*
X8598Y113354D01*
X8253Y113509D01*
X7908Y113457D01*
X7563Y113251D01*
G01X11000Y145950D02*
Y149050D01*
X10540Y148430D01*
G01Y145950D02*
X11460D01*
G01X2630Y144500D02*
X3397D01*
Y143570D01*
X3167Y143260D01*
X2898Y143053D01*
X2515Y142950D01*
X2132Y143053D01*
X1863Y143260D01*
X1633Y143570D01*
X1480Y143932D01*
X1403Y144345D01*
Y144707D01*
X1480Y145017D01*
X1633Y145378D01*
X1863Y145688D01*
X2093Y145895D01*
X2400Y146050D01*
X2668D01*
X2975Y145947D01*
X3205Y145740D01*
G01X4695Y142950D02*
Y146050D01*
G01X6305D02*
Y142950D01*
G01Y144500D02*
X4695D01*
G01X8600Y142950D02*
Y146050D01*
X8140Y145430D01*
G01Y142950D02*
X9060D01*
G01X10960Y160122D02*
Y163222D01*
X9542Y161000D01*
X11458D01*
G01X9657Y156070D02*
X9887Y155708D01*
X10193Y155502D01*
X10538Y155450D01*
X10845Y155502D01*
X11152Y155760D01*
X11343Y156070D01*
X11382Y156380D01*
X11305Y156742D01*
X11037Y157000D01*
X10768Y157103D01*
X10423D01*
G01X10768D02*
X10998Y157258D01*
X11190Y157517D01*
X11267Y157827D01*
X11190Y158137D01*
X10998Y158395D01*
X10653Y158550D01*
X10308Y158498D01*
X9963Y158292D01*
G01X10272Y153033D02*
X10502Y153343D01*
X10770Y153498D01*
X11077Y153550D01*
X11460Y153447D01*
X11728Y153188D01*
X11805Y152878D01*
X11767Y152568D01*
X11613Y152310D01*
X10847Y151793D01*
X10502Y151432D01*
X10272Y150915D01*
X10195Y150450D01*
X11805D01*
G01X7550Y150007D02*
X4450D01*
Y150773D01*
X4605Y151080D01*
X4812Y151310D01*
X5122Y151502D01*
X5483Y151655D01*
X6000Y151693D01*
X6517Y151655D01*
X6878Y151502D01*
X7188Y151310D01*
X7395Y151080D01*
X7550Y150773D01*
Y150007D01*
G01X7137Y153145D02*
X7395Y153452D01*
X7550Y153797D01*
Y154103D01*
X7395Y154410D01*
X7137Y154640D01*
X6775Y154755D01*
X6413Y154678D01*
X6103Y154487D01*
X5897Y154142D01*
X5793Y153682D01*
X5587Y153413D01*
X5225Y153298D01*
X4863Y153375D01*
X4605Y153567D01*
X4450Y153835D01*
Y154103D01*
X4553Y154372D01*
X4812Y154602D01*
G01X7550Y157050D02*
X4450D01*
X5070Y156590D01*
G01X7550D02*
Y157510D01*
G01Y160610D02*
X4450D01*
X6672Y159192D01*
Y161108D01*
G01X3130Y168991D02*
X3897D01*
Y168061D01*
X3667Y167751D01*
X3398Y167544D01*
X3015Y167441D01*
X2632Y167544D01*
X2363Y167751D01*
X2133Y168061D01*
X1980Y168423D01*
X1903Y168836D01*
Y169198D01*
X1980Y169508D01*
X2133Y169869D01*
X2363Y170179D01*
X2593Y170386D01*
X2900Y170541D01*
X3168D01*
X3475Y170438D01*
X3705Y170231D01*
G01X5195Y167441D02*
Y170541D01*
G01X6805D02*
Y167441D01*
G01Y168991D02*
X5195D01*
G01X8257Y168061D02*
X8487Y167699D01*
X8793Y167493D01*
X9138Y167441D01*
X9445Y167493D01*
X9752Y167751D01*
X9943Y168061D01*
X9982Y168371D01*
X9905Y168733D01*
X9637Y168991D01*
X9368Y169094D01*
X9023D01*
G01X9368D02*
X9598Y169249D01*
X9790Y169508D01*
X9867Y169818D01*
X9790Y170128D01*
X9598Y170386D01*
X9253Y170541D01*
X8908Y170489D01*
X8563Y170283D01*
G01X10500Y205450D02*
Y208550D01*
X10040Y207930D01*
G01Y205450D02*
X10960D01*
G01X9772Y212237D02*
X10002Y212547D01*
X10270Y212702D01*
X10577Y212754D01*
X10960Y212651D01*
X11228Y212392D01*
X11305Y212082D01*
X11267Y211772D01*
X11113Y211514D01*
X10347Y210997D01*
X10002Y210636D01*
X9772Y210119D01*
X9695Y209654D01*
X11305D01*
G01X9657Y214274D02*
X9887Y213912D01*
X10193Y213706D01*
X10538Y213654D01*
X10845Y213706D01*
X11152Y213964D01*
X11343Y214274D01*
X11382Y214584D01*
X11305Y214946D01*
X11037Y215204D01*
X10768Y215307D01*
X10423D01*
G01X10768D02*
X10998Y215462D01*
X11190Y215721D01*
X11267Y216031D01*
X11190Y216341D01*
X10998Y216599D01*
X10653Y216754D01*
X10308Y216702D01*
X9963Y216496D01*
G01X7550Y206507D02*
X4450D01*
Y207273D01*
X4605Y207580D01*
X4812Y207810D01*
X5122Y208002D01*
X5483Y208155D01*
X6000Y208193D01*
X6517Y208155D01*
X6878Y208002D01*
X7188Y207810D01*
X7395Y207580D01*
X7550Y207273D01*
Y206507D01*
G01X7137Y209645D02*
X7395Y209952D01*
X7550Y210297D01*
Y210603D01*
X7395Y210910D01*
X7137Y211140D01*
X6775Y211255D01*
X6413Y211178D01*
X6103Y210987D01*
X5897Y210642D01*
X5793Y210182D01*
X5587Y209913D01*
X5225Y209798D01*
X4863Y209875D01*
X4605Y210067D01*
X4450Y210335D01*
Y210603D01*
X4553Y210872D01*
X4812Y211102D01*
G01X7550Y213550D02*
X4450D01*
X5070Y213090D01*
G01X7550D02*
Y214010D01*
G01Y216573D02*
X6878Y216650D01*
X6310Y216765D01*
X5793Y216918D01*
X5225Y217110D01*
X4450Y217417D01*
Y215883D01*
G01X3130Y202500D02*
X3897D01*
Y201570D01*
X3667Y201260D01*
X3398Y201053D01*
X3015Y200950D01*
X2632Y201053D01*
X2363Y201260D01*
X2133Y201570D01*
X1980Y201932D01*
X1903Y202345D01*
Y202707D01*
X1980Y203017D01*
X2133Y203378D01*
X2363Y203688D01*
X2593Y203895D01*
X2900Y204050D01*
X3168D01*
X3475Y203947D01*
X3705Y203740D01*
G01X5195Y200950D02*
Y204050D01*
G01X6805D02*
Y200950D01*
G01Y202500D02*
X5195D01*
G01X9100Y200950D02*
Y204050D01*
X8640Y203430D01*
G01Y200950D02*
X9560D01*
G01X10960Y217654D02*
Y220754D01*
X9542Y218532D01*
X11458D01*
G01X3630Y226023D02*
X4397D01*
Y225093D01*
X4167Y224783D01*
X3898Y224576D01*
X3515Y224473D01*
X3132Y224576D01*
X2863Y224783D01*
X2633Y225093D01*
X2480Y225455D01*
X2403Y225868D01*
Y226230D01*
X2480Y226540D01*
X2633Y226901D01*
X2863Y227211D01*
X3093Y227418D01*
X3400Y227573D01*
X3668D01*
X3975Y227470D01*
X4205Y227263D01*
G01X5695Y224473D02*
Y227573D01*
G01X7305D02*
Y224473D01*
G01Y226023D02*
X5695D01*
G01X8757Y225093D02*
X8987Y224731D01*
X9293Y224525D01*
X9638Y224473D01*
X9945Y224525D01*
X10252Y224783D01*
X10443Y225093D01*
X10482Y225403D01*
X10405Y225765D01*
X10137Y226023D01*
X9868Y226126D01*
X9523D01*
G01X9868D02*
X10098Y226281D01*
X10290Y226540D01*
X10367Y226850D01*
X10290Y227160D01*
X10098Y227418D01*
X9753Y227573D01*
X9408Y227521D01*
X9063Y227315D01*
G01X11000Y260950D02*
Y264050D01*
X10540Y263430D01*
G01Y260950D02*
X11460D01*
G01X9772Y267768D02*
X10002Y268078D01*
X10270Y268233D01*
X10577Y268285D01*
X10960Y268182D01*
X11228Y267923D01*
X11305Y267613D01*
X11267Y267303D01*
X11113Y267045D01*
X10347Y266528D01*
X10002Y266167D01*
X9772Y265650D01*
X9695Y265185D01*
X11305D01*
G01X7550Y264507D02*
X4450D01*
Y265273D01*
X4605Y265580D01*
X4812Y265810D01*
X5122Y266002D01*
X5483Y266155D01*
X6000Y266193D01*
X6517Y266155D01*
X6878Y266002D01*
X7188Y265810D01*
X7395Y265580D01*
X7550Y265273D01*
Y264507D01*
G01X7137Y267645D02*
X7395Y267952D01*
X7550Y268297D01*
Y268603D01*
X7395Y268910D01*
X7137Y269140D01*
X6775Y269255D01*
X6413Y269178D01*
X6103Y268987D01*
X5897Y268642D01*
X5793Y268182D01*
X5587Y267913D01*
X5225Y267798D01*
X4863Y267875D01*
X4605Y268067D01*
X4450Y268335D01*
Y268603D01*
X4553Y268872D01*
X4812Y269102D01*
G01X7550Y271550D02*
X4450D01*
X5070Y271090D01*
G01X7550D02*
Y272010D01*
G01X6258Y273922D02*
X5897Y274190D01*
X5690Y274420D01*
X5587Y274727D01*
X5690Y274995D01*
X5897Y275187D01*
X6207Y275340D01*
X6568Y275378D01*
X6878Y275340D01*
X7188Y275187D01*
X7447Y274957D01*
X7550Y274688D01*
X7447Y274382D01*
X7137Y274113D01*
X6672Y273960D01*
X6155Y273922D01*
X5483Y273998D01*
X5122Y274113D01*
X4760Y274305D01*
X4502Y274573D01*
X4450Y274842D01*
X4553Y275110D01*
X4812Y275302D01*
G01X3130Y259000D02*
X3897D01*
Y258070D01*
X3667Y257760D01*
X3398Y257553D01*
X3015Y257450D01*
X2632Y257553D01*
X2363Y257760D01*
X2133Y258070D01*
X1980Y258432D01*
X1903Y258845D01*
Y259207D01*
X1980Y259517D01*
X2133Y259878D01*
X2363Y260188D01*
X2593Y260395D01*
X2900Y260550D01*
X3168D01*
X3475Y260447D01*
X3705Y260240D01*
G01X5195Y257450D02*
Y260550D01*
G01X6805D02*
Y257450D01*
G01Y259000D02*
X5195D01*
G01X9100Y257450D02*
Y260550D01*
X8640Y259930D01*
G01Y257450D02*
X9560D01*
G01X9657Y270305D02*
X9887Y269943D01*
X10193Y269737D01*
X10538Y269685D01*
X10845Y269737D01*
X11152Y269995D01*
X11343Y270305D01*
X11382Y270615D01*
X11305Y270977D01*
X11037Y271235D01*
X10768Y271338D01*
X10423D01*
G01X10768D02*
X10998Y271493D01*
X11190Y271752D01*
X11267Y272062D01*
X11190Y272372D01*
X10998Y272630D01*
X10653Y272785D01*
X10308Y272733D01*
X9963Y272527D01*
G01X10960Y273685D02*
Y276785D01*
X9542Y274563D01*
X11458D01*
G01X8784Y315843D02*
X5684D01*
X6304Y315383D01*
G01X8784D02*
Y316303D01*
G01X7050Y319507D02*
X3950D01*
Y320273D01*
X4105Y320580D01*
X4312Y320810D01*
X4622Y321002D01*
X4983Y321155D01*
X5500Y321193D01*
X6017Y321155D01*
X6378Y321002D01*
X6688Y320810D01*
X6895Y320580D01*
X7050Y320273D01*
Y319507D01*
G01X6637Y322645D02*
X6895Y322952D01*
X7050Y323297D01*
Y323603D01*
X6895Y323910D01*
X6637Y324140D01*
X6275Y324255D01*
X5913Y324178D01*
X5603Y323987D01*
X5397Y323642D01*
X5293Y323182D01*
X5087Y322913D01*
X4725Y322798D01*
X4363Y322875D01*
X4105Y323067D01*
X3950Y323335D01*
Y323603D01*
X4053Y323872D01*
X4312Y324102D01*
G01X7050Y326550D02*
X3950D01*
X4570Y326090D01*
G01X7050D02*
Y327010D01*
G01Y329650D02*
X6998Y329918D01*
X6843Y330225D01*
X6585Y330417D01*
X6223Y330493D01*
X5862Y330417D01*
X5552Y330187D01*
X5397Y329842D01*
Y329458D01*
X5293Y329228D01*
X5035Y329037D01*
X4673Y328960D01*
X4312Y329075D01*
X4053Y329343D01*
X3950Y329650D01*
X4053Y329957D01*
X4312Y330225D01*
X4673Y330340D01*
X5035Y330263D01*
X5293Y330072D01*
X5397Y329842D01*
Y329458D01*
X5552Y329113D01*
X5862Y328883D01*
X6223Y328807D01*
X6585Y328883D01*
X6843Y329075D01*
X6998Y329382D01*
X7050Y329650D01*
G01X11050Y332460D02*
X7950D01*
X10172Y331042D01*
Y332958D01*
G01X9862Y322396D02*
X9552Y322626D01*
X9397Y322894D01*
X9345Y323201D01*
X9448Y323584D01*
X9707Y323852D01*
X10017Y323929D01*
X10327Y323891D01*
X10585Y323737D01*
X11102Y322971D01*
X11463Y322626D01*
X11980Y322396D01*
X12445Y322319D01*
Y323929D01*
G01X11733Y326304D02*
X12095Y326534D01*
X12301Y326840D01*
X12353Y327185D01*
X12301Y327492D01*
X12043Y327799D01*
X11733Y327990D01*
X11423Y328029D01*
X11061Y327952D01*
X10803Y327684D01*
X10700Y327415D01*
Y327070D01*
G01Y327415D02*
X10545Y327645D01*
X10286Y327837D01*
X9976Y327914D01*
X9666Y327837D01*
X9408Y327645D01*
X9253Y327300D01*
X9305Y326955D01*
X9511Y326610D01*
G01X23881Y35261D02*
Y38361D01*
X24878Y35778D01*
X25875Y38361D01*
Y35261D01*
G01X28745D02*
X27211D01*
Y38361D01*
X28745D01*
G01X28131Y36863D02*
X27211D01*
G01X31078Y35261D02*
Y38361D01*
X30618Y37741D01*
G01Y35261D02*
X31538D01*
G01X34178Y38361D02*
X33871Y38258D01*
X33641Y37999D01*
X33488Y37689D01*
X33373Y37276D01*
X33335Y36811D01*
X33373Y36346D01*
X33488Y35933D01*
X33641Y35623D01*
X33871Y35364D01*
X34178Y35261D01*
X34485Y35364D01*
X34715Y35623D01*
X34868Y35933D01*
X34983Y36346D01*
X35021Y36811D01*
X34983Y37276D01*
X34868Y37689D01*
X34715Y37999D01*
X34485Y38258D01*
X34178Y38361D01*
G01X23169Y53110D02*
X23936D01*
Y52180D01*
X23706Y51870D01*
X23437Y51663D01*
X23054Y51560D01*
X22671Y51663D01*
X22402Y51870D01*
X22172Y52180D01*
X22019Y52542D01*
X21942Y52955D01*
Y53317D01*
X22019Y53627D01*
X22172Y53988D01*
X22402Y54298D01*
X22632Y54505D01*
X22939Y54660D01*
X23207D01*
X23514Y54557D01*
X23744Y54350D01*
G01X25234Y51560D02*
Y54660D01*
G01X26844D02*
Y51560D01*
G01Y53110D02*
X25234D01*
G01X29599Y51560D02*
Y54660D01*
X28181Y52438D01*
X30097D01*
G01X13722Y70330D02*
X13914Y70020D01*
X14144Y69813D01*
X14412Y69710D01*
X14719Y69813D01*
X14949Y70020D01*
X15179Y70330D01*
X15256Y70743D01*
Y72810D01*
G01X16861Y72293D02*
X17091Y72603D01*
X17359Y72758D01*
X17666Y72810D01*
X18049Y72707D01*
X18317Y72448D01*
X18394Y72138D01*
X18356Y71828D01*
X18202Y71570D01*
X17436Y71053D01*
X17091Y70692D01*
X16861Y70175D01*
X16784Y69710D01*
X18394D01*
G01X26772Y94033D02*
X27002Y94343D01*
X27270Y94498D01*
X27577Y94550D01*
X27960Y94447D01*
X28228Y94188D01*
X28305Y93878D01*
X28267Y93568D01*
X28113Y93310D01*
X27347Y92793D01*
X27002Y92432D01*
X26772Y91915D01*
X26695Y91450D01*
X28305D01*
G01X12000Y89950D02*
Y93050D01*
X11540Y92430D01*
G01Y89950D02*
X12460D01*
G01X10772Y96673D02*
X11002Y96983D01*
X11270Y97138D01*
X11577Y97190D01*
X11960Y97087D01*
X12228Y96828D01*
X12305Y96518D01*
X12267Y96208D01*
X12113Y95950D01*
X11347Y95433D01*
X11002Y95072D01*
X10772Y94555D01*
X10695Y94090D01*
X12305D01*
G01X23130Y87500D02*
X23897D01*
Y86570D01*
X23667Y86260D01*
X23398Y86053D01*
X23015Y85950D01*
X22632Y86053D01*
X22363Y86260D01*
X22133Y86570D01*
X21980Y86932D01*
X21903Y87345D01*
Y87707D01*
X21980Y88017D01*
X22133Y88378D01*
X22363Y88688D01*
X22593Y88895D01*
X22900Y89050D01*
X23168D01*
X23475Y88947D01*
X23705Y88740D01*
G01X25195Y85950D02*
Y89050D01*
G01X26805D02*
Y85950D01*
G01Y87500D02*
X25195D01*
G01X28372Y88533D02*
X28602Y88843D01*
X28870Y88998D01*
X29177Y89050D01*
X29560Y88947D01*
X29828Y88688D01*
X29905Y88378D01*
X29867Y88068D01*
X29713Y87810D01*
X28947Y87293D01*
X28602Y86932D01*
X28372Y86415D01*
X28295Y85950D01*
X29905D01*
G01X22743Y101792D02*
X22513Y101947D01*
X22245Y102050D01*
X21938D01*
X21593Y101895D01*
X21325Y101637D01*
X21133Y101327D01*
X20980Y100810D01*
X20942Y100345D01*
X21018Y99880D01*
X21133Y99570D01*
X21363Y99260D01*
X21632Y99053D01*
X21900Y98950D01*
X22168D01*
X22437Y99053D01*
X22667Y99208D01*
X22858Y99415D01*
G01X24233Y98950D02*
Y102050D01*
X25192D01*
X25498Y101895D01*
X25690Y101688D01*
X25767Y101275D01*
X25690Y100862D01*
X25460Y100603D01*
X25192Y100448D01*
X24233D01*
G01X25192D02*
X25767Y98950D01*
G01X27257Y99415D02*
X27487Y99157D01*
X27755Y99002D01*
X28100Y98950D01*
X28445Y99053D01*
X28713Y99260D01*
X28905Y99622D01*
X28943Y100035D01*
X28867Y100448D01*
X28675Y100707D01*
X28407Y100913D01*
X28138Y100965D01*
X27870Y100913D01*
X27525Y100707D01*
X27640Y102050D01*
X28675D01*
G01X20096Y105807D02*
Y108907D01*
X18678Y106685D01*
X20594D01*
G01X26793Y106427D02*
X27023Y106065D01*
X27329Y105859D01*
X27674Y105807D01*
X27981Y105859D01*
X28288Y106117D01*
X28479Y106427D01*
X28518Y106737D01*
X28441Y107099D01*
X28173Y107357D01*
X27904Y107460D01*
X27559D01*
G01X27904D02*
X28134Y107615D01*
X28326Y107874D01*
X28403Y108184D01*
X28326Y108494D01*
X28134Y108752D01*
X27789Y108907D01*
X27444Y108855D01*
X27099Y108649D01*
G01X11960Y103090D02*
Y106190D01*
X10542Y103968D01*
X12458D01*
G01X10657Y99210D02*
X10887Y98848D01*
X11193Y98642D01*
X11538Y98590D01*
X11845Y98642D01*
X12152Y98900D01*
X12343Y99210D01*
X12382Y99520D01*
X12305Y99882D01*
X12037Y100140D01*
X11768Y100243D01*
X11423D01*
G01X11768D02*
X11998Y100398D01*
X12190Y100657D01*
X12267Y100967D01*
X12190Y101277D01*
X11998Y101535D01*
X11653Y101690D01*
X11308Y101638D01*
X10963Y101432D01*
G01X23630Y112000D02*
X24397D01*
Y111070D01*
X24167Y110760D01*
X23898Y110553D01*
X23515Y110450D01*
X23132Y110553D01*
X22863Y110760D01*
X22633Y111070D01*
X22480Y111432D01*
X22403Y111845D01*
Y112207D01*
X22480Y112517D01*
X22633Y112878D01*
X22863Y113188D01*
X23093Y113395D01*
X23400Y113550D01*
X23668D01*
X23975Y113447D01*
X24205Y113240D01*
G01X25695Y110450D02*
Y113550D01*
G01X27305D02*
Y110450D01*
G01Y112000D02*
X25695D01*
G01X30060Y110450D02*
Y113550D01*
X28642Y111328D01*
X30558D01*
G01X13722Y127416D02*
X13914Y127106D01*
X14144Y126899D01*
X14412Y126796D01*
X14719Y126899D01*
X14949Y127106D01*
X15179Y127416D01*
X15256Y127829D01*
Y129896D01*
G01X17589Y126796D02*
Y129896D01*
X17129Y129276D01*
G01Y126796D02*
X18049D01*
G01X23169Y146496D02*
X23936D01*
Y145566D01*
X23706Y145256D01*
X23437Y145049D01*
X23054Y144946D01*
X22671Y145049D01*
X22402Y145256D01*
X22172Y145566D01*
X22019Y145928D01*
X21942Y146341D01*
Y146703D01*
X22019Y147013D01*
X22172Y147374D01*
X22402Y147684D01*
X22632Y147891D01*
X22939Y148046D01*
X23207D01*
X23514Y147943D01*
X23744Y147736D01*
G01X25234Y144946D02*
Y148046D01*
G01X26844D02*
Y144946D01*
G01Y146496D02*
X25234D01*
G01X28411Y147529D02*
X28641Y147839D01*
X28909Y147994D01*
X29216Y148046D01*
X29599Y147943D01*
X29867Y147684D01*
X29944Y147374D01*
X29906Y147064D01*
X29752Y146806D01*
X28986Y146289D01*
X28641Y145928D01*
X28411Y145411D01*
X28334Y144946D01*
X29944D01*
G01X29650Y149381D02*
X26550D01*
Y150340D01*
X26705Y150646D01*
X26912Y150838D01*
X27325Y150915D01*
X27738Y150838D01*
X27997Y150608D01*
X28152Y150340D01*
Y149381D01*
G01Y150340D02*
X29650Y150915D01*
G01X27067Y152520D02*
X26757Y152750D01*
X26602Y153018D01*
X26550Y153325D01*
X26653Y153708D01*
X26912Y153976D01*
X27222Y154053D01*
X27532Y154015D01*
X27790Y153861D01*
X28307Y153095D01*
X28668Y152750D01*
X29185Y152520D01*
X29650Y152443D01*
Y154053D01*
G01Y156271D02*
X28978Y156348D01*
X28410Y156463D01*
X27893Y156616D01*
X27325Y156808D01*
X26550Y157115D01*
Y155581D01*
G01X27067Y158720D02*
X26757Y158950D01*
X26602Y159218D01*
X26550Y159525D01*
X26653Y159908D01*
X26912Y160176D01*
X27222Y160253D01*
X27532Y160215D01*
X27790Y160061D01*
X28307Y159295D01*
X28668Y158950D01*
X29185Y158720D01*
X29650Y158643D01*
Y160253D01*
G01X25150Y149381D02*
X22050D01*
Y150340D01*
X22205Y150646D01*
X22412Y150838D01*
X22825Y150915D01*
X23238Y150838D01*
X23497Y150608D01*
X23652Y150340D01*
Y149381D01*
G01Y150340D02*
X25150Y150915D01*
G01Y153248D02*
X22050D01*
X22670Y152788D01*
G01X25150D02*
Y153708D01*
G01X22567Y155620D02*
X22257Y155850D01*
X22102Y156118D01*
X22050Y156425D01*
X22153Y156808D01*
X22412Y157076D01*
X22722Y157153D01*
X23032Y157115D01*
X23290Y156961D01*
X23807Y156195D01*
X24168Y155850D01*
X24685Y155620D01*
X25150Y155543D01*
Y157153D01*
G01Y159908D02*
X22050D01*
X24272Y158490D01*
Y160406D01*
G01X20650Y149381D02*
X17550D01*
Y150340D01*
X17705Y150646D01*
X17912Y150838D01*
X18325Y150915D01*
X18738Y150838D01*
X18997Y150608D01*
X19152Y150340D01*
Y149381D01*
G01Y150340D02*
X20650Y150915D01*
G01X20030Y152405D02*
X20392Y152635D01*
X20598Y152941D01*
X20650Y153286D01*
X20598Y153593D01*
X20340Y153900D01*
X20030Y154091D01*
X19720Y154130D01*
X19358Y154053D01*
X19100Y153785D01*
X18997Y153516D01*
Y153171D01*
G01Y153516D02*
X18842Y153746D01*
X18583Y153938D01*
X18273Y154015D01*
X17963Y153938D01*
X17705Y153746D01*
X17550Y153401D01*
X17602Y153056D01*
X17808Y152711D01*
G01X20650Y156348D02*
X20598Y156616D01*
X20443Y156923D01*
X20185Y157115D01*
X19823Y157191D01*
X19462Y157115D01*
X19152Y156885D01*
X18997Y156540D01*
Y156156D01*
X18893Y155926D01*
X18635Y155735D01*
X18273Y155658D01*
X17912Y155773D01*
X17653Y156041D01*
X17550Y156348D01*
X17653Y156655D01*
X17912Y156923D01*
X18273Y157038D01*
X18635Y156961D01*
X18893Y156770D01*
X18997Y156540D01*
Y156156D01*
X19152Y155811D01*
X19462Y155581D01*
X19823Y155505D01*
X20185Y155581D01*
X20443Y155773D01*
X20598Y156080D01*
X20650Y156348D01*
G01X20185Y158605D02*
X20443Y158835D01*
X20598Y159103D01*
X20650Y159448D01*
X20547Y159793D01*
X20340Y160061D01*
X19978Y160253D01*
X19565Y160291D01*
X19152Y160215D01*
X18893Y160023D01*
X18687Y159755D01*
X18635Y159486D01*
X18687Y159218D01*
X18893Y158873D01*
X17550Y158988D01*
Y160023D01*
G01X23169Y167283D02*
X23936D01*
Y166353D01*
X23706Y166043D01*
X23437Y165836D01*
X23054Y165733D01*
X22671Y165836D01*
X22402Y166043D01*
X22172Y166353D01*
X22019Y166715D01*
X21942Y167128D01*
Y167490D01*
X22019Y167800D01*
X22172Y168161D01*
X22402Y168471D01*
X22632Y168678D01*
X22939Y168833D01*
X23207D01*
X23514Y168730D01*
X23744Y168523D01*
G01X25234Y165733D02*
Y168833D01*
G01X26844D02*
Y165733D01*
G01Y167283D02*
X25234D01*
G01X29599Y165733D02*
Y168833D01*
X28181Y166611D01*
X30097D01*
G01X13722Y184503D02*
X13914Y184193D01*
X14144Y183986D01*
X14412Y183883D01*
X14719Y183986D01*
X14949Y184193D01*
X15179Y184503D01*
X15256Y184916D01*
Y186983D01*
G01X18049Y183883D02*
Y186983D01*
X16631Y184761D01*
X18547D01*
G01X27246Y207757D02*
X27476Y208067D01*
X27744Y208222D01*
X28051Y208274D01*
X28434Y208171D01*
X28702Y207912D01*
X28779Y207602D01*
X28741Y207292D01*
X28587Y207034D01*
X27821Y206517D01*
X27476Y206156D01*
X27246Y205639D01*
X27169Y205174D01*
X28779D01*
G01X25243Y214792D02*
X25013Y214947D01*
X24745Y215050D01*
X24438D01*
X24093Y214895D01*
X23825Y214637D01*
X23633Y214327D01*
X23480Y213810D01*
X23442Y213345D01*
X23518Y212880D01*
X23633Y212570D01*
X23863Y212260D01*
X24132Y212053D01*
X24400Y211950D01*
X24668D01*
X24937Y212053D01*
X25167Y212208D01*
X25358Y212415D01*
G01X26733Y211950D02*
Y215050D01*
X27692D01*
X27998Y214895D01*
X28190Y214688D01*
X28267Y214275D01*
X28190Y213862D01*
X27960Y213603D01*
X27692Y213448D01*
X26733D01*
G01X27692D02*
X28267Y211950D01*
G01X31060D02*
Y215050D01*
X29642Y212828D01*
X31558D01*
G01X21630Y202000D02*
X22397D01*
Y201070D01*
X22167Y200760D01*
X21898Y200553D01*
X21515Y200450D01*
X21132Y200553D01*
X20863Y200760D01*
X20633Y201070D01*
X20480Y201432D01*
X20403Y201845D01*
Y202207D01*
X20480Y202517D01*
X20633Y202878D01*
X20863Y203188D01*
X21093Y203395D01*
X21400Y203550D01*
X21668D01*
X21975Y203447D01*
X22205Y203240D01*
G01X23695Y200450D02*
Y203550D01*
G01X25305D02*
Y200450D01*
G01Y202000D02*
X23695D01*
G01X26872Y203033D02*
X27102Y203343D01*
X27370Y203498D01*
X27677Y203550D01*
X28060Y203447D01*
X28328Y203188D01*
X28405Y202878D01*
X28367Y202568D01*
X28213Y202310D01*
X27447Y201793D01*
X27102Y201432D01*
X26872Y200915D01*
X26795Y200450D01*
X28405D01*
G01X17934Y219174D02*
Y222274D01*
X16516Y220052D01*
X18432D01*
G01X22630Y226023D02*
X23397D01*
Y225093D01*
X23167Y224783D01*
X22898Y224576D01*
X22515Y224473D01*
X22132Y224576D01*
X21863Y224783D01*
X21633Y225093D01*
X21480Y225455D01*
X21403Y225868D01*
Y226230D01*
X21480Y226540D01*
X21633Y226901D01*
X21863Y227211D01*
X22093Y227418D01*
X22400Y227573D01*
X22668D01*
X22975Y227470D01*
X23205Y227263D01*
G01X24695Y224473D02*
Y227573D01*
G01X26305D02*
Y224473D01*
G01Y226023D02*
X24695D01*
G01X29060Y224473D02*
Y227573D01*
X27642Y225351D01*
X29558D01*
G01X13722Y241590D02*
X13914Y241280D01*
X14144Y241073D01*
X14412Y240970D01*
X14719Y241073D01*
X14949Y241280D01*
X15179Y241590D01*
X15256Y242003D01*
Y244070D01*
G01X16746Y241590D02*
X16976Y241228D01*
X17282Y241022D01*
X17627Y240970D01*
X17934Y241022D01*
X18241Y241280D01*
X18432Y241590D01*
X18471Y241900D01*
X18394Y242262D01*
X18126Y242520D01*
X17857Y242623D01*
X17512D01*
G01X17857D02*
X18087Y242778D01*
X18279Y243037D01*
X18356Y243347D01*
X18279Y243657D01*
X18087Y243915D01*
X17742Y244070D01*
X17397Y244018D01*
X17052Y243812D01*
G01X25750Y263091D02*
X22650D01*
Y264050D01*
X22805Y264356D01*
X23012Y264548D01*
X23425Y264625D01*
X23838Y264548D01*
X24097Y264318D01*
X24252Y264050D01*
Y263091D01*
G01Y264050D02*
X25750Y264625D01*
G01X25130Y266115D02*
X25492Y266345D01*
X25698Y266651D01*
X25750Y266996D01*
X25698Y267303D01*
X25440Y267610D01*
X25130Y267801D01*
X24820Y267840D01*
X24458Y267763D01*
X24200Y267495D01*
X24097Y267226D01*
Y266881D01*
G01Y267226D02*
X23942Y267456D01*
X23683Y267648D01*
X23373Y267725D01*
X23063Y267648D01*
X22805Y267456D01*
X22650Y267111D01*
X22702Y266766D01*
X22908Y266421D01*
G01X25750Y269981D02*
X25078Y270058D01*
X24510Y270173D01*
X23993Y270326D01*
X23425Y270518D01*
X22650Y270825D01*
Y269291D01*
G01X25750Y273618D02*
X22650D01*
X24872Y272200D01*
Y274116D01*
G01X21250Y263091D02*
X18150D01*
Y264050D01*
X18305Y264356D01*
X18512Y264548D01*
X18925Y264625D01*
X19338Y264548D01*
X19597Y264318D01*
X19752Y264050D01*
Y263091D01*
G01Y264050D02*
X21250Y264625D01*
G01X20630Y266115D02*
X20992Y266345D01*
X21198Y266651D01*
X21250Y266996D01*
X21198Y267303D01*
X20940Y267610D01*
X20630Y267801D01*
X20320Y267840D01*
X19958Y267763D01*
X19700Y267495D01*
X19597Y267226D01*
Y266881D01*
G01Y267226D02*
X19442Y267456D01*
X19183Y267648D01*
X18873Y267725D01*
X18563Y267648D01*
X18305Y267456D01*
X18150Y267111D01*
X18202Y266766D01*
X18408Y266421D01*
G01X20888Y269406D02*
X21147Y269675D01*
X21250Y269981D01*
X21147Y270288D01*
X20837Y270556D01*
X20372Y270748D01*
X19907Y270825D01*
X19338D01*
X18873Y270748D01*
X18460Y270556D01*
X18253Y270326D01*
X18150Y270058D01*
X18253Y269751D01*
X18460Y269521D01*
X18770Y269368D01*
X19183Y269291D01*
X19545Y269368D01*
X19907Y269560D01*
X20113Y269790D01*
X20165Y270058D01*
X20062Y270365D01*
X19803Y270595D01*
X19338Y270825D01*
G01X21250Y273158D02*
X18150D01*
X18770Y272698D01*
G01X21250D02*
Y273618D01*
G01X30250Y263091D02*
X27150D01*
Y264050D01*
X27305Y264356D01*
X27512Y264548D01*
X27925Y264625D01*
X28338Y264548D01*
X28597Y264318D01*
X28752Y264050D01*
Y263091D01*
G01Y264050D02*
X30250Y264625D01*
G01X29630Y266115D02*
X29992Y266345D01*
X30198Y266651D01*
X30250Y266996D01*
X30198Y267303D01*
X29940Y267610D01*
X29630Y267801D01*
X29320Y267840D01*
X28958Y267763D01*
X28700Y267495D01*
X28597Y267226D01*
Y266881D01*
G01Y267226D02*
X28442Y267456D01*
X28183Y267648D01*
X27873Y267725D01*
X27563Y267648D01*
X27305Y267456D01*
X27150Y267111D01*
X27202Y266766D01*
X27408Y266421D01*
G01X30250Y269981D02*
X29578Y270058D01*
X29010Y270173D01*
X28493Y270326D01*
X27925Y270518D01*
X27150Y270825D01*
Y269291D01*
G01X28958Y272430D02*
X28597Y272698D01*
X28390Y272928D01*
X28287Y273235D01*
X28390Y273503D01*
X28597Y273695D01*
X28907Y273848D01*
X29268Y273886D01*
X29578Y273848D01*
X29888Y273695D01*
X30147Y273465D01*
X30250Y273196D01*
X30147Y272890D01*
X29837Y272621D01*
X29372Y272468D01*
X28855Y272430D01*
X28183Y272506D01*
X27822Y272621D01*
X27460Y272813D01*
X27202Y273081D01*
X27150Y273350D01*
X27253Y273618D01*
X27512Y273810D01*
G01X23169Y260670D02*
X23936D01*
Y259740D01*
X23706Y259430D01*
X23437Y259223D01*
X23054Y259120D01*
X22671Y259223D01*
X22402Y259430D01*
X22172Y259740D01*
X22019Y260102D01*
X21942Y260515D01*
Y260877D01*
X22019Y261187D01*
X22172Y261548D01*
X22402Y261858D01*
X22632Y262065D01*
X22939Y262220D01*
X23207D01*
X23514Y262117D01*
X23744Y261910D01*
G01X25234Y259120D02*
Y262220D01*
G01X26844D02*
Y259120D01*
G01Y260670D02*
X25234D01*
G01X28411Y261703D02*
X28641Y262013D01*
X28909Y262168D01*
X29216Y262220D01*
X29599Y262117D01*
X29867Y261858D01*
X29944Y261548D01*
X29906Y261238D01*
X29752Y260980D01*
X28986Y260463D01*
X28641Y260102D01*
X28411Y259585D01*
X28334Y259120D01*
X29944D01*
G01X18516Y315583D02*
X15416D01*
Y316542D01*
X15571Y316848D01*
X15778Y317040D01*
X16191Y317117D01*
X16604Y317040D01*
X16863Y316810D01*
X17018Y316542D01*
Y315583D01*
G01Y316542D02*
X18516Y317117D01*
G01X17896Y318607D02*
X18258Y318837D01*
X18464Y319143D01*
X18516Y319488D01*
X18464Y319795D01*
X18206Y320102D01*
X17896Y320293D01*
X17586Y320332D01*
X17224Y320255D01*
X16966Y319987D01*
X16863Y319718D01*
Y319373D01*
G01Y319718D02*
X16708Y319948D01*
X16449Y320140D01*
X16139Y320217D01*
X15829Y320140D01*
X15571Y319948D01*
X15416Y319603D01*
X15468Y319258D01*
X15674Y318913D01*
G01X18154Y321898D02*
X18413Y322167D01*
X18516Y322473D01*
X18413Y322780D01*
X18103Y323048D01*
X17638Y323240D01*
X17173Y323317D01*
X16604D01*
X16139Y323240D01*
X15726Y323048D01*
X15519Y322818D01*
X15416Y322550D01*
X15519Y322243D01*
X15726Y322013D01*
X16036Y321860D01*
X16449Y321783D01*
X16811Y321860D01*
X17173Y322052D01*
X17379Y322282D01*
X17431Y322550D01*
X17328Y322857D01*
X17069Y323087D01*
X16604Y323317D01*
G01X18516Y325573D02*
X17844Y325650D01*
X17276Y325765D01*
X16759Y325918D01*
X16191Y326110D01*
X15416Y326417D01*
Y324883D01*
G01X23516Y315583D02*
X20416D01*
Y316542D01*
X20571Y316848D01*
X20778Y317040D01*
X21191Y317117D01*
X21604Y317040D01*
X21863Y316810D01*
X22018Y316542D01*
Y315583D01*
G01Y316542D02*
X23516Y317117D01*
G01Y319910D02*
X20416D01*
X22638Y318492D01*
Y320408D01*
G01X20933Y321822D02*
X20623Y322052D01*
X20468Y322320D01*
X20416Y322627D01*
X20519Y323010D01*
X20778Y323278D01*
X21088Y323355D01*
X21398Y323317D01*
X21656Y323163D01*
X22173Y322397D01*
X22534Y322052D01*
X23051Y321822D01*
X23516Y321745D01*
Y323355D01*
G01X23051Y324807D02*
X23309Y325037D01*
X23464Y325305D01*
X23516Y325650D01*
X23413Y325995D01*
X23206Y326263D01*
X22844Y326455D01*
X22431Y326493D01*
X22018Y326417D01*
X21759Y326225D01*
X21553Y325957D01*
X21501Y325688D01*
X21553Y325420D01*
X21759Y325075D01*
X20416Y325190D01*
Y326225D01*
G01X28516Y315583D02*
X25416D01*
Y316542D01*
X25571Y316848D01*
X25778Y317040D01*
X26191Y317117D01*
X26604Y317040D01*
X26863Y316810D01*
X27018Y316542D01*
Y315583D01*
G01Y316542D02*
X28516Y317117D01*
G01Y319910D02*
X25416D01*
X27638Y318492D01*
Y320408D01*
G01X25933Y321822D02*
X25623Y322052D01*
X25468Y322320D01*
X25416Y322627D01*
X25519Y323010D01*
X25778Y323278D01*
X26088Y323355D01*
X26398Y323317D01*
X26656Y323163D01*
X27173Y322397D01*
X27534Y322052D01*
X28051Y321822D01*
X28516Y321745D01*
Y323355D01*
G01Y325573D02*
X27844Y325650D01*
X27276Y325765D01*
X26759Y325918D01*
X26191Y326110D01*
X25416Y326417D01*
Y324883D01*
G01X25130Y330500D02*
X25897D01*
Y329570D01*
X25667Y329260D01*
X25398Y329053D01*
X25015Y328950D01*
X24632Y329053D01*
X24363Y329260D01*
X24133Y329570D01*
X23980Y329932D01*
X23903Y330345D01*
Y330707D01*
X23980Y331017D01*
X24133Y331378D01*
X24363Y331688D01*
X24593Y331895D01*
X24900Y332050D01*
X25168D01*
X25475Y331947D01*
X25705Y331740D01*
G01X27195Y328950D02*
Y332050D01*
G01X28805D02*
Y328950D01*
G01Y330500D02*
X27195D01*
G01X31560Y328950D02*
Y332050D01*
X30142Y329828D01*
X32058D01*
G01X16207Y330103D02*
X16360Y330258D01*
X16475Y330517D01*
X16552Y330878D01*
X16475Y331188D01*
X16322Y331395D01*
X16053Y331550D01*
X15018D01*
Y328450D01*
X16283D01*
X16552Y328657D01*
X16705Y328967D01*
X16782Y329328D01*
X16705Y329690D01*
X16475Y330000D01*
X16207Y330103D01*
X15018D01*
G01X19000Y328450D02*
Y331550D01*
X18540Y330930D01*
G01Y328450D02*
X19460D01*
G01X21372Y331033D02*
X21602Y331343D01*
X21870Y331498D01*
X22177Y331550D01*
X22560Y331447D01*
X22828Y331188D01*
X22905Y330878D01*
X22867Y330568D01*
X22713Y330310D01*
X21947Y329793D01*
X21602Y329432D01*
X21372Y328915D01*
X21295Y328450D01*
X22905D01*
G01X13633Y341570D02*
X13825Y341260D01*
X14055Y341053D01*
X14323Y340950D01*
X14630Y341053D01*
X14860Y341260D01*
X15090Y341570D01*
X15167Y341983D01*
Y344050D01*
G01X17500Y340950D02*
Y344050D01*
X17040Y343430D01*
G01Y340950D02*
X17960D01*
G01X19757Y341570D02*
X19987Y341208D01*
X20293Y341002D01*
X20638Y340950D01*
X20945Y341002D01*
X21252Y341260D01*
X21443Y341570D01*
X21482Y341880D01*
X21405Y342242D01*
X21137Y342500D01*
X20868Y342603D01*
X20523D01*
G01X20868D02*
X21098Y342758D01*
X21290Y343017D01*
X21367Y343327D01*
X21290Y343637D01*
X21098Y343895D01*
X20753Y344050D01*
X20408Y343998D01*
X20063Y343792D01*
G01X23130Y352500D02*
X23897D01*
Y351570D01*
X23667Y351260D01*
X23398Y351053D01*
X23015Y350950D01*
X22632Y351053D01*
X22363Y351260D01*
X22133Y351570D01*
X21980Y351932D01*
X21903Y352345D01*
Y352707D01*
X21980Y353017D01*
X22133Y353378D01*
X22363Y353688D01*
X22593Y353895D01*
X22900Y354050D01*
X23168D01*
X23475Y353947D01*
X23705Y353740D01*
G01X25195Y350950D02*
Y354050D01*
G01X26805D02*
Y350950D01*
G01Y352500D02*
X25195D01*
G01X28257Y351570D02*
X28487Y351208D01*
X28793Y351002D01*
X29138Y350950D01*
X29445Y351002D01*
X29752Y351260D01*
X29943Y351570D01*
X29982Y351880D01*
X29905Y352242D01*
X29637Y352500D01*
X29368Y352603D01*
X29023D01*
G01X29368D02*
X29598Y352758D01*
X29790Y353017D01*
X29867Y353327D01*
X29790Y353637D01*
X29598Y353895D01*
X29253Y354050D01*
X28908Y353998D01*
X28563Y353792D01*
G01X20550Y350992D02*
X17450Y351950D01*
X20550Y352908D01*
G01X19465Y352563D02*
Y351337D01*
G01X20550Y355050D02*
X17450D01*
X18070Y354590D01*
G01X20550D02*
Y355510D01*
G01X25431Y371481D02*
Y374581D01*
X26428Y371998D01*
X27425Y374581D01*
Y371481D01*
G01X30295D02*
X28761D01*
Y374581D01*
X30295D01*
G01X29681Y373083D02*
X28761D01*
G01X31976Y371843D02*
X32245Y371584D01*
X32551Y371481D01*
X32858Y371584D01*
X33126Y371894D01*
X33318Y372359D01*
X33395Y372824D01*
Y373393D01*
X33318Y373858D01*
X33126Y374271D01*
X32896Y374478D01*
X32628Y374581D01*
X32321Y374478D01*
X32091Y374271D01*
X31938Y373961D01*
X31861Y373548D01*
X31938Y373186D01*
X32130Y372824D01*
X32360Y372618D01*
X32628Y372566D01*
X32935Y372669D01*
X33165Y372928D01*
X33395Y373393D01*
G01X45334Y61383D02*
X42234D01*
Y62342D01*
X42389Y62648D01*
X42596Y62840D01*
X43009Y62917D01*
X43422Y62840D01*
X43681Y62610D01*
X43836Y62342D01*
Y61383D01*
G01Y62342D02*
X45334Y62917D01*
G01Y65710D02*
X42234D01*
X44456Y64292D01*
Y66208D01*
G01X44972Y67698D02*
X45231Y67967D01*
X45334Y68273D01*
X45231Y68580D01*
X44921Y68848D01*
X44456Y69040D01*
X43991Y69117D01*
X43422D01*
X42957Y69040D01*
X42544Y68848D01*
X42337Y68618D01*
X42234Y68350D01*
X42337Y68043D01*
X42544Y67813D01*
X42854Y67660D01*
X43267Y67583D01*
X43629Y67660D01*
X43991Y67852D01*
X44197Y68082D01*
X44249Y68350D01*
X44146Y68657D01*
X43887Y68887D01*
X43422Y69117D01*
G01X45334Y71373D02*
X44662Y71450D01*
X44094Y71565D01*
X43577Y71718D01*
X43009Y71910D01*
X42234Y72217D01*
Y70683D01*
G01X33689Y71260D02*
Y74360D01*
X33229Y73740D01*
G01Y71260D02*
X34149D01*
G01X47050Y104083D02*
X43950D01*
Y105042D01*
X44105Y105348D01*
X44312Y105540D01*
X44725Y105617D01*
X45138Y105540D01*
X45397Y105310D01*
X45552Y105042D01*
Y104083D01*
G01Y105042D02*
X47050Y105617D01*
G01Y107950D02*
X43950D01*
X44570Y107490D01*
G01X47050D02*
Y108410D01*
G01X44467Y110322D02*
X44157Y110552D01*
X44002Y110820D01*
X43950Y111127D01*
X44053Y111510D01*
X44312Y111778D01*
X44622Y111855D01*
X44932Y111817D01*
X45190Y111663D01*
X45707Y110897D01*
X46068Y110552D01*
X46585Y110322D01*
X47050Y110245D01*
Y111855D01*
G01X44467Y113422D02*
X44157Y113652D01*
X44002Y113920D01*
X43950Y114227D01*
X44053Y114610D01*
X44312Y114878D01*
X44622Y114955D01*
X44932Y114917D01*
X45190Y114763D01*
X45707Y113997D01*
X46068Y113652D01*
X46585Y113422D01*
X47050Y113345D01*
Y114955D01*
G01Y116583D02*
X43950D01*
Y117542D01*
X44105Y117848D01*
X44312Y118040D01*
X44725Y118117D01*
X45138Y118040D01*
X45397Y117810D01*
X45552Y117542D01*
Y116583D01*
G01Y117542D02*
X47050Y118117D01*
G01Y120910D02*
X43950D01*
X46172Y119492D01*
Y121408D01*
G01X46688Y122898D02*
X46947Y123167D01*
X47050Y123473D01*
X46947Y123780D01*
X46637Y124048D01*
X46172Y124240D01*
X45707Y124317D01*
X45138D01*
X44673Y124240D01*
X44260Y124048D01*
X44053Y123818D01*
X43950Y123550D01*
X44053Y123243D01*
X44260Y123013D01*
X44570Y122860D01*
X44983Y122783D01*
X45345Y122860D01*
X45707Y123052D01*
X45913Y123282D01*
X45965Y123550D01*
X45862Y123857D01*
X45603Y124087D01*
X45138Y124317D01*
G01X45758Y125922D02*
X45397Y126190D01*
X45190Y126420D01*
X45087Y126727D01*
X45190Y126995D01*
X45397Y127187D01*
X45707Y127340D01*
X46068Y127378D01*
X46378Y127340D01*
X46688Y127187D01*
X46947Y126957D01*
X47050Y126688D01*
X46947Y126382D01*
X46637Y126113D01*
X46172Y125960D01*
X45655Y125922D01*
X44983Y125998D01*
X44622Y126113D01*
X44260Y126305D01*
X44002Y126573D01*
X43950Y126842D01*
X44053Y127110D01*
X44312Y127302D01*
G01X33689Y128346D02*
Y131446D01*
X33229Y130826D01*
G01Y128346D02*
X34149D01*
G01X34150Y149381D02*
X31050D01*
Y150340D01*
X31205Y150646D01*
X31412Y150838D01*
X31825Y150915D01*
X32238Y150838D01*
X32497Y150608D01*
X32652Y150340D01*
Y149381D01*
G01Y150340D02*
X34150Y150915D01*
G01X33530Y152405D02*
X33892Y152635D01*
X34098Y152941D01*
X34150Y153286D01*
X34098Y153593D01*
X33840Y153900D01*
X33530Y154091D01*
X33220Y154130D01*
X32858Y154053D01*
X32600Y153785D01*
X32497Y153516D01*
Y153171D01*
G01Y153516D02*
X32342Y153746D01*
X32083Y153938D01*
X31773Y154015D01*
X31463Y153938D01*
X31205Y153746D01*
X31050Y153401D01*
X31102Y153056D01*
X31308Y152711D01*
G01X34150Y156348D02*
X34098Y156616D01*
X33943Y156923D01*
X33685Y157115D01*
X33323Y157191D01*
X32962Y157115D01*
X32652Y156885D01*
X32497Y156540D01*
Y156156D01*
X32393Y155926D01*
X32135Y155735D01*
X31773Y155658D01*
X31412Y155773D01*
X31153Y156041D01*
X31050Y156348D01*
X31153Y156655D01*
X31412Y156923D01*
X31773Y157038D01*
X32135Y156961D01*
X32393Y156770D01*
X32497Y156540D01*
Y156156D01*
X32652Y155811D01*
X32962Y155581D01*
X33323Y155505D01*
X33685Y155581D01*
X33943Y155773D01*
X34098Y156080D01*
X34150Y156348D01*
G01Y159371D02*
X33478Y159448D01*
X32910Y159563D01*
X32393Y159716D01*
X31825Y159908D01*
X31050Y160215D01*
Y158681D01*
G01X38650Y149381D02*
X35550D01*
Y150340D01*
X35705Y150646D01*
X35912Y150838D01*
X36325Y150915D01*
X36738Y150838D01*
X36997Y150608D01*
X37152Y150340D01*
Y149381D01*
G01Y150340D02*
X38650Y150915D01*
G01Y153248D02*
X35550D01*
X36170Y152788D01*
G01X38650D02*
Y153708D01*
G01X36067Y155620D02*
X35757Y155850D01*
X35602Y156118D01*
X35550Y156425D01*
X35653Y156808D01*
X35912Y157076D01*
X36222Y157153D01*
X36532Y157115D01*
X36790Y156961D01*
X37307Y156195D01*
X37668Y155850D01*
X38185Y155620D01*
X38650Y155543D01*
Y157153D01*
G01X38185Y158605D02*
X38443Y158835D01*
X38598Y159103D01*
X38650Y159448D01*
X38547Y159793D01*
X38340Y160061D01*
X37978Y160253D01*
X37565Y160291D01*
X37152Y160215D01*
X36893Y160023D01*
X36687Y159755D01*
X36635Y159486D01*
X36687Y159218D01*
X36893Y158873D01*
X35550Y158988D01*
Y160023D01*
G01X43150Y149381D02*
X40050D01*
Y150340D01*
X40205Y150646D01*
X40412Y150838D01*
X40825Y150915D01*
X41238Y150838D01*
X41497Y150608D01*
X41652Y150340D01*
Y149381D01*
G01Y150340D02*
X43150Y150915D01*
G01X42530Y152405D02*
X42892Y152635D01*
X43098Y152941D01*
X43150Y153286D01*
X43098Y153593D01*
X42840Y153900D01*
X42530Y154091D01*
X42220Y154130D01*
X41858Y154053D01*
X41600Y153785D01*
X41497Y153516D01*
Y153171D01*
G01Y153516D02*
X41342Y153746D01*
X41083Y153938D01*
X40773Y154015D01*
X40463Y153938D01*
X40205Y153746D01*
X40050Y153401D01*
X40102Y153056D01*
X40308Y152711D01*
G01X43150Y156348D02*
X43098Y156616D01*
X42943Y156923D01*
X42685Y157115D01*
X42323Y157191D01*
X41962Y157115D01*
X41652Y156885D01*
X41497Y156540D01*
Y156156D01*
X41393Y155926D01*
X41135Y155735D01*
X40773Y155658D01*
X40412Y155773D01*
X40153Y156041D01*
X40050Y156348D01*
X40153Y156655D01*
X40412Y156923D01*
X40773Y157038D01*
X41135Y156961D01*
X41393Y156770D01*
X41497Y156540D01*
Y156156D01*
X41652Y155811D01*
X41962Y155581D01*
X42323Y155505D01*
X42685Y155581D01*
X42943Y155773D01*
X43098Y156080D01*
X43150Y156348D01*
G01X41858Y158720D02*
X41497Y158988D01*
X41290Y159218D01*
X41187Y159525D01*
X41290Y159793D01*
X41497Y159985D01*
X41807Y160138D01*
X42168Y160176D01*
X42478Y160138D01*
X42788Y159985D01*
X43047Y159755D01*
X43150Y159486D01*
X43047Y159180D01*
X42737Y158911D01*
X42272Y158758D01*
X41755Y158720D01*
X41083Y158796D01*
X40722Y158911D01*
X40360Y159103D01*
X40102Y159371D01*
X40050Y159640D01*
X40153Y159908D01*
X40412Y160100D01*
G01X47050Y160083D02*
X43950D01*
Y161042D01*
X44105Y161348D01*
X44312Y161540D01*
X44725Y161617D01*
X45138Y161540D01*
X45397Y161310D01*
X45552Y161042D01*
Y160083D01*
G01Y161042D02*
X47050Y161617D01*
G01Y164410D02*
X43950D01*
X46172Y162992D01*
Y164908D01*
G01X46688Y166398D02*
X46947Y166667D01*
X47050Y166973D01*
X46947Y167280D01*
X46637Y167548D01*
X46172Y167740D01*
X45707Y167817D01*
X45138D01*
X44673Y167740D01*
X44260Y167548D01*
X44053Y167318D01*
X43950Y167050D01*
X44053Y166743D01*
X44260Y166513D01*
X44570Y166360D01*
X44983Y166283D01*
X45345Y166360D01*
X45707Y166552D01*
X45913Y166782D01*
X45965Y167050D01*
X45862Y167357D01*
X45603Y167587D01*
X45138Y167817D01*
G01X46688Y169498D02*
X46947Y169767D01*
X47050Y170073D01*
X46947Y170380D01*
X46637Y170648D01*
X46172Y170840D01*
X45707Y170917D01*
X45138D01*
X44673Y170840D01*
X44260Y170648D01*
X44053Y170418D01*
X43950Y170150D01*
X44053Y169843D01*
X44260Y169613D01*
X44570Y169460D01*
X44983Y169383D01*
X45345Y169460D01*
X45707Y169652D01*
X45913Y169882D01*
X45965Y170150D01*
X45862Y170457D01*
X45603Y170687D01*
X45138Y170917D01*
G01X46550Y173583D02*
X43450D01*
Y174542D01*
X43605Y174848D01*
X43812Y175040D01*
X44225Y175117D01*
X44638Y175040D01*
X44897Y174810D01*
X45052Y174542D01*
Y173583D01*
G01Y174542D02*
X46550Y175117D01*
G01Y177450D02*
X43450D01*
X44070Y176990D01*
G01X46550D02*
Y177910D01*
G01X43967Y179822D02*
X43657Y180052D01*
X43502Y180320D01*
X43450Y180627D01*
X43553Y181010D01*
X43812Y181278D01*
X44122Y181355D01*
X44432Y181317D01*
X44690Y181163D01*
X45207Y180397D01*
X45568Y180052D01*
X46085Y179822D01*
X46550Y179745D01*
Y181355D01*
G01X45258Y182922D02*
X44897Y183190D01*
X44690Y183420D01*
X44587Y183727D01*
X44690Y183995D01*
X44897Y184187D01*
X45207Y184340D01*
X45568Y184378D01*
X45878Y184340D01*
X46188Y184187D01*
X46447Y183957D01*
X46550Y183688D01*
X46447Y183382D01*
X46137Y183113D01*
X45672Y182960D01*
X45155Y182922D01*
X44483Y182998D01*
X44122Y183113D01*
X43760Y183305D01*
X43502Y183573D01*
X43450Y183842D01*
X43553Y184110D01*
X43812Y184302D01*
G01X32150Y185441D02*
Y188541D01*
X31690Y187921D01*
G01Y185441D02*
X32610D01*
G01X46193Y217292D02*
X45963Y217447D01*
X45695Y217550D01*
X45388D01*
X45043Y217395D01*
X44775Y217137D01*
X44583Y216827D01*
X44430Y216310D01*
X44392Y215845D01*
X44468Y215380D01*
X44583Y215070D01*
X44813Y214760D01*
X45082Y214553D01*
X45350Y214450D01*
X45618D01*
X45887Y214553D01*
X46117Y214708D01*
X46308Y214915D01*
G01X47607Y215070D02*
X47837Y214708D01*
X48143Y214502D01*
X48488Y214450D01*
X48795Y214502D01*
X49102Y214760D01*
X49293Y215070D01*
X49332Y215380D01*
X49255Y215742D01*
X48987Y216000D01*
X48718Y216103D01*
X48373D01*
G01X48718D02*
X48948Y216258D01*
X49140Y216517D01*
X49217Y216827D01*
X49140Y217137D01*
X48948Y217395D01*
X48603Y217550D01*
X48258Y217498D01*
X47913Y217292D01*
G01X51550Y214450D02*
Y217550D01*
X51090Y216930D01*
G01Y214450D02*
X52010D01*
G01X54650D02*
X54918Y214502D01*
X55225Y214657D01*
X55417Y214915D01*
X55493Y215277D01*
X55417Y215638D01*
X55187Y215948D01*
X54842Y216103D01*
X54458D01*
X54228Y216207D01*
X54037Y216465D01*
X53960Y216827D01*
X54075Y217188D01*
X54343Y217447D01*
X54650Y217550D01*
X54957Y217447D01*
X55225Y217188D01*
X55340Y216827D01*
X55263Y216465D01*
X55072Y216207D01*
X54842Y216103D01*
X54458D01*
X54113Y215948D01*
X53883Y215638D01*
X53807Y215277D01*
X53883Y214915D01*
X54075Y214657D01*
X54382Y214502D01*
X54650Y214450D01*
G01X29631Y218294D02*
X29861Y217932D01*
X30167Y217726D01*
X30512Y217674D01*
X30819Y217726D01*
X31126Y217984D01*
X31317Y218294D01*
X31356Y218604D01*
X31279Y218966D01*
X31011Y219224D01*
X30742Y219327D01*
X30397D01*
G01X30742D02*
X30972Y219482D01*
X31164Y219741D01*
X31241Y220051D01*
X31164Y220361D01*
X30972Y220619D01*
X30627Y220774D01*
X30282Y220722D01*
X29937Y220516D01*
G01X47550Y219583D02*
X44450D01*
Y220542D01*
X44605Y220848D01*
X44812Y221040D01*
X45225Y221117D01*
X45638Y221040D01*
X45897Y220810D01*
X46052Y220542D01*
Y219583D01*
G01Y220542D02*
X47550Y221117D01*
G01Y223450D02*
X44450D01*
X45070Y222990D01*
G01X47550D02*
Y223910D01*
G01X44967Y225822D02*
X44657Y226052D01*
X44502Y226320D01*
X44450Y226627D01*
X44553Y227010D01*
X44812Y227278D01*
X45122Y227355D01*
X45432Y227317D01*
X45690Y227163D01*
X46207Y226397D01*
X46568Y226052D01*
X47085Y225822D01*
X47550Y225745D01*
Y227355D01*
G01Y229573D02*
X46878Y229650D01*
X46310Y229765D01*
X45793Y229918D01*
X45225Y230110D01*
X44450Y230417D01*
Y228883D01*
G01X46550Y232083D02*
X43450D01*
Y233042D01*
X43605Y233348D01*
X43812Y233540D01*
X44225Y233617D01*
X44638Y233540D01*
X44897Y233310D01*
X45052Y233042D01*
Y232083D01*
G01Y233042D02*
X46550Y233617D01*
G01Y236410D02*
X43450D01*
X45672Y234992D01*
Y236908D01*
G01X46188Y238398D02*
X46447Y238667D01*
X46550Y238973D01*
X46447Y239280D01*
X46137Y239548D01*
X45672Y239740D01*
X45207Y239817D01*
X44638D01*
X44173Y239740D01*
X43760Y239548D01*
X43553Y239318D01*
X43450Y239050D01*
X43553Y238743D01*
X43760Y238513D01*
X44070Y238360D01*
X44483Y238283D01*
X44845Y238360D01*
X45207Y238552D01*
X45413Y238782D01*
X45465Y239050D01*
X45362Y239357D01*
X45103Y239587D01*
X44638Y239817D01*
G01X46550Y242150D02*
X46498Y242418D01*
X46343Y242725D01*
X46085Y242917D01*
X45723Y242993D01*
X45362Y242917D01*
X45052Y242687D01*
X44897Y242342D01*
Y241958D01*
X44793Y241728D01*
X44535Y241537D01*
X44173Y241460D01*
X43812Y241575D01*
X43553Y241843D01*
X43450Y242150D01*
X43553Y242457D01*
X43812Y242725D01*
X44173Y242840D01*
X44535Y242763D01*
X44793Y242572D01*
X44897Y242342D01*
Y241958D01*
X45052Y241613D01*
X45362Y241383D01*
X45723Y241307D01*
X46085Y241383D01*
X46343Y241575D01*
X46498Y241882D01*
X46550Y242150D01*
G01X33689Y242520D02*
Y245620D01*
X33229Y245000D01*
G01Y242520D02*
X34149D01*
G01X39250Y263091D02*
X36150D01*
Y264050D01*
X36305Y264356D01*
X36512Y264548D01*
X36925Y264625D01*
X37338Y264548D01*
X37597Y264318D01*
X37752Y264050D01*
Y263091D01*
G01Y264050D02*
X39250Y264625D01*
G01X38630Y266115D02*
X38992Y266345D01*
X39198Y266651D01*
X39250Y266996D01*
X39198Y267303D01*
X38940Y267610D01*
X38630Y267801D01*
X38320Y267840D01*
X37958Y267763D01*
X37700Y267495D01*
X37597Y267226D01*
Y266881D01*
G01Y267226D02*
X37442Y267456D01*
X37183Y267648D01*
X36873Y267725D01*
X36563Y267648D01*
X36305Y267456D01*
X36150Y267111D01*
X36202Y266766D01*
X36408Y266421D01*
G01X38888Y269406D02*
X39147Y269675D01*
X39250Y269981D01*
X39147Y270288D01*
X38837Y270556D01*
X38372Y270748D01*
X37907Y270825D01*
X37338D01*
X36873Y270748D01*
X36460Y270556D01*
X36253Y270326D01*
X36150Y270058D01*
X36253Y269751D01*
X36460Y269521D01*
X36770Y269368D01*
X37183Y269291D01*
X37545Y269368D01*
X37907Y269560D01*
X38113Y269790D01*
X38165Y270058D01*
X38062Y270365D01*
X37803Y270595D01*
X37338Y270825D01*
G01X36667Y272430D02*
X36357Y272660D01*
X36202Y272928D01*
X36150Y273235D01*
X36253Y273618D01*
X36512Y273886D01*
X36822Y273963D01*
X37132Y273925D01*
X37390Y273771D01*
X37907Y273005D01*
X38268Y272660D01*
X38785Y272430D01*
X39250Y272353D01*
Y273963D01*
G01X43750Y263091D02*
X40650D01*
Y264050D01*
X40805Y264356D01*
X41012Y264548D01*
X41425Y264625D01*
X41838Y264548D01*
X42097Y264318D01*
X42252Y264050D01*
Y263091D01*
G01Y264050D02*
X43750Y264625D01*
G01X43130Y266115D02*
X43492Y266345D01*
X43698Y266651D01*
X43750Y266996D01*
X43698Y267303D01*
X43440Y267610D01*
X43130Y267801D01*
X42820Y267840D01*
X42458Y267763D01*
X42200Y267495D01*
X42097Y267226D01*
Y266881D01*
G01Y267226D02*
X41942Y267456D01*
X41683Y267648D01*
X41373Y267725D01*
X41063Y267648D01*
X40805Y267456D01*
X40650Y267111D01*
X40702Y266766D01*
X40908Y266421D01*
G01X43750Y269981D02*
X43078Y270058D01*
X42510Y270173D01*
X41993Y270326D01*
X41425Y270518D01*
X40650Y270825D01*
Y269291D01*
G01X43285Y272315D02*
X43543Y272545D01*
X43698Y272813D01*
X43750Y273158D01*
X43647Y273503D01*
X43440Y273771D01*
X43078Y273963D01*
X42665Y274001D01*
X42252Y273925D01*
X41993Y273733D01*
X41787Y273465D01*
X41735Y273196D01*
X41787Y272928D01*
X41993Y272583D01*
X40650Y272698D01*
Y273733D01*
G01X34750Y263091D02*
X31650D01*
Y264050D01*
X31805Y264356D01*
X32012Y264548D01*
X32425Y264625D01*
X32838Y264548D01*
X33097Y264318D01*
X33252Y264050D01*
Y263091D01*
G01Y264050D02*
X34750Y264625D01*
G01X34130Y266115D02*
X34492Y266345D01*
X34698Y266651D01*
X34750Y266996D01*
X34698Y267303D01*
X34440Y267610D01*
X34130Y267801D01*
X33820Y267840D01*
X33458Y267763D01*
X33200Y267495D01*
X33097Y267226D01*
Y266881D01*
G01Y267226D02*
X32942Y267456D01*
X32683Y267648D01*
X32373Y267725D01*
X32063Y267648D01*
X31805Y267456D01*
X31650Y267111D01*
X31702Y266766D01*
X31908Y266421D01*
G01X34388Y269406D02*
X34647Y269675D01*
X34750Y269981D01*
X34647Y270288D01*
X34337Y270556D01*
X33872Y270748D01*
X33407Y270825D01*
X32838D01*
X32373Y270748D01*
X31960Y270556D01*
X31753Y270326D01*
X31650Y270058D01*
X31753Y269751D01*
X31960Y269521D01*
X32270Y269368D01*
X32683Y269291D01*
X33045Y269368D01*
X33407Y269560D01*
X33613Y269790D01*
X33665Y270058D01*
X33562Y270365D01*
X33303Y270595D01*
X32838Y270825D01*
G01X34130Y272315D02*
X34492Y272545D01*
X34698Y272851D01*
X34750Y273196D01*
X34698Y273503D01*
X34440Y273810D01*
X34130Y274001D01*
X33820Y274040D01*
X33458Y273963D01*
X33200Y273695D01*
X33097Y273426D01*
Y273081D01*
G01Y273426D02*
X32942Y273656D01*
X32683Y273848D01*
X32373Y273925D01*
X32063Y273848D01*
X31805Y273656D01*
X31650Y273311D01*
X31702Y272966D01*
X31908Y272621D01*
G01X43518Y315583D02*
X40418D01*
Y316542D01*
X40573Y316848D01*
X40780Y317040D01*
X41193Y317117D01*
X41606Y317040D01*
X41865Y316810D01*
X42020Y316542D01*
Y315583D01*
G01Y316542D02*
X43518Y317117D01*
G01X42898Y318607D02*
X43260Y318837D01*
X43466Y319143D01*
X43518Y319488D01*
X43466Y319795D01*
X43208Y320102D01*
X42898Y320293D01*
X42588Y320332D01*
X42226Y320255D01*
X41968Y319987D01*
X41865Y319718D01*
Y319373D01*
G01Y319718D02*
X41710Y319948D01*
X41451Y320140D01*
X41141Y320217D01*
X40831Y320140D01*
X40573Y319948D01*
X40418Y319603D01*
X40470Y319258D01*
X40676Y318913D01*
G01X43156Y321898D02*
X43415Y322167D01*
X43518Y322473D01*
X43415Y322780D01*
X43105Y323048D01*
X42640Y323240D01*
X42175Y323317D01*
X41606D01*
X41141Y323240D01*
X40728Y323048D01*
X40521Y322818D01*
X40418Y322550D01*
X40521Y322243D01*
X40728Y322013D01*
X41038Y321860D01*
X41451Y321783D01*
X41813Y321860D01*
X42175Y322052D01*
X42381Y322282D01*
X42433Y322550D01*
X42330Y322857D01*
X42071Y323087D01*
X41606Y323317D01*
G01X43518Y325650D02*
X43466Y325918D01*
X43311Y326225D01*
X43053Y326417D01*
X42691Y326493D01*
X42330Y326417D01*
X42020Y326187D01*
X41865Y325842D01*
Y325458D01*
X41761Y325228D01*
X41503Y325037D01*
X41141Y324960D01*
X40780Y325075D01*
X40521Y325343D01*
X40418Y325650D01*
X40521Y325957D01*
X40780Y326225D01*
X41141Y326340D01*
X41503Y326263D01*
X41761Y326072D01*
X41865Y325842D01*
Y325458D01*
X42020Y325113D01*
X42330Y324883D01*
X42691Y324807D01*
X43053Y324883D01*
X43311Y325075D01*
X43466Y325382D01*
X43518Y325650D01*
G01X38518Y315583D02*
X35418D01*
Y316542D01*
X35573Y316848D01*
X35780Y317040D01*
X36193Y317117D01*
X36606Y317040D01*
X36865Y316810D01*
X37020Y316542D01*
Y315583D01*
G01Y316542D02*
X38518Y317117D01*
G01Y319910D02*
X35418D01*
X37640Y318492D01*
Y320408D01*
G01X35935Y321822D02*
X35625Y322052D01*
X35470Y322320D01*
X35418Y322627D01*
X35521Y323010D01*
X35780Y323278D01*
X36090Y323355D01*
X36400Y323317D01*
X36658Y323163D01*
X37175Y322397D01*
X37536Y322052D01*
X38053Y321822D01*
X38518Y321745D01*
Y323355D01*
G01X37226Y324922D02*
X36865Y325190D01*
X36658Y325420D01*
X36555Y325727D01*
X36658Y325995D01*
X36865Y326187D01*
X37175Y326340D01*
X37536Y326378D01*
X37846Y326340D01*
X38156Y326187D01*
X38415Y325957D01*
X38518Y325688D01*
X38415Y325382D01*
X38105Y325113D01*
X37640Y324960D01*
X37123Y324922D01*
X36451Y324998D01*
X36090Y325113D01*
X35728Y325305D01*
X35470Y325573D01*
X35418Y325842D01*
X35521Y326110D01*
X35780Y326302D01*
G01X33518Y315583D02*
X30418D01*
Y316542D01*
X30573Y316848D01*
X30780Y317040D01*
X31193Y317117D01*
X31606Y317040D01*
X31865Y316810D01*
X32020Y316542D01*
Y315583D01*
G01Y316542D02*
X33518Y317117D01*
G01X32898Y318607D02*
X33260Y318837D01*
X33466Y319143D01*
X33518Y319488D01*
X33466Y319795D01*
X33208Y320102D01*
X32898Y320293D01*
X32588Y320332D01*
X32226Y320255D01*
X31968Y319987D01*
X31865Y319718D01*
Y319373D01*
G01Y319718D02*
X31710Y319948D01*
X31451Y320140D01*
X31141Y320217D01*
X30831Y320140D01*
X30573Y319948D01*
X30418Y319603D01*
X30470Y319258D01*
X30676Y318913D01*
G01X33156Y321898D02*
X33415Y322167D01*
X33518Y322473D01*
X33415Y322780D01*
X33105Y323048D01*
X32640Y323240D01*
X32175Y323317D01*
X31606D01*
X31141Y323240D01*
X30728Y323048D01*
X30521Y322818D01*
X30418Y322550D01*
X30521Y322243D01*
X30728Y322013D01*
X31038Y321860D01*
X31451Y321783D01*
X31813Y321860D01*
X32175Y322052D01*
X32381Y322282D01*
X32433Y322550D01*
X32330Y322857D01*
X32071Y323087D01*
X31606Y323317D01*
G01X33156Y324998D02*
X33415Y325267D01*
X33518Y325573D01*
X33415Y325880D01*
X33105Y326148D01*
X32640Y326340D01*
X32175Y326417D01*
X31606D01*
X31141Y326340D01*
X30728Y326148D01*
X30521Y325918D01*
X30418Y325650D01*
X30521Y325343D01*
X30728Y325113D01*
X31038Y324960D01*
X31451Y324883D01*
X31813Y324960D01*
X32175Y325152D01*
X32381Y325382D01*
X32433Y325650D01*
X32330Y325957D01*
X32071Y326187D01*
X31606Y326417D01*
G01X42630Y330000D02*
X43397D01*
Y329070D01*
X43167Y328760D01*
X42898Y328553D01*
X42515Y328450D01*
X42132Y328553D01*
X41863Y328760D01*
X41633Y329070D01*
X41480Y329432D01*
X41403Y329845D01*
Y330207D01*
X41480Y330517D01*
X41633Y330878D01*
X41863Y331188D01*
X42093Y331395D01*
X42400Y331550D01*
X42668D01*
X42975Y331447D01*
X43205Y331240D01*
G01X44695Y328450D02*
Y331550D01*
G01X46305D02*
Y328450D01*
G01Y330000D02*
X44695D01*
G01X47872Y331033D02*
X48102Y331343D01*
X48370Y331498D01*
X48677Y331550D01*
X49060Y331447D01*
X49328Y331188D01*
X49405Y330878D01*
X49367Y330568D01*
X49213Y330310D01*
X48447Y329793D01*
X48102Y329432D01*
X47872Y328915D01*
X47795Y328450D01*
X49405D01*
G01X41130Y353500D02*
X41897D01*
Y352570D01*
X41667Y352260D01*
X41398Y352053D01*
X41015Y351950D01*
X40632Y352053D01*
X40363Y352260D01*
X40133Y352570D01*
X39980Y352932D01*
X39903Y353345D01*
Y353707D01*
X39980Y354017D01*
X40133Y354378D01*
X40363Y354688D01*
X40593Y354895D01*
X40900Y355050D01*
X41168D01*
X41475Y354947D01*
X41705Y354740D01*
G01X43195Y351950D02*
Y355050D01*
G01X44805D02*
Y351950D01*
G01Y353500D02*
X43195D01*
G01X47100Y351950D02*
Y355050D01*
X46640Y354430D01*
G01Y351950D02*
X47560D01*
G01X58310Y62145D02*
X58578Y62197D01*
X58885Y62352D01*
X59077Y62610D01*
X59153Y62972D01*
X59077Y63333D01*
X58847Y63643D01*
X58502Y63798D01*
X58118D01*
X57888Y63902D01*
X57697Y64160D01*
X57620Y64522D01*
X57735Y64883D01*
X58003Y65142D01*
X58310Y65245D01*
X58617Y65142D01*
X58885Y64883D01*
X59000Y64522D01*
X58923Y64160D01*
X58732Y63902D01*
X58502Y63798D01*
X58118D01*
X57773Y63643D01*
X57543Y63333D01*
X57467Y62972D01*
X57543Y62610D01*
X57735Y62352D01*
X58042Y62197D01*
X58310Y62145D01*
G01X51085Y62661D02*
X51315Y62403D01*
X51583Y62248D01*
X51928Y62196D01*
X52273Y62299D01*
X52541Y62506D01*
X52733Y62868D01*
X52771Y63281D01*
X52695Y63694D01*
X52503Y63953D01*
X52235Y64159D01*
X51966Y64211D01*
X51698Y64159D01*
X51353Y63953D01*
X51468Y65296D01*
X52503D01*
G01X50460Y76878D02*
Y79978D01*
X49042Y77756D01*
X50958D01*
G01X53174Y67317D02*
X55396D01*
X55861Y67470D01*
X56171Y67777D01*
X56274Y68160D01*
X56171Y68543D01*
X55861Y68850D01*
X55396Y69003D01*
X53174D01*
G01X56274Y71260D02*
X53174D01*
X53794Y70800D01*
G01X56274D02*
Y71720D01*
G01Y74820D02*
X53174D01*
X55396Y73402D01*
Y75318D01*
G01X60333Y71591D02*
Y68491D01*
G01X59451Y71591D02*
X61215D01*
G01X62666Y68491D02*
Y71591D01*
X63586D01*
X63893Y71436D01*
X64123Y71074D01*
X64200Y70661D01*
X64123Y70248D01*
X63931Y69938D01*
X63586Y69783D01*
X62666D01*
G01X65690Y69111D02*
X65920Y68749D01*
X66226Y68543D01*
X66571Y68491D01*
X66878Y68543D01*
X67185Y68801D01*
X67376Y69111D01*
X67415Y69421D01*
X67338Y69783D01*
X67070Y70041D01*
X66801Y70144D01*
X66456D01*
G01X66801D02*
X67031Y70299D01*
X67223Y70558D01*
X67300Y70868D01*
X67223Y71178D01*
X67031Y71436D01*
X66686Y71591D01*
X66341Y71539D01*
X65996Y71333D01*
G01X69633Y68491D02*
Y71591D01*
X69173Y70971D01*
G01Y68491D02*
X70093D01*
G01X59550Y85083D02*
X56450D01*
Y86042D01*
X56605Y86348D01*
X56812Y86540D01*
X57225Y86617D01*
X57638Y86540D01*
X57897Y86310D01*
X58052Y86042D01*
Y85083D01*
G01Y86042D02*
X59550Y86617D01*
G01X58930Y88107D02*
X59292Y88337D01*
X59498Y88643D01*
X59550Y88988D01*
X59498Y89295D01*
X59240Y89602D01*
X58930Y89793D01*
X58620Y89832D01*
X58258Y89755D01*
X58000Y89487D01*
X57897Y89218D01*
Y88873D01*
G01Y89218D02*
X57742Y89448D01*
X57483Y89640D01*
X57173Y89717D01*
X56863Y89640D01*
X56605Y89448D01*
X56450Y89103D01*
X56502Y88758D01*
X56708Y88413D01*
G01X58258Y91322D02*
X57897Y91590D01*
X57690Y91820D01*
X57587Y92127D01*
X57690Y92395D01*
X57897Y92587D01*
X58207Y92740D01*
X58568Y92778D01*
X58878Y92740D01*
X59188Y92587D01*
X59447Y92357D01*
X59550Y92088D01*
X59447Y91782D01*
X59137Y91513D01*
X58672Y91360D01*
X58155Y91322D01*
X57483Y91398D01*
X57122Y91513D01*
X56760Y91705D01*
X56502Y91973D01*
X56450Y92242D01*
X56553Y92510D01*
X56812Y92702D01*
G01X59550Y95150D02*
X59498Y95418D01*
X59343Y95725D01*
X59085Y95917D01*
X58723Y95993D01*
X58362Y95917D01*
X58052Y95687D01*
X57897Y95342D01*
Y94958D01*
X57793Y94728D01*
X57535Y94537D01*
X57173Y94460D01*
X56812Y94575D01*
X56553Y94843D01*
X56450Y95150D01*
X56553Y95457D01*
X56812Y95725D01*
X57173Y95840D01*
X57535Y95763D01*
X57793Y95572D01*
X57897Y95342D01*
Y94958D01*
X58052Y94613D01*
X58362Y94383D01*
X58723Y94307D01*
X59085Y94383D01*
X59343Y94575D01*
X59498Y94882D01*
X59550Y95150D01*
G01X49534Y85083D02*
X46434D01*
Y86042D01*
X46589Y86348D01*
X46796Y86540D01*
X47209Y86617D01*
X47622Y86540D01*
X47881Y86310D01*
X48036Y86042D01*
Y85083D01*
G01Y86042D02*
X49534Y86617D01*
G01X48914Y88107D02*
X49276Y88337D01*
X49482Y88643D01*
X49534Y88988D01*
X49482Y89295D01*
X49224Y89602D01*
X48914Y89793D01*
X48604Y89832D01*
X48242Y89755D01*
X47984Y89487D01*
X47881Y89218D01*
Y88873D01*
G01Y89218D02*
X47726Y89448D01*
X47467Y89640D01*
X47157Y89717D01*
X46847Y89640D01*
X46589Y89448D01*
X46434Y89103D01*
X46486Y88758D01*
X46692Y88413D01*
G01X49534Y91973D02*
X48862Y92050D01*
X48294Y92165D01*
X47777Y92318D01*
X47209Y92510D01*
X46434Y92817D01*
Y91283D01*
G01Y95150D02*
X46537Y94843D01*
X46796Y94613D01*
X47106Y94460D01*
X47519Y94345D01*
X47984Y94307D01*
X48449Y94345D01*
X48862Y94460D01*
X49172Y94613D01*
X49431Y94843D01*
X49534Y95150D01*
X49431Y95457D01*
X49172Y95687D01*
X48862Y95840D01*
X48449Y95955D01*
X47984Y95993D01*
X47519Y95955D01*
X47106Y95840D01*
X46796Y95687D01*
X46537Y95457D01*
X46434Y95150D01*
G01X54534Y85083D02*
X51434D01*
Y86042D01*
X51589Y86348D01*
X51796Y86540D01*
X52209Y86617D01*
X52622Y86540D01*
X52881Y86310D01*
X53036Y86042D01*
Y85083D01*
G01Y86042D02*
X54534Y86617D01*
G01Y88950D02*
X51434D01*
X52054Y88490D01*
G01X54534D02*
Y89410D01*
G01X54069Y91207D02*
X54327Y91437D01*
X54482Y91705D01*
X54534Y92050D01*
X54431Y92395D01*
X54224Y92663D01*
X53862Y92855D01*
X53449Y92893D01*
X53036Y92817D01*
X52777Y92625D01*
X52571Y92357D01*
X52519Y92088D01*
X52571Y91820D01*
X52777Y91475D01*
X51434Y91590D01*
Y92625D01*
G01X54534Y95073D02*
X53862Y95150D01*
X53294Y95265D01*
X52777Y95418D01*
X52209Y95610D01*
X51434Y95917D01*
Y94383D01*
G01X61950Y81350D02*
X65050D01*
G01X61950Y80468D02*
Y82232D01*
G01X65050Y83683D02*
X61950D01*
Y84603D01*
X62105Y84910D01*
X62467Y85140D01*
X62880Y85217D01*
X63293Y85140D01*
X63603Y84948D01*
X63758Y84603D01*
Y83683D01*
G01X64430Y86707D02*
X64792Y86937D01*
X64998Y87243D01*
X65050Y87588D01*
X64998Y87895D01*
X64740Y88202D01*
X64430Y88393D01*
X64120Y88432D01*
X63758Y88355D01*
X63500Y88087D01*
X63397Y87818D01*
Y87473D01*
G01Y87818D02*
X63242Y88048D01*
X62983Y88240D01*
X62673Y88317D01*
X62363Y88240D01*
X62105Y88048D01*
X61950Y87703D01*
X62002Y87358D01*
X62208Y87013D01*
G01X64585Y89807D02*
X64843Y90037D01*
X64998Y90305D01*
X65050Y90650D01*
X64947Y90995D01*
X64740Y91263D01*
X64378Y91455D01*
X63965Y91493D01*
X63552Y91417D01*
X63293Y91225D01*
X63087Y90957D01*
X63035Y90688D01*
X63087Y90420D01*
X63293Y90075D01*
X61950Y90190D01*
Y91225D01*
G01X61208Y108243D02*
X61053Y108013D01*
X60950Y107745D01*
Y107438D01*
X61105Y107093D01*
X61363Y106825D01*
X61673Y106633D01*
X62190Y106480D01*
X62655Y106442D01*
X63120Y106518D01*
X63430Y106633D01*
X63740Y106863D01*
X63947Y107132D01*
X64050Y107400D01*
Y107668D01*
X63947Y107937D01*
X63792Y108167D01*
X63585Y108358D01*
G01X64050Y110500D02*
X63998Y110768D01*
X63843Y111075D01*
X63585Y111267D01*
X63223Y111343D01*
X62862Y111267D01*
X62552Y111037D01*
X62397Y110692D01*
Y110308D01*
X62293Y110078D01*
X62035Y109887D01*
X61673Y109810D01*
X61312Y109925D01*
X61053Y110193D01*
X60950Y110500D01*
X61053Y110807D01*
X61312Y111075D01*
X61673Y111190D01*
X62035Y111113D01*
X62293Y110922D01*
X62397Y110692D01*
Y110308D01*
X62552Y109963D01*
X62862Y109733D01*
X63223Y109657D01*
X63585Y109733D01*
X63843Y109925D01*
X63998Y110232D01*
X64050Y110500D01*
G01X63430Y112757D02*
X63792Y112987D01*
X63998Y113293D01*
X64050Y113638D01*
X63998Y113945D01*
X63740Y114252D01*
X63430Y114443D01*
X63120Y114482D01*
X62758Y114405D01*
X62500Y114137D01*
X62397Y113868D01*
Y113523D01*
G01Y113868D02*
X62242Y114098D01*
X61983Y114290D01*
X61673Y114367D01*
X61363Y114290D01*
X61105Y114098D01*
X60950Y113753D01*
X61002Y113408D01*
X61208Y113063D01*
G01X48122Y101335D02*
X47892Y101490D01*
X47624Y101593D01*
X47317D01*
X46972Y101438D01*
X46704Y101180D01*
X46512Y100870D01*
X46359Y100353D01*
X46321Y99888D01*
X46397Y99423D01*
X46512Y99113D01*
X46742Y98803D01*
X47011Y98596D01*
X47279Y98493D01*
X47547D01*
X47816Y98596D01*
X48046Y98751D01*
X48237Y98958D01*
G01X49536Y99113D02*
X49766Y98751D01*
X50072Y98545D01*
X50417Y98493D01*
X50724Y98545D01*
X51031Y98803D01*
X51222Y99113D01*
X51261Y99423D01*
X51184Y99785D01*
X50916Y100043D01*
X50647Y100146D01*
X50302D01*
G01X50647D02*
X50877Y100301D01*
X51069Y100560D01*
X51146Y100870D01*
X51069Y101180D01*
X50877Y101438D01*
X50532Y101593D01*
X50187Y101541D01*
X49842Y101335D01*
G01X53479Y98493D02*
Y101593D01*
X53019Y100973D01*
G01Y98493D02*
X53939D01*
G01X56579D02*
Y101593D01*
X56119Y100973D01*
G01Y98493D02*
X57039D01*
G01X52050Y104083D02*
X48950D01*
Y105042D01*
X49105Y105348D01*
X49312Y105540D01*
X49725Y105617D01*
X50138Y105540D01*
X50397Y105310D01*
X50552Y105042D01*
Y104083D01*
G01Y105042D02*
X52050Y105617D01*
G01X51430Y107107D02*
X51792Y107337D01*
X51998Y107643D01*
X52050Y107988D01*
X51998Y108295D01*
X51740Y108602D01*
X51430Y108793D01*
X51120Y108832D01*
X50758Y108755D01*
X50500Y108487D01*
X50397Y108218D01*
Y107873D01*
G01Y108218D02*
X50242Y108448D01*
X49983Y108640D01*
X49673Y108717D01*
X49363Y108640D01*
X49105Y108448D01*
X48950Y108103D01*
X49002Y107758D01*
X49208Y107413D01*
G01X52050Y110973D02*
X51378Y111050D01*
X50810Y111165D01*
X50293Y111318D01*
X49725Y111510D01*
X48950Y111817D01*
Y110283D01*
G01X52050Y114073D02*
X51378Y114150D01*
X50810Y114265D01*
X50293Y114418D01*
X49725Y114610D01*
X48950Y114917D01*
Y113383D01*
G01X54950Y106350D02*
X58050D01*
G01X54950Y105468D02*
Y107232D01*
G01X58050Y108683D02*
X54950D01*
Y109603D01*
X55105Y109910D01*
X55467Y110140D01*
X55880Y110217D01*
X56293Y110140D01*
X56603Y109948D01*
X56758Y109603D01*
Y108683D01*
G01X57430Y111707D02*
X57792Y111937D01*
X57998Y112243D01*
X58050Y112588D01*
X57998Y112895D01*
X57740Y113202D01*
X57430Y113393D01*
X57120Y113432D01*
X56758Y113355D01*
X56500Y113087D01*
X56397Y112818D01*
Y112473D01*
G01Y112818D02*
X56242Y113048D01*
X55983Y113240D01*
X55673Y113317D01*
X55363Y113240D01*
X55105Y113048D01*
X54950Y112703D01*
X55002Y112358D01*
X55208Y112013D01*
G01X54950Y115650D02*
X55053Y115343D01*
X55312Y115113D01*
X55622Y114960D01*
X56035Y114845D01*
X56500Y114807D01*
X56965Y114845D01*
X57378Y114960D01*
X57688Y115113D01*
X57947Y115343D01*
X58050Y115650D01*
X57947Y115957D01*
X57688Y116187D01*
X57378Y116340D01*
X56965Y116455D01*
X56500Y116493D01*
X56035Y116455D01*
X55622Y116340D01*
X55312Y116187D01*
X55053Y115957D01*
X54950Y115650D01*
G01X58310Y119231D02*
X58578Y119283D01*
X58885Y119438D01*
X59077Y119696D01*
X59153Y120058D01*
X59077Y120419D01*
X58847Y120729D01*
X58502Y120884D01*
X58118D01*
X57888Y120988D01*
X57697Y121246D01*
X57620Y121608D01*
X57735Y121969D01*
X58003Y122228D01*
X58310Y122331D01*
X58617Y122228D01*
X58885Y121969D01*
X59000Y121608D01*
X58923Y121246D01*
X58732Y120988D01*
X58502Y120884D01*
X58118D01*
X57773Y120729D01*
X57543Y120419D01*
X57467Y120058D01*
X57543Y119696D01*
X57735Y119438D01*
X58042Y119283D01*
X58310Y119231D01*
G01X51085Y119747D02*
X51315Y119489D01*
X51583Y119334D01*
X51928Y119282D01*
X52273Y119385D01*
X52541Y119592D01*
X52733Y119954D01*
X52771Y120367D01*
X52695Y120780D01*
X52503Y121039D01*
X52235Y121245D01*
X51966Y121297D01*
X51698Y121245D01*
X51353Y121039D01*
X51468Y122382D01*
X52503D01*
G01X53174Y124403D02*
X55396D01*
X55861Y124556D01*
X56171Y124863D01*
X56274Y125246D01*
X56171Y125629D01*
X55861Y125936D01*
X55396Y126089D01*
X53174D01*
G01X56274Y128346D02*
X53174D01*
X53794Y127886D01*
G01X56274D02*
Y128806D01*
G01X55654Y130603D02*
X56016Y130833D01*
X56222Y131139D01*
X56274Y131484D01*
X56222Y131791D01*
X55964Y132098D01*
X55654Y132289D01*
X55344Y132328D01*
X54982Y132251D01*
X54724Y131983D01*
X54621Y131714D01*
Y131369D01*
G01Y131714D02*
X54466Y131944D01*
X54207Y132136D01*
X53897Y132213D01*
X53587Y132136D01*
X53329Y131944D01*
X53174Y131599D01*
X53226Y131254D01*
X53432Y130909D01*
G01X60433Y131091D02*
Y127991D01*
G01X59551Y131091D02*
X61315D01*
G01X62766Y127991D02*
Y131091D01*
X63686D01*
X63993Y130936D01*
X64223Y130574D01*
X64300Y130161D01*
X64223Y129748D01*
X64031Y129438D01*
X63686Y129283D01*
X62766D01*
G01X65790Y128611D02*
X66020Y128249D01*
X66326Y128043D01*
X66671Y127991D01*
X66978Y128043D01*
X67285Y128301D01*
X67476Y128611D01*
X67515Y128921D01*
X67438Y129283D01*
X67170Y129541D01*
X66901Y129644D01*
X66556D01*
G01X66901D02*
X67131Y129799D01*
X67323Y130058D01*
X67400Y130368D01*
X67323Y130678D01*
X67131Y130936D01*
X66786Y131091D01*
X66441Y131039D01*
X66096Y130833D01*
G01X70193Y127991D02*
Y131091D01*
X68775Y128869D01*
X70691D01*
G01X59550Y141083D02*
X56450D01*
Y142042D01*
X56605Y142348D01*
X56812Y142540D01*
X57225Y142617D01*
X57638Y142540D01*
X57897Y142310D01*
X58052Y142042D01*
Y141083D01*
G01Y142042D02*
X59550Y142617D01*
G01X58930Y144107D02*
X59292Y144337D01*
X59498Y144643D01*
X59550Y144988D01*
X59498Y145295D01*
X59240Y145602D01*
X58930Y145793D01*
X58620Y145832D01*
X58258Y145755D01*
X58000Y145487D01*
X57897Y145218D01*
Y144873D01*
G01Y145218D02*
X57742Y145448D01*
X57483Y145640D01*
X57173Y145717D01*
X56863Y145640D01*
X56605Y145448D01*
X56450Y145103D01*
X56502Y144758D01*
X56708Y144413D01*
G01X58258Y147322D02*
X57897Y147590D01*
X57690Y147820D01*
X57587Y148127D01*
X57690Y148395D01*
X57897Y148587D01*
X58207Y148740D01*
X58568Y148778D01*
X58878Y148740D01*
X59188Y148587D01*
X59447Y148357D01*
X59550Y148088D01*
X59447Y147782D01*
X59137Y147513D01*
X58672Y147360D01*
X58155Y147322D01*
X57483Y147398D01*
X57122Y147513D01*
X56760Y147705D01*
X56502Y147973D01*
X56450Y148242D01*
X56553Y148510D01*
X56812Y148702D01*
G01X59085Y150307D02*
X59343Y150537D01*
X59498Y150805D01*
X59550Y151150D01*
X59447Y151495D01*
X59240Y151763D01*
X58878Y151955D01*
X58465Y151993D01*
X58052Y151917D01*
X57793Y151725D01*
X57587Y151457D01*
X57535Y151188D01*
X57587Y150920D01*
X57793Y150575D01*
X56450Y150690D01*
Y151725D01*
G01X49034Y141083D02*
X45934D01*
Y142042D01*
X46089Y142348D01*
X46296Y142540D01*
X46709Y142617D01*
X47122Y142540D01*
X47381Y142310D01*
X47536Y142042D01*
Y141083D01*
G01Y142042D02*
X49034Y142617D01*
G01X48414Y144107D02*
X48776Y144337D01*
X48982Y144643D01*
X49034Y144988D01*
X48982Y145295D01*
X48724Y145602D01*
X48414Y145793D01*
X48104Y145832D01*
X47742Y145755D01*
X47484Y145487D01*
X47381Y145218D01*
Y144873D01*
G01Y145218D02*
X47226Y145448D01*
X46967Y145640D01*
X46657Y145717D01*
X46347Y145640D01*
X46089Y145448D01*
X45934Y145103D01*
X45986Y144758D01*
X46192Y144413D01*
G01X47742Y147322D02*
X47381Y147590D01*
X47174Y147820D01*
X47071Y148127D01*
X47174Y148395D01*
X47381Y148587D01*
X47691Y148740D01*
X48052Y148778D01*
X48362Y148740D01*
X48672Y148587D01*
X48931Y148357D01*
X49034Y148088D01*
X48931Y147782D01*
X48621Y147513D01*
X48156Y147360D01*
X47639Y147322D01*
X46967Y147398D01*
X46606Y147513D01*
X46244Y147705D01*
X45986Y147973D01*
X45934Y148242D01*
X46037Y148510D01*
X46296Y148702D01*
G01X49034Y151073D02*
X48362Y151150D01*
X47794Y151265D01*
X47277Y151418D01*
X46709Y151610D01*
X45934Y151917D01*
Y150383D01*
G01X54550Y141083D02*
X51450D01*
Y142042D01*
X51605Y142348D01*
X51812Y142540D01*
X52225Y142617D01*
X52638Y142540D01*
X52897Y142310D01*
X53052Y142042D01*
Y141083D01*
G01Y142042D02*
X54550Y142617D01*
G01Y144950D02*
X51450D01*
X52070Y144490D01*
G01X54550D02*
Y145410D01*
G01X54085Y147207D02*
X54343Y147437D01*
X54498Y147705D01*
X54550Y148050D01*
X54447Y148395D01*
X54240Y148663D01*
X53878Y148855D01*
X53465Y148893D01*
X53052Y148817D01*
X52793Y148625D01*
X52587Y148357D01*
X52535Y148088D01*
X52587Y147820D01*
X52793Y147475D01*
X51450Y147590D01*
Y148625D01*
G01X53258Y150422D02*
X52897Y150690D01*
X52690Y150920D01*
X52587Y151227D01*
X52690Y151495D01*
X52897Y151687D01*
X53207Y151840D01*
X53568Y151878D01*
X53878Y151840D01*
X54188Y151687D01*
X54447Y151457D01*
X54550Y151188D01*
X54447Y150882D01*
X54137Y150613D01*
X53672Y150460D01*
X53155Y150422D01*
X52483Y150498D01*
X52122Y150613D01*
X51760Y150805D01*
X51502Y151073D01*
X51450Y151342D01*
X51553Y151610D01*
X51812Y151802D01*
G01X51460Y133909D02*
Y137009D01*
X50042Y134787D01*
X51958D01*
G01X60208Y163743D02*
X60053Y163513D01*
X59950Y163245D01*
Y162938D01*
X60105Y162593D01*
X60363Y162325D01*
X60673Y162133D01*
X61190Y161980D01*
X61655Y161942D01*
X62120Y162018D01*
X62430Y162133D01*
X62740Y162363D01*
X62947Y162632D01*
X63050Y162900D01*
Y163168D01*
X62947Y163437D01*
X62792Y163667D01*
X62585Y163858D01*
G01X63050Y166000D02*
X62998Y166268D01*
X62843Y166575D01*
X62585Y166767D01*
X62223Y166843D01*
X61862Y166767D01*
X61552Y166537D01*
X61397Y166192D01*
Y165808D01*
X61293Y165578D01*
X61035Y165387D01*
X60673Y165310D01*
X60312Y165425D01*
X60053Y165693D01*
X59950Y166000D01*
X60053Y166307D01*
X60312Y166575D01*
X60673Y166690D01*
X61035Y166613D01*
X61293Y166422D01*
X61397Y166192D01*
Y165808D01*
X61552Y165463D01*
X61862Y165233D01*
X62223Y165157D01*
X62585Y165233D01*
X62843Y165425D01*
X62998Y165732D01*
X63050Y166000D01*
G01Y169560D02*
X59950D01*
X62172Y168142D01*
Y170058D01*
G01X47193Y158792D02*
X46963Y158947D01*
X46695Y159050D01*
X46388D01*
X46043Y158895D01*
X45775Y158637D01*
X45583Y158327D01*
X45430Y157810D01*
X45392Y157345D01*
X45468Y156880D01*
X45583Y156570D01*
X45813Y156260D01*
X46082Y156053D01*
X46350Y155950D01*
X46618D01*
X46887Y156053D01*
X47117Y156208D01*
X47308Y156415D01*
G01X48607Y156570D02*
X48837Y156208D01*
X49143Y156002D01*
X49488Y155950D01*
X49795Y156002D01*
X50102Y156260D01*
X50293Y156570D01*
X50332Y156880D01*
X50255Y157242D01*
X49987Y157500D01*
X49718Y157603D01*
X49373D01*
G01X49718D02*
X49948Y157758D01*
X50140Y158017D01*
X50217Y158327D01*
X50140Y158637D01*
X49948Y158895D01*
X49603Y159050D01*
X49258Y158998D01*
X48913Y158792D01*
G01X52550Y155950D02*
Y159050D01*
X52090Y158430D01*
G01Y155950D02*
X53010D01*
G01X55650Y159050D02*
X55343Y158947D01*
X55113Y158688D01*
X54960Y158378D01*
X54845Y157965D01*
X54807Y157500D01*
X54845Y157035D01*
X54960Y156622D01*
X55113Y156312D01*
X55343Y156053D01*
X55650Y155950D01*
X55957Y156053D01*
X56187Y156312D01*
X56340Y156622D01*
X56455Y157035D01*
X56493Y157500D01*
X56455Y157965D01*
X56340Y158378D01*
X56187Y158688D01*
X55957Y158947D01*
X55650Y159050D01*
G01X48083Y163450D02*
Y166550D01*
X49042D01*
X49348Y166395D01*
X49540Y166188D01*
X49617Y165775D01*
X49540Y165362D01*
X49310Y165103D01*
X49042Y164948D01*
X48083D01*
G01X49042D02*
X49617Y163450D01*
G01X51107Y164070D02*
X51337Y163708D01*
X51643Y163502D01*
X51988Y163450D01*
X52295Y163502D01*
X52602Y163760D01*
X52793Y164070D01*
X52832Y164380D01*
X52755Y164742D01*
X52487Y165000D01*
X52218Y165103D01*
X51873D01*
G01X52218D02*
X52448Y165258D01*
X52640Y165517D01*
X52717Y165827D01*
X52640Y166137D01*
X52448Y166395D01*
X52103Y166550D01*
X51758Y166498D01*
X51413Y166292D01*
G01X55050Y163450D02*
X55318Y163502D01*
X55625Y163657D01*
X55817Y163915D01*
X55893Y164277D01*
X55817Y164638D01*
X55587Y164948D01*
X55242Y165103D01*
X54858D01*
X54628Y165207D01*
X54437Y165465D01*
X54360Y165827D01*
X54475Y166188D01*
X54743Y166447D01*
X55050Y166550D01*
X55357Y166447D01*
X55625Y166188D01*
X55740Y165827D01*
X55663Y165465D01*
X55472Y165207D01*
X55242Y165103D01*
X54858D01*
X54513Y164948D01*
X54283Y164638D01*
X54207Y164277D01*
X54283Y163915D01*
X54475Y163657D01*
X54782Y163502D01*
X55050Y163450D01*
G01X57307Y164070D02*
X57537Y163708D01*
X57843Y163502D01*
X58188Y163450D01*
X58495Y163502D01*
X58802Y163760D01*
X58993Y164070D01*
X59032Y164380D01*
X58955Y164742D01*
X58687Y165000D01*
X58418Y165103D01*
X58073D01*
G01X58418D02*
X58648Y165258D01*
X58840Y165517D01*
X58917Y165827D01*
X58840Y166137D01*
X58648Y166395D01*
X58303Y166550D01*
X57958Y166498D01*
X57613Y166292D01*
G01X61000Y175950D02*
X61268Y176002D01*
X61575Y176157D01*
X61767Y176415D01*
X61843Y176777D01*
X61767Y177138D01*
X61537Y177448D01*
X61192Y177603D01*
X60808D01*
X60578Y177707D01*
X60387Y177965D01*
X60310Y178327D01*
X60425Y178688D01*
X60693Y178947D01*
X61000Y179050D01*
X61307Y178947D01*
X61575Y178688D01*
X61690Y178327D01*
X61613Y177965D01*
X61422Y177707D01*
X61192Y177603D01*
X60808D01*
X60463Y177448D01*
X60233Y177138D01*
X60157Y176777D01*
X60233Y176415D01*
X60425Y176157D01*
X60732Y176002D01*
X61000Y175950D01*
G01X49157Y175915D02*
X49387Y175657D01*
X49655Y175502D01*
X50000Y175450D01*
X50345Y175553D01*
X50613Y175760D01*
X50805Y176122D01*
X50843Y176535D01*
X50767Y176948D01*
X50575Y177207D01*
X50307Y177413D01*
X50038Y177465D01*
X49770Y177413D01*
X49425Y177207D01*
X49540Y178550D01*
X50575D01*
G01X48850Y173550D02*
Y170450D01*
G01X47968Y173550D02*
X49732D01*
G01X51183Y170450D02*
Y173550D01*
X52103D01*
X52410Y173395D01*
X52640Y173033D01*
X52717Y172620D01*
X52640Y172207D01*
X52448Y171897D01*
X52103Y171742D01*
X51183D01*
G01X54322Y173033D02*
X54552Y173343D01*
X54820Y173498D01*
X55127Y173550D01*
X55510Y173447D01*
X55778Y173188D01*
X55855Y172878D01*
X55817Y172568D01*
X55663Y172310D01*
X54897Y171793D01*
X54552Y171432D01*
X54322Y170915D01*
X54245Y170450D01*
X55855D01*
G01X57498Y170812D02*
X57767Y170553D01*
X58073Y170450D01*
X58380Y170553D01*
X58648Y170863D01*
X58840Y171328D01*
X58917Y171793D01*
Y172362D01*
X58840Y172827D01*
X58648Y173240D01*
X58418Y173447D01*
X58150Y173550D01*
X57843Y173447D01*
X57613Y173240D01*
X57460Y172930D01*
X57383Y172517D01*
X57460Y172155D01*
X57652Y171793D01*
X57882Y171587D01*
X58150Y171535D01*
X58457Y171638D01*
X58687Y171897D01*
X58917Y172362D01*
G01X53174Y181490D02*
X55396D01*
X55861Y181643D01*
X56171Y181950D01*
X56274Y182333D01*
X56171Y182716D01*
X55861Y183023D01*
X55396Y183176D01*
X53174D01*
G01X56274Y185433D02*
X53174D01*
X53794Y184973D01*
G01X56274D02*
Y185893D01*
G01X54982Y187805D02*
X54621Y188073D01*
X54414Y188303D01*
X54311Y188610D01*
X54414Y188878D01*
X54621Y189070D01*
X54931Y189223D01*
X55292Y189261D01*
X55602Y189223D01*
X55912Y189070D01*
X56171Y188840D01*
X56274Y188571D01*
X56171Y188265D01*
X55861Y187996D01*
X55396Y187843D01*
X54879Y187805D01*
X54207Y187881D01*
X53846Y187996D01*
X53484Y188188D01*
X53226Y188456D01*
X53174Y188725D01*
X53277Y188993D01*
X53536Y189185D01*
G01X49960Y190950D02*
Y194050D01*
X48542Y191828D01*
X50458D01*
G01X58850Y200050D02*
Y196950D01*
G01X57968Y200050D02*
X59732D01*
G01X61183Y196950D02*
Y200050D01*
X62103D01*
X62410Y199895D01*
X62640Y199533D01*
X62717Y199120D01*
X62640Y198707D01*
X62448Y198397D01*
X62103Y198242D01*
X61183D01*
G01X64207Y197570D02*
X64437Y197208D01*
X64743Y197002D01*
X65088Y196950D01*
X65395Y197002D01*
X65702Y197260D01*
X65893Y197570D01*
X65932Y197880D01*
X65855Y198242D01*
X65587Y198500D01*
X65318Y198603D01*
X64973D01*
G01X65318D02*
X65548Y198758D01*
X65740Y199017D01*
X65817Y199327D01*
X65740Y199637D01*
X65548Y199895D01*
X65203Y200050D01*
X64858Y199998D01*
X64513Y199792D01*
G01X67307Y197570D02*
X67537Y197208D01*
X67843Y197002D01*
X68188Y196950D01*
X68495Y197002D01*
X68802Y197260D01*
X68993Y197570D01*
X69032Y197880D01*
X68955Y198242D01*
X68687Y198500D01*
X68418Y198603D01*
X68073D01*
G01X68418D02*
X68648Y198758D01*
X68840Y199017D01*
X68917Y199327D01*
X68840Y199637D01*
X68648Y199895D01*
X68303Y200050D01*
X67958Y199998D01*
X67613Y199792D01*
G01X59050Y201583D02*
X55950D01*
Y202542D01*
X56105Y202848D01*
X56312Y203040D01*
X56725Y203117D01*
X57138Y203040D01*
X57397Y202810D01*
X57552Y202542D01*
Y201583D01*
G01Y202542D02*
X59050Y203117D01*
G01X58430Y204607D02*
X58792Y204837D01*
X58998Y205143D01*
X59050Y205488D01*
X58998Y205795D01*
X58740Y206102D01*
X58430Y206293D01*
X58120Y206332D01*
X57758Y206255D01*
X57500Y205987D01*
X57397Y205718D01*
Y205373D01*
G01Y205718D02*
X57242Y205948D01*
X56983Y206140D01*
X56673Y206217D01*
X56363Y206140D01*
X56105Y205948D01*
X55950Y205603D01*
X56002Y205258D01*
X56208Y204913D01*
G01X58430Y207707D02*
X58792Y207937D01*
X58998Y208243D01*
X59050Y208588D01*
X58998Y208895D01*
X58740Y209202D01*
X58430Y209393D01*
X58120Y209432D01*
X57758Y209355D01*
X57500Y209087D01*
X57397Y208818D01*
Y208473D01*
G01Y208818D02*
X57242Y209048D01*
X56983Y209240D01*
X56673Y209317D01*
X56363Y209240D01*
X56105Y209048D01*
X55950Y208703D01*
X56002Y208358D01*
X56208Y208013D01*
G01X59050Y211650D02*
X55950D01*
X56570Y211190D01*
G01X59050D02*
Y212110D01*
G01X49034Y201583D02*
X45934D01*
Y202542D01*
X46089Y202848D01*
X46296Y203040D01*
X46709Y203117D01*
X47122Y203040D01*
X47381Y202810D01*
X47536Y202542D01*
Y201583D01*
G01Y202542D02*
X49034Y203117D01*
G01X48414Y204607D02*
X48776Y204837D01*
X48982Y205143D01*
X49034Y205488D01*
X48982Y205795D01*
X48724Y206102D01*
X48414Y206293D01*
X48104Y206332D01*
X47742Y206255D01*
X47484Y205987D01*
X47381Y205718D01*
Y205373D01*
G01Y205718D02*
X47226Y205948D01*
X46967Y206140D01*
X46657Y206217D01*
X46347Y206140D01*
X46089Y205948D01*
X45934Y205603D01*
X45986Y205258D01*
X46192Y204913D01*
G01X49034Y208473D02*
X48362Y208550D01*
X47794Y208665D01*
X47277Y208818D01*
X46709Y209010D01*
X45934Y209317D01*
Y207783D01*
G01X46451Y210922D02*
X46141Y211152D01*
X45986Y211420D01*
X45934Y211727D01*
X46037Y212110D01*
X46296Y212378D01*
X46606Y212455D01*
X46916Y212417D01*
X47174Y212263D01*
X47691Y211497D01*
X48052Y211152D01*
X48569Y210922D01*
X49034Y210845D01*
Y212455D01*
G01X54034Y201583D02*
X50934D01*
Y202542D01*
X51089Y202848D01*
X51296Y203040D01*
X51709Y203117D01*
X52122Y203040D01*
X52381Y202810D01*
X52536Y202542D01*
Y201583D01*
G01Y202542D02*
X54034Y203117D01*
G01Y205450D02*
X50934D01*
X51554Y204990D01*
G01X54034D02*
Y205910D01*
G01X51451Y207822D02*
X51141Y208052D01*
X50986Y208320D01*
X50934Y208627D01*
X51037Y209010D01*
X51296Y209278D01*
X51606Y209355D01*
X51916Y209317D01*
X52174Y209163D01*
X52691Y208397D01*
X53052Y208052D01*
X53569Y207822D01*
X54034Y207745D01*
Y209355D01*
G01Y211650D02*
X50934D01*
X51554Y211190D01*
G01X54034D02*
Y212110D01*
G01X62708Y222743D02*
X62553Y222513D01*
X62450Y222245D01*
Y221938D01*
X62605Y221593D01*
X62863Y221325D01*
X63173Y221133D01*
X63690Y220980D01*
X64155Y220942D01*
X64620Y221018D01*
X64930Y221133D01*
X65240Y221363D01*
X65447Y221632D01*
X65550Y221900D01*
Y222168D01*
X65447Y222437D01*
X65292Y222667D01*
X65085Y222858D01*
G01X65550Y225000D02*
X65498Y225268D01*
X65343Y225575D01*
X65085Y225767D01*
X64723Y225843D01*
X64362Y225767D01*
X64052Y225537D01*
X63897Y225192D01*
Y224808D01*
X63793Y224578D01*
X63535Y224387D01*
X63173Y224310D01*
X62812Y224425D01*
X62553Y224693D01*
X62450Y225000D01*
X62553Y225307D01*
X62812Y225575D01*
X63173Y225690D01*
X63535Y225613D01*
X63793Y225422D01*
X63897Y225192D01*
Y224808D01*
X64052Y224463D01*
X64362Y224233D01*
X64723Y224157D01*
X65085Y224233D01*
X65343Y224425D01*
X65498Y224732D01*
X65550Y225000D01*
G01X65085Y227257D02*
X65343Y227487D01*
X65498Y227755D01*
X65550Y228100D01*
X65447Y228445D01*
X65240Y228713D01*
X64878Y228905D01*
X64465Y228943D01*
X64052Y228867D01*
X63793Y228675D01*
X63587Y228407D01*
X63535Y228138D01*
X63587Y227870D01*
X63793Y227525D01*
X62450Y227640D01*
Y228675D01*
G01X53050Y219583D02*
X49950D01*
Y220542D01*
X50105Y220848D01*
X50312Y221040D01*
X50725Y221117D01*
X51138Y221040D01*
X51397Y220810D01*
X51552Y220542D01*
Y219583D01*
G01Y220542D02*
X53050Y221117D01*
G01X52430Y222607D02*
X52792Y222837D01*
X52998Y223143D01*
X53050Y223488D01*
X52998Y223795D01*
X52740Y224102D01*
X52430Y224293D01*
X52120Y224332D01*
X51758Y224255D01*
X51500Y223987D01*
X51397Y223718D01*
Y223373D01*
G01Y223718D02*
X51242Y223948D01*
X50983Y224140D01*
X50673Y224217D01*
X50363Y224140D01*
X50105Y223948D01*
X49950Y223603D01*
X50002Y223258D01*
X50208Y222913D01*
G01X53050Y226550D02*
X52998Y226818D01*
X52843Y227125D01*
X52585Y227317D01*
X52223Y227393D01*
X51862Y227317D01*
X51552Y227087D01*
X51397Y226742D01*
Y226358D01*
X51293Y226128D01*
X51035Y225937D01*
X50673Y225860D01*
X50312Y225975D01*
X50053Y226243D01*
X49950Y226550D01*
X50053Y226857D01*
X50312Y227125D01*
X50673Y227240D01*
X51035Y227163D01*
X51293Y226972D01*
X51397Y226742D01*
Y226358D01*
X51552Y226013D01*
X51862Y225783D01*
X52223Y225707D01*
X52585Y225783D01*
X52843Y225975D01*
X52998Y226282D01*
X53050Y226550D01*
G01Y229650D02*
X49950D01*
X50570Y229190D01*
G01X53050D02*
Y230110D01*
G01X48657Y234438D02*
X48887Y234180D01*
X49155Y234025D01*
X49500Y233973D01*
X49845Y234076D01*
X50113Y234283D01*
X50305Y234645D01*
X50343Y235058D01*
X50267Y235471D01*
X50075Y235730D01*
X49807Y235936D01*
X49538Y235988D01*
X49270Y235936D01*
X48925Y235730D01*
X49040Y237073D01*
X50075D01*
G01X60000Y233450D02*
X60268Y233502D01*
X60575Y233657D01*
X60767Y233915D01*
X60843Y234277D01*
X60767Y234638D01*
X60537Y234948D01*
X60192Y235103D01*
X59808D01*
X59578Y235207D01*
X59387Y235465D01*
X59310Y235827D01*
X59425Y236188D01*
X59693Y236447D01*
X60000Y236550D01*
X60307Y236447D01*
X60575Y236188D01*
X60690Y235827D01*
X60613Y235465D01*
X60422Y235207D01*
X60192Y235103D01*
X59808D01*
X59463Y234948D01*
X59233Y234638D01*
X59157Y234277D01*
X59233Y233915D01*
X59425Y233657D01*
X59732Y233502D01*
X60000Y233450D01*
G01X55950Y221350D02*
X59050D01*
G01X55950Y220468D02*
Y222232D01*
G01X59050Y223683D02*
X55950D01*
Y224603D01*
X56105Y224910D01*
X56467Y225140D01*
X56880Y225217D01*
X57293Y225140D01*
X57603Y224948D01*
X57758Y224603D01*
Y223683D01*
G01X56467Y226822D02*
X56157Y227052D01*
X56002Y227320D01*
X55950Y227627D01*
X56053Y228010D01*
X56312Y228278D01*
X56622Y228355D01*
X56932Y228317D01*
X57190Y228163D01*
X57707Y227397D01*
X58068Y227052D01*
X58585Y226822D01*
X59050Y226745D01*
Y228355D01*
G01Y230650D02*
X58998Y230918D01*
X58843Y231225D01*
X58585Y231417D01*
X58223Y231493D01*
X57862Y231417D01*
X57552Y231187D01*
X57397Y230842D01*
Y230458D01*
X57293Y230228D01*
X57035Y230037D01*
X56673Y229960D01*
X56312Y230075D01*
X56053Y230343D01*
X55950Y230650D01*
X56053Y230957D01*
X56312Y231225D01*
X56673Y231340D01*
X57035Y231263D01*
X57293Y231072D01*
X57397Y230842D01*
Y230458D01*
X57552Y230113D01*
X57862Y229883D01*
X58223Y229807D01*
X58585Y229883D01*
X58843Y230075D01*
X58998Y230382D01*
X59050Y230650D01*
G01X50460Y248973D02*
Y252073D01*
X49042Y249851D01*
X50958D01*
G01X53174Y238577D02*
X55396D01*
X55861Y238730D01*
X56171Y239037D01*
X56274Y239420D01*
X56171Y239803D01*
X55861Y240110D01*
X55396Y240263D01*
X53174D01*
G01X56274Y242520D02*
X53174D01*
X53794Y242060D01*
G01X56274D02*
Y242980D01*
G01X55809Y244777D02*
X56067Y245007D01*
X56222Y245275D01*
X56274Y245620D01*
X56171Y245965D01*
X55964Y246233D01*
X55602Y246425D01*
X55189Y246463D01*
X54776Y246387D01*
X54517Y246195D01*
X54311Y245927D01*
X54259Y245658D01*
X54311Y245390D01*
X54517Y245045D01*
X53174Y245160D01*
Y246195D01*
G01X47422Y269335D02*
X47192Y269490D01*
X46924Y269593D01*
X46617D01*
X46272Y269438D01*
X46004Y269180D01*
X45812Y268870D01*
X45659Y268353D01*
X45621Y267888D01*
X45697Y267423D01*
X45812Y267113D01*
X46042Y266803D01*
X46311Y266596D01*
X46579Y266493D01*
X46847D01*
X47116Y266596D01*
X47346Y266751D01*
X47537Y266958D01*
G01X48836Y267113D02*
X49066Y266751D01*
X49372Y266545D01*
X49717Y266493D01*
X50024Y266545D01*
X50331Y266803D01*
X50522Y267113D01*
X50561Y267423D01*
X50484Y267785D01*
X50216Y268043D01*
X49947Y268146D01*
X49602D01*
G01X49947D02*
X50177Y268301D01*
X50369Y268560D01*
X50446Y268870D01*
X50369Y269180D01*
X50177Y269438D01*
X49832Y269593D01*
X49487Y269541D01*
X49142Y269335D01*
G01X52779Y266493D02*
Y269593D01*
X52319Y268973D01*
G01Y266493D02*
X53239D01*
G01X55802D02*
X55879Y267165D01*
X55994Y267733D01*
X56147Y268250D01*
X56339Y268818D01*
X56646Y269593D01*
X55112D01*
G01X59350Y253583D02*
X56250D01*
Y254542D01*
X56405Y254848D01*
X56612Y255040D01*
X57025Y255117D01*
X57438Y255040D01*
X57697Y254810D01*
X57852Y254542D01*
Y253583D01*
G01Y254542D02*
X59350Y255117D01*
G01X58730Y256607D02*
X59092Y256837D01*
X59298Y257143D01*
X59350Y257488D01*
X59298Y257795D01*
X59040Y258102D01*
X58730Y258293D01*
X58420Y258332D01*
X58058Y258255D01*
X57800Y257987D01*
X57697Y257718D01*
Y257373D01*
G01Y257718D02*
X57542Y257948D01*
X57283Y258140D01*
X56973Y258217D01*
X56663Y258140D01*
X56405Y257948D01*
X56250Y257603D01*
X56302Y257258D01*
X56508Y256913D01*
G01X58058Y259822D02*
X57697Y260090D01*
X57490Y260320D01*
X57387Y260627D01*
X57490Y260895D01*
X57697Y261087D01*
X58007Y261240D01*
X58368Y261278D01*
X58678Y261240D01*
X58988Y261087D01*
X59247Y260857D01*
X59350Y260588D01*
X59247Y260282D01*
X58937Y260013D01*
X58472Y259860D01*
X57955Y259822D01*
X57283Y259898D01*
X56922Y260013D01*
X56560Y260205D01*
X56302Y260473D01*
X56250Y260742D01*
X56353Y261010D01*
X56612Y261202D01*
G01X59350Y263650D02*
X56250D01*
X56870Y263190D01*
G01X59350D02*
Y264110D01*
G01X62481Y264850D02*
Y267950D01*
X63440D01*
X63746Y267795D01*
X63938Y267588D01*
X64015Y267175D01*
X63938Y266762D01*
X63708Y266503D01*
X63440Y266348D01*
X62481D01*
G01X63440D02*
X64015Y264850D01*
G01X66271D02*
X66348Y265522D01*
X66463Y266090D01*
X66616Y266607D01*
X66808Y267175D01*
X67115Y267950D01*
X65581D01*
G01X68720Y267433D02*
X68950Y267743D01*
X69218Y267898D01*
X69525Y267950D01*
X69908Y267847D01*
X70176Y267588D01*
X70253Y267278D01*
X70215Y266968D01*
X70061Y266710D01*
X69295Y266193D01*
X68950Y265832D01*
X68720Y265315D01*
X68643Y264850D01*
X70253D01*
G01X62481Y269350D02*
Y272450D01*
X63440D01*
X63746Y272295D01*
X63938Y272088D01*
X64015Y271675D01*
X63938Y271262D01*
X63708Y271003D01*
X63440Y270848D01*
X62481D01*
G01X63440D02*
X64015Y269350D01*
G01X66271D02*
X66348Y270022D01*
X66463Y270590D01*
X66616Y271107D01*
X66808Y271675D01*
X67115Y272450D01*
X65581D01*
G01X69448D02*
X69141Y272347D01*
X68911Y272088D01*
X68758Y271778D01*
X68643Y271365D01*
X68605Y270900D01*
X68643Y270435D01*
X68758Y270022D01*
X68911Y269712D01*
X69141Y269453D01*
X69448Y269350D01*
X69755Y269453D01*
X69985Y269712D01*
X70138Y270022D01*
X70253Y270435D01*
X70291Y270900D01*
X70253Y271365D01*
X70138Y271778D01*
X69985Y272088D01*
X69755Y272347D01*
X69448Y272450D01*
G01X48834Y253583D02*
X45734D01*
Y254542D01*
X45889Y254848D01*
X46096Y255040D01*
X46509Y255117D01*
X46922Y255040D01*
X47181Y254810D01*
X47336Y254542D01*
Y253583D01*
G01Y254542D02*
X48834Y255117D01*
G01X48214Y256607D02*
X48576Y256837D01*
X48782Y257143D01*
X48834Y257488D01*
X48782Y257795D01*
X48524Y258102D01*
X48214Y258293D01*
X47904Y258332D01*
X47542Y258255D01*
X47284Y257987D01*
X47181Y257718D01*
Y257373D01*
G01Y257718D02*
X47026Y257948D01*
X46767Y258140D01*
X46457Y258217D01*
X46147Y258140D01*
X45889Y257948D01*
X45734Y257603D01*
X45786Y257258D01*
X45992Y256913D01*
G01X48834Y260473D02*
X48162Y260550D01*
X47594Y260665D01*
X47077Y260818D01*
X46509Y261010D01*
X45734Y261317D01*
Y259783D01*
G01X48834Y263650D02*
X45734D01*
X46354Y263190D01*
G01X48834D02*
Y264110D01*
G01X54550Y253583D02*
X51450D01*
Y254542D01*
X51605Y254848D01*
X51812Y255040D01*
X52225Y255117D01*
X52638Y255040D01*
X52897Y254810D01*
X53052Y254542D01*
Y253583D01*
G01Y254542D02*
X54550Y255117D01*
G01Y257450D02*
X51450D01*
X52070Y256990D01*
G01X54550D02*
Y257910D01*
G01X51967Y259822D02*
X51657Y260052D01*
X51502Y260320D01*
X51450Y260627D01*
X51553Y261010D01*
X51812Y261278D01*
X52122Y261355D01*
X52432Y261317D01*
X52690Y261163D01*
X53207Y260397D01*
X53568Y260052D01*
X54085Y259822D01*
X54550Y259745D01*
Y261355D01*
G01X51450Y263650D02*
X51553Y263343D01*
X51812Y263113D01*
X52122Y262960D01*
X52535Y262845D01*
X53000Y262807D01*
X53465Y262845D01*
X53878Y262960D01*
X54188Y263113D01*
X54447Y263343D01*
X54550Y263650D01*
X54447Y263957D01*
X54188Y264187D01*
X53878Y264340D01*
X53465Y264455D01*
X53000Y264493D01*
X52535Y264455D01*
X52122Y264340D01*
X51812Y264187D01*
X51553Y263957D01*
X51450Y263650D01*
G01X60931Y260366D02*
Y263466D01*
X61890D01*
X62196Y263311D01*
X62388Y263104D01*
X62465Y262691D01*
X62388Y262278D01*
X62158Y262019D01*
X61890Y261864D01*
X60931D01*
G01X61890D02*
X62465Y260366D01*
G01X63955Y260986D02*
X64185Y260624D01*
X64491Y260418D01*
X64836Y260366D01*
X65143Y260418D01*
X65450Y260676D01*
X65641Y260986D01*
X65680Y261296D01*
X65603Y261658D01*
X65335Y261916D01*
X65066Y262019D01*
X64721D01*
G01X65066D02*
X65296Y262174D01*
X65488Y262433D01*
X65565Y262743D01*
X65488Y263053D01*
X65296Y263311D01*
X64951Y263466D01*
X64606Y263414D01*
X64261Y263208D01*
G01X68358Y260366D02*
Y263466D01*
X66940Y261244D01*
X68856D01*
G01X70921Y260366D02*
X70998Y261038D01*
X71113Y261606D01*
X71266Y262123D01*
X71458Y262691D01*
X71765Y263466D01*
X70231D01*
G01X62850Y256550D02*
Y253450D01*
G01X61968Y256550D02*
X63732D01*
G01X65183Y253450D02*
Y256550D01*
X66103D01*
X66410Y256395D01*
X66640Y256033D01*
X66717Y255620D01*
X66640Y255207D01*
X66448Y254897D01*
X66103Y254742D01*
X65183D01*
G01X68207Y254070D02*
X68437Y253708D01*
X68743Y253502D01*
X69088Y253450D01*
X69395Y253502D01*
X69702Y253760D01*
X69893Y254070D01*
X69932Y254380D01*
X69855Y254742D01*
X69587Y255000D01*
X69318Y255103D01*
X68973D01*
G01X69318D02*
X69548Y255258D01*
X69740Y255517D01*
X69817Y255827D01*
X69740Y256137D01*
X69548Y256395D01*
X69203Y256550D01*
X68858Y256498D01*
X68513Y256292D01*
G01X71422Y256033D02*
X71652Y256343D01*
X71920Y256498D01*
X72227Y256550D01*
X72610Y256447D01*
X72878Y256188D01*
X72955Y255878D01*
X72917Y255568D01*
X72763Y255310D01*
X71997Y254793D01*
X71652Y254432D01*
X71422Y253915D01*
X71345Y253450D01*
X72955D01*
G01X57083Y277450D02*
Y280550D01*
X58042D01*
X58348Y280395D01*
X58540Y280188D01*
X58617Y279775D01*
X58540Y279362D01*
X58310Y279103D01*
X58042Y278948D01*
X57083D01*
G01X58042D02*
X58617Y277450D01*
G01X60107Y278070D02*
X60337Y277708D01*
X60643Y277502D01*
X60988Y277450D01*
X61295Y277502D01*
X61602Y277760D01*
X61793Y278070D01*
X61832Y278380D01*
X61755Y278742D01*
X61487Y279000D01*
X61218Y279103D01*
X60873D01*
G01X61218D02*
X61448Y279258D01*
X61640Y279517D01*
X61717Y279827D01*
X61640Y280137D01*
X61448Y280395D01*
X61103Y280550D01*
X60758Y280498D01*
X60413Y280292D01*
G01X64510Y277450D02*
Y280550D01*
X63092Y278328D01*
X65008D01*
G01X66422Y278742D02*
X66690Y279103D01*
X66920Y279310D01*
X67227Y279413D01*
X67495Y279310D01*
X67687Y279103D01*
X67840Y278793D01*
X67878Y278432D01*
X67840Y278122D01*
X67687Y277812D01*
X67457Y277553D01*
X67188Y277450D01*
X66882Y277553D01*
X66613Y277863D01*
X66460Y278328D01*
X66422Y278845D01*
X66498Y279517D01*
X66613Y279878D01*
X66805Y280240D01*
X67073Y280498D01*
X67342Y280550D01*
X67610Y280447D01*
X67802Y280188D01*
G01X59533Y293091D02*
Y289991D01*
G01X58651Y293091D02*
X60415D01*
G01X61866Y289991D02*
Y293091D01*
X62786D01*
X63093Y292936D01*
X63323Y292574D01*
X63400Y292161D01*
X63323Y291748D01*
X63131Y291438D01*
X62786Y291283D01*
X61866D01*
G01X65005Y292574D02*
X65235Y292884D01*
X65503Y293039D01*
X65810Y293091D01*
X66193Y292988D01*
X66461Y292729D01*
X66538Y292419D01*
X66500Y292109D01*
X66346Y291851D01*
X65580Y291334D01*
X65235Y290973D01*
X65005Y290456D01*
X64928Y289991D01*
X66538D01*
G01X69293D02*
Y293091D01*
X67875Y290869D01*
X69791D01*
G01X55583Y327966D02*
Y331066D01*
X56542D01*
X56848Y330911D01*
X57040Y330704D01*
X57117Y330291D01*
X57040Y329878D01*
X56810Y329619D01*
X56542Y329464D01*
X55583D01*
G01X56542D02*
X57117Y327966D01*
G01X59910D02*
Y331066D01*
X58492Y328844D01*
X60408D01*
G01X63010Y327966D02*
Y331066D01*
X61592Y328844D01*
X63508D01*
G01X64807Y328431D02*
X65037Y328173D01*
X65305Y328018D01*
X65650Y327966D01*
X65995Y328069D01*
X66263Y328276D01*
X66455Y328638D01*
X66493Y329051D01*
X66417Y329464D01*
X66225Y329723D01*
X65957Y329929D01*
X65688Y329981D01*
X65420Y329929D01*
X65075Y329723D01*
X65190Y331066D01*
X66225D01*
G01X53707Y335644D02*
X53552Y335797D01*
X53293Y335912D01*
X52932Y335989D01*
X52622Y335912D01*
X52415Y335759D01*
X52260Y335490D01*
Y334455D01*
X55360D01*
Y335720D01*
X55153Y335989D01*
X54843Y336142D01*
X54482Y336219D01*
X54120Y336142D01*
X53810Y335912D01*
X53707Y335644D01*
Y334455D01*
G01X55360Y338437D02*
X52260D01*
X52880Y337977D01*
G01X55360D02*
Y338897D01*
G01X60534Y352083D02*
X57434D01*
Y353042D01*
X57589Y353348D01*
X57796Y353540D01*
X58209Y353617D01*
X58622Y353540D01*
X58881Y353310D01*
X59036Y353042D01*
Y352083D01*
G01Y353042D02*
X60534Y353617D01*
G01Y356410D02*
X57434D01*
X59656Y354992D01*
Y356908D01*
G01X60534Y359510D02*
X57434D01*
X59656Y358092D01*
Y360008D01*
G01X57951Y361422D02*
X57641Y361652D01*
X57486Y361920D01*
X57434Y362227D01*
X57537Y362610D01*
X57796Y362878D01*
X58106Y362955D01*
X58416Y362917D01*
X58674Y362763D01*
X59191Y361997D01*
X59552Y361652D01*
X60069Y361422D01*
X60534Y361345D01*
Y362955D01*
G01X55487Y343719D02*
X52387Y344677D01*
X55487Y345635D01*
G01X54402Y345290D02*
Y344064D01*
G01X55487Y347777D02*
X52387D01*
X53007Y347317D01*
G01X55487D02*
Y348237D01*
G01X52904Y350149D02*
X52594Y350379D01*
X52439Y350647D01*
X52387Y350954D01*
X52490Y351337D01*
X52749Y351605D01*
X53059Y351682D01*
X53369Y351644D01*
X53627Y351490D01*
X54144Y350724D01*
X54505Y350379D01*
X55022Y350149D01*
X55487Y350072D01*
Y351682D01*
G01X55467Y383552D02*
X58567D01*
Y385086D01*
G01X55984Y386691D02*
X55674Y386921D01*
X55519Y387189D01*
X55467Y387496D01*
X55570Y387879D01*
X55829Y388147D01*
X56139Y388224D01*
X56449Y388186D01*
X56707Y388032D01*
X57224Y387266D01*
X57585Y386921D01*
X58102Y386691D01*
X58567Y386614D01*
Y388224D01*
G01X55467Y390519D02*
X55570Y390212D01*
X55829Y389982D01*
X56139Y389829D01*
X56552Y389714D01*
X57017Y389676D01*
X57482Y389714D01*
X57895Y389829D01*
X58205Y389982D01*
X58464Y390212D01*
X58567Y390519D01*
X58464Y390826D01*
X58205Y391056D01*
X57895Y391209D01*
X57482Y391324D01*
X57017Y391362D01*
X56552Y391324D01*
X56139Y391209D01*
X55829Y391056D01*
X55570Y390826D01*
X55467Y390519D01*
G01X71433Y63591D02*
Y60491D01*
G01X70551Y63591D02*
X72315D01*
G01X73766Y60491D02*
Y63591D01*
X74686D01*
X74993Y63436D01*
X75223Y63074D01*
X75300Y62661D01*
X75223Y62248D01*
X75031Y61938D01*
X74686Y61783D01*
X73766D01*
G01X76905Y63074D02*
X77135Y63384D01*
X77403Y63539D01*
X77710Y63591D01*
X78093Y63488D01*
X78361Y63229D01*
X78438Y62919D01*
X78400Y62609D01*
X78246Y62351D01*
X77480Y61834D01*
X77135Y61473D01*
X76905Y60956D01*
X76828Y60491D01*
X78438D01*
G01X80733Y63591D02*
X80426Y63488D01*
X80196Y63229D01*
X80043Y62919D01*
X79928Y62506D01*
X79890Y62041D01*
X79928Y61576D01*
X80043Y61163D01*
X80196Y60853D01*
X80426Y60594D01*
X80733Y60491D01*
X81040Y60594D01*
X81270Y60853D01*
X81423Y61163D01*
X81538Y61576D01*
X81576Y62041D01*
X81538Y62506D01*
X81423Y62919D01*
X81270Y63229D01*
X81040Y63488D01*
X80733Y63591D01*
G01X73334Y64107D02*
X73592Y64337D01*
X73747Y64605D01*
X73799Y64950D01*
X73696Y65295D01*
X73489Y65563D01*
X73127Y65755D01*
X72714Y65793D01*
X72301Y65717D01*
X72042Y65525D01*
X71836Y65257D01*
X71784Y64988D01*
X71836Y64720D01*
X72042Y64375D01*
X70699Y64490D01*
Y65525D01*
G01X82099Y64950D02*
X82047Y65218D01*
X81892Y65525D01*
X81634Y65717D01*
X81272Y65793D01*
X80911Y65717D01*
X80601Y65487D01*
X80446Y65142D01*
Y64758D01*
X80342Y64528D01*
X80084Y64337D01*
X79722Y64260D01*
X79361Y64375D01*
X79102Y64643D01*
X78999Y64950D01*
X79102Y65257D01*
X79361Y65525D01*
X79722Y65640D01*
X80084Y65563D01*
X80342Y65372D01*
X80446Y65142D01*
Y64758D01*
X80601Y64413D01*
X80911Y64183D01*
X81272Y64107D01*
X81634Y64183D01*
X81892Y64375D01*
X82047Y64682D01*
X82099Y64950D01*
G01X76468Y78857D02*
X78690D01*
X79155Y79010D01*
X79465Y79317D01*
X79568Y79700D01*
X79465Y80083D01*
X79155Y80390D01*
X78690Y80543D01*
X76468D01*
G01X79568Y82800D02*
X76468D01*
X77088Y82340D01*
G01X79568D02*
Y83260D01*
G01X79206Y85248D02*
X79465Y85517D01*
X79568Y85823D01*
X79465Y86130D01*
X79155Y86398D01*
X78690Y86590D01*
X78225Y86667D01*
X77656D01*
X77191Y86590D01*
X76778Y86398D01*
X76571Y86168D01*
X76468Y85900D01*
X76571Y85593D01*
X76778Y85363D01*
X77088Y85210D01*
X77501Y85133D01*
X77863Y85210D01*
X78225Y85402D01*
X78431Y85632D01*
X78483Y85900D01*
X78380Y86207D01*
X78121Y86437D01*
X77656Y86667D01*
G01X74583Y109482D02*
Y112582D01*
X75542D01*
X75848Y112427D01*
X76040Y112220D01*
X76117Y111807D01*
X76040Y111394D01*
X75810Y111135D01*
X75542Y110980D01*
X74583D01*
G01X75542D02*
X76117Y109482D01*
G01X77722Y112065D02*
X77952Y112375D01*
X78220Y112530D01*
X78527Y112582D01*
X78910Y112479D01*
X79178Y112220D01*
X79255Y111910D01*
X79217Y111600D01*
X79063Y111342D01*
X78297Y110825D01*
X77952Y110464D01*
X77722Y109947D01*
X77645Y109482D01*
X79255D01*
G01X81473D02*
X81550Y110154D01*
X81665Y110722D01*
X81818Y111239D01*
X82010Y111807D01*
X82317Y112582D01*
X80783D01*
G01X83807Y110102D02*
X84037Y109740D01*
X84343Y109534D01*
X84688Y109482D01*
X84995Y109534D01*
X85302Y109792D01*
X85493Y110102D01*
X85532Y110412D01*
X85455Y110774D01*
X85187Y111032D01*
X84918Y111135D01*
X84573D01*
G01X84918D02*
X85148Y111290D01*
X85340Y111549D01*
X85417Y111859D01*
X85340Y112169D01*
X85148Y112427D01*
X84803Y112582D01*
X84458Y112530D01*
X84113Y112324D01*
G01X74583Y104482D02*
Y107582D01*
X75542D01*
X75848Y107427D01*
X76040Y107220D01*
X76117Y106807D01*
X76040Y106394D01*
X75810Y106135D01*
X75542Y105980D01*
X74583D01*
G01X75542D02*
X76117Y104482D01*
G01X77607Y105102D02*
X77837Y104740D01*
X78143Y104534D01*
X78488Y104482D01*
X78795Y104534D01*
X79102Y104792D01*
X79293Y105102D01*
X79332Y105412D01*
X79255Y105774D01*
X78987Y106032D01*
X78718Y106135D01*
X78373D01*
G01X78718D02*
X78948Y106290D01*
X79140Y106549D01*
X79217Y106859D01*
X79140Y107169D01*
X78948Y107427D01*
X78603Y107582D01*
X78258Y107530D01*
X77913Y107324D01*
G01X81550Y104482D02*
X81818Y104534D01*
X82125Y104689D01*
X82317Y104947D01*
X82393Y105309D01*
X82317Y105670D01*
X82087Y105980D01*
X81742Y106135D01*
X81358D01*
X81128Y106239D01*
X80937Y106497D01*
X80860Y106859D01*
X80975Y107220D01*
X81243Y107479D01*
X81550Y107582D01*
X81857Y107479D01*
X82125Y107220D01*
X82240Y106859D01*
X82163Y106497D01*
X81972Y106239D01*
X81742Y106135D01*
X81358D01*
X81013Y105980D01*
X80783Y105670D01*
X80707Y105309D01*
X80783Y104947D01*
X80975Y104689D01*
X81282Y104534D01*
X81550Y104482D01*
G01X84650D02*
X84918Y104534D01*
X85225Y104689D01*
X85417Y104947D01*
X85493Y105309D01*
X85417Y105670D01*
X85187Y105980D01*
X84842Y106135D01*
X84458D01*
X84228Y106239D01*
X84037Y106497D01*
X83960Y106859D01*
X84075Y107220D01*
X84343Y107479D01*
X84650Y107582D01*
X84957Y107479D01*
X85225Y107220D01*
X85340Y106859D01*
X85263Y106497D01*
X85072Y106239D01*
X84842Y106135D01*
X84458D01*
X84113Y105980D01*
X83883Y105670D01*
X83807Y105309D01*
X83883Y104947D01*
X84075Y104689D01*
X84382Y104534D01*
X84650Y104482D01*
G01X74099Y102810D02*
X70999D01*
X73221Y101392D01*
Y103308D01*
G01X74583Y119482D02*
Y122582D01*
X75542D01*
X75848Y122427D01*
X76040Y122220D01*
X76117Y121807D01*
X76040Y121394D01*
X75810Y121135D01*
X75542Y120980D01*
X74583D01*
G01X75542D02*
X76117Y119482D01*
G01X77607Y120102D02*
X77837Y119740D01*
X78143Y119534D01*
X78488Y119482D01*
X78795Y119534D01*
X79102Y119792D01*
X79293Y120102D01*
X79332Y120412D01*
X79255Y120774D01*
X78987Y121032D01*
X78718Y121135D01*
X78373D01*
G01X78718D02*
X78948Y121290D01*
X79140Y121549D01*
X79217Y121859D01*
X79140Y122169D01*
X78948Y122427D01*
X78603Y122582D01*
X78258Y122530D01*
X77913Y122324D01*
G01X80898Y119844D02*
X81167Y119585D01*
X81473Y119482D01*
X81780Y119585D01*
X82048Y119895D01*
X82240Y120360D01*
X82317Y120825D01*
Y121394D01*
X82240Y121859D01*
X82048Y122272D01*
X81818Y122479D01*
X81550Y122582D01*
X81243Y122479D01*
X81013Y122272D01*
X80860Y121962D01*
X80783Y121549D01*
X80860Y121187D01*
X81052Y120825D01*
X81282Y120619D01*
X81550Y120567D01*
X81857Y120670D01*
X82087Y120929D01*
X82317Y121394D01*
G01X84650Y122582D02*
X84343Y122479D01*
X84113Y122220D01*
X83960Y121910D01*
X83845Y121497D01*
X83807Y121032D01*
X83845Y120567D01*
X83960Y120154D01*
X84113Y119844D01*
X84343Y119585D01*
X84650Y119482D01*
X84957Y119585D01*
X85187Y119844D01*
X85340Y120154D01*
X85455Y120567D01*
X85493Y121032D01*
X85455Y121497D01*
X85340Y121910D01*
X85187Y122220D01*
X84957Y122479D01*
X84650Y122582D01*
G01X74583Y124482D02*
Y127582D01*
X75542D01*
X75848Y127427D01*
X76040Y127220D01*
X76117Y126807D01*
X76040Y126394D01*
X75810Y126135D01*
X75542Y125980D01*
X74583D01*
G01X75542D02*
X76117Y124482D01*
G01X77722Y127065D02*
X77952Y127375D01*
X78220Y127530D01*
X78527Y127582D01*
X78910Y127479D01*
X79178Y127220D01*
X79255Y126910D01*
X79217Y126600D01*
X79063Y126342D01*
X78297Y125825D01*
X77952Y125464D01*
X77722Y124947D01*
X77645Y124482D01*
X79255D01*
G01X81473D02*
X81550Y125154D01*
X81665Y125722D01*
X81818Y126239D01*
X82010Y126807D01*
X82317Y127582D01*
X80783D01*
G01X85110Y124482D02*
Y127582D01*
X83692Y125360D01*
X85608D01*
G01X74583Y129482D02*
Y132582D01*
X75542D01*
X75848Y132427D01*
X76040Y132220D01*
X76117Y131807D01*
X76040Y131394D01*
X75810Y131135D01*
X75542Y130980D01*
X74583D01*
G01X75542D02*
X76117Y129482D01*
G01X77607Y130102D02*
X77837Y129740D01*
X78143Y129534D01*
X78488Y129482D01*
X78795Y129534D01*
X79102Y129792D01*
X79293Y130102D01*
X79332Y130412D01*
X79255Y130774D01*
X78987Y131032D01*
X78718Y131135D01*
X78373D01*
G01X78718D02*
X78948Y131290D01*
X79140Y131549D01*
X79217Y131859D01*
X79140Y132169D01*
X78948Y132427D01*
X78603Y132582D01*
X78258Y132530D01*
X77913Y132324D01*
G01X81550Y129482D02*
X81818Y129534D01*
X82125Y129689D01*
X82317Y129947D01*
X82393Y130309D01*
X82317Y130670D01*
X82087Y130980D01*
X81742Y131135D01*
X81358D01*
X81128Y131239D01*
X80937Y131497D01*
X80860Y131859D01*
X80975Y132220D01*
X81243Y132479D01*
X81550Y132582D01*
X81857Y132479D01*
X82125Y132220D01*
X82240Y131859D01*
X82163Y131497D01*
X81972Y131239D01*
X81742Y131135D01*
X81358D01*
X81013Y130980D01*
X80783Y130670D01*
X80707Y130309D01*
X80783Y129947D01*
X80975Y129689D01*
X81282Y129534D01*
X81550Y129482D01*
G01X83998Y129844D02*
X84267Y129585D01*
X84573Y129482D01*
X84880Y129585D01*
X85148Y129895D01*
X85340Y130360D01*
X85417Y130825D01*
Y131394D01*
X85340Y131859D01*
X85148Y132272D01*
X84918Y132479D01*
X84650Y132582D01*
X84343Y132479D01*
X84113Y132272D01*
X83960Y131962D01*
X83883Y131549D01*
X83960Y131187D01*
X84152Y130825D01*
X84382Y130619D01*
X84650Y130567D01*
X84957Y130670D01*
X85187Y130929D01*
X85417Y131394D01*
G01X74583Y114482D02*
Y117582D01*
X75542D01*
X75848Y117427D01*
X76040Y117220D01*
X76117Y116807D01*
X76040Y116394D01*
X75810Y116135D01*
X75542Y115980D01*
X74583D01*
G01X75542D02*
X76117Y114482D01*
G01X77607Y115102D02*
X77837Y114740D01*
X78143Y114534D01*
X78488Y114482D01*
X78795Y114534D01*
X79102Y114792D01*
X79293Y115102D01*
X79332Y115412D01*
X79255Y115774D01*
X78987Y116032D01*
X78718Y116135D01*
X78373D01*
G01X78718D02*
X78948Y116290D01*
X79140Y116549D01*
X79217Y116859D01*
X79140Y117169D01*
X78948Y117427D01*
X78603Y117582D01*
X78258Y117530D01*
X77913Y117324D01*
G01X81473Y114482D02*
X81550Y115154D01*
X81665Y115722D01*
X81818Y116239D01*
X82010Y116807D01*
X82317Y117582D01*
X80783D01*
G01X83807Y115102D02*
X84037Y114740D01*
X84343Y114534D01*
X84688Y114482D01*
X84995Y114534D01*
X85302Y114792D01*
X85493Y115102D01*
X85532Y115412D01*
X85455Y115774D01*
X85187Y116032D01*
X84918Y116135D01*
X84573D01*
G01X84918D02*
X85148Y116290D01*
X85340Y116549D01*
X85417Y116859D01*
X85340Y117169D01*
X85148Y117427D01*
X84803Y117582D01*
X84458Y117530D01*
X84113Y117324D01*
G01X79880Y140883D02*
X80110Y141193D01*
X80378Y141348D01*
X80685Y141400D01*
X81068Y141297D01*
X81336Y141038D01*
X81413Y140728D01*
X81375Y140418D01*
X81221Y140160D01*
X80455Y139643D01*
X80110Y139282D01*
X79880Y138765D01*
X79803Y138300D01*
X81413D01*
G01X70138Y138169D02*
Y141269D01*
X68720Y139047D01*
X70636D01*
G01X73183Y151570D02*
X73375Y151260D01*
X73605Y151053D01*
X73873Y150950D01*
X74180Y151053D01*
X74410Y151260D01*
X74640Y151570D01*
X74717Y151983D01*
Y154050D01*
G01X76398Y151312D02*
X76667Y151053D01*
X76973Y150950D01*
X77280Y151053D01*
X77548Y151363D01*
X77740Y151828D01*
X77817Y152293D01*
Y152862D01*
X77740Y153327D01*
X77548Y153740D01*
X77318Y153947D01*
X77050Y154050D01*
X76743Y153947D01*
X76513Y153740D01*
X76360Y153430D01*
X76283Y153017D01*
X76360Y152655D01*
X76552Y152293D01*
X76782Y152087D01*
X77050Y152035D01*
X77357Y152138D01*
X77587Y152397D01*
X77817Y152862D01*
G01X71230Y178982D02*
Y182082D01*
X72189D01*
X72495Y181927D01*
X72687Y181720D01*
X72764Y181307D01*
X72687Y180894D01*
X72457Y180635D01*
X72189Y180480D01*
X71230D01*
G01X72189D02*
X72764Y178982D01*
G01X75557D02*
Y182082D01*
X74139Y179860D01*
X76055D01*
G01X78197Y182082D02*
X77890Y181979D01*
X77660Y181720D01*
X77507Y181410D01*
X77392Y180997D01*
X77354Y180532D01*
X77392Y180067D01*
X77507Y179654D01*
X77660Y179344D01*
X77890Y179085D01*
X78197Y178982D01*
X78504Y179085D01*
X78734Y179344D01*
X78887Y179654D01*
X79002Y180067D01*
X79040Y180532D01*
X79002Y180997D01*
X78887Y181410D01*
X78734Y181720D01*
X78504Y181979D01*
X78197Y182082D01*
G01X81297D02*
X80990Y181979D01*
X80760Y181720D01*
X80607Y181410D01*
X80492Y180997D01*
X80454Y180532D01*
X80492Y180067D01*
X80607Y179654D01*
X80760Y179344D01*
X80990Y179085D01*
X81297Y178982D01*
X81604Y179085D01*
X81834Y179344D01*
X81987Y179654D01*
X82102Y180067D01*
X82140Y180532D01*
X82102Y180997D01*
X81987Y181410D01*
X81834Y181720D01*
X81604Y181979D01*
X81297Y182082D01*
G01X71230Y174482D02*
Y177582D01*
X72189D01*
X72495Y177427D01*
X72687Y177220D01*
X72764Y176807D01*
X72687Y176394D01*
X72457Y176135D01*
X72189Y175980D01*
X71230D01*
G01X72189D02*
X72764Y174482D01*
G01X74254Y175102D02*
X74484Y174740D01*
X74790Y174534D01*
X75135Y174482D01*
X75442Y174534D01*
X75749Y174792D01*
X75940Y175102D01*
X75979Y175412D01*
X75902Y175774D01*
X75634Y176032D01*
X75365Y176135D01*
X75020D01*
G01X75365D02*
X75595Y176290D01*
X75787Y176549D01*
X75864Y176859D01*
X75787Y177169D01*
X75595Y177427D01*
X75250Y177582D01*
X74905Y177530D01*
X74560Y177324D01*
G01X77545Y174844D02*
X77814Y174585D01*
X78120Y174482D01*
X78427Y174585D01*
X78695Y174895D01*
X78887Y175360D01*
X78964Y175825D01*
Y176394D01*
X78887Y176859D01*
X78695Y177272D01*
X78465Y177479D01*
X78197Y177582D01*
X77890Y177479D01*
X77660Y177272D01*
X77507Y176962D01*
X77430Y176549D01*
X77507Y176187D01*
X77699Y175825D01*
X77929Y175619D01*
X78197Y175567D01*
X78504Y175670D01*
X78734Y175929D01*
X78964Y176394D01*
G01X81757Y174482D02*
Y177582D01*
X80339Y175360D01*
X82255D01*
G01X70237Y166193D02*
X70467Y165831D01*
X70773Y165625D01*
X71118Y165573D01*
X71425Y165625D01*
X71732Y165883D01*
X71923Y166193D01*
X71962Y166503D01*
X71885Y166865D01*
X71617Y167123D01*
X71348Y167226D01*
X71003D01*
G01X71348D02*
X71578Y167381D01*
X71770Y167640D01*
X71847Y167950D01*
X71770Y168260D01*
X71578Y168518D01*
X71233Y168673D01*
X70888Y168621D01*
X70543Y168415D01*
G01X71230Y192482D02*
Y195582D01*
X72189D01*
X72495Y195427D01*
X72687Y195220D01*
X72764Y194807D01*
X72687Y194394D01*
X72457Y194135D01*
X72189Y193980D01*
X71230D01*
G01X72189D02*
X72764Y192482D01*
G01X74254Y193102D02*
X74484Y192740D01*
X74790Y192534D01*
X75135Y192482D01*
X75442Y192534D01*
X75749Y192792D01*
X75940Y193102D01*
X75979Y193412D01*
X75902Y193774D01*
X75634Y194032D01*
X75365Y194135D01*
X75020D01*
G01X75365D02*
X75595Y194290D01*
X75787Y194549D01*
X75864Y194859D01*
X75787Y195169D01*
X75595Y195427D01*
X75250Y195582D01*
X74905Y195530D01*
X74560Y195324D01*
G01X77545Y192844D02*
X77814Y192585D01*
X78120Y192482D01*
X78427Y192585D01*
X78695Y192895D01*
X78887Y193360D01*
X78964Y193825D01*
Y194394D01*
X78887Y194859D01*
X78695Y195272D01*
X78465Y195479D01*
X78197Y195582D01*
X77890Y195479D01*
X77660Y195272D01*
X77507Y194962D01*
X77430Y194549D01*
X77507Y194187D01*
X77699Y193825D01*
X77929Y193619D01*
X78197Y193567D01*
X78504Y193670D01*
X78734Y193929D01*
X78964Y194394D01*
G01X80454Y192947D02*
X80684Y192689D01*
X80952Y192534D01*
X81297Y192482D01*
X81642Y192585D01*
X81910Y192792D01*
X82102Y193154D01*
X82140Y193567D01*
X82064Y193980D01*
X81872Y194239D01*
X81604Y194445D01*
X81335Y194497D01*
X81067Y194445D01*
X80722Y194239D01*
X80837Y195582D01*
X81872D01*
G01X71230Y196982D02*
Y200082D01*
X72189D01*
X72495Y199927D01*
X72687Y199720D01*
X72764Y199307D01*
X72687Y198894D01*
X72457Y198635D01*
X72189Y198480D01*
X71230D01*
G01X72189D02*
X72764Y196982D01*
G01X75557D02*
Y200082D01*
X74139Y197860D01*
X76055D01*
G01X78197Y200082D02*
X77890Y199979D01*
X77660Y199720D01*
X77507Y199410D01*
X77392Y198997D01*
X77354Y198532D01*
X77392Y198067D01*
X77507Y197654D01*
X77660Y197344D01*
X77890Y197085D01*
X78197Y196982D01*
X78504Y197085D01*
X78734Y197344D01*
X78887Y197654D01*
X79002Y198067D01*
X79040Y198532D01*
X79002Y198997D01*
X78887Y199410D01*
X78734Y199720D01*
X78504Y199979D01*
X78197Y200082D01*
G01X81297Y196982D02*
Y200082D01*
X80837Y199462D01*
G01Y196982D02*
X81757D01*
G01X71230Y187982D02*
Y191082D01*
X72189D01*
X72495Y190927D01*
X72687Y190720D01*
X72764Y190307D01*
X72687Y189894D01*
X72457Y189635D01*
X72189Y189480D01*
X71230D01*
G01X72189D02*
X72764Y187982D01*
G01X74254Y188602D02*
X74484Y188240D01*
X74790Y188034D01*
X75135Y187982D01*
X75442Y188034D01*
X75749Y188292D01*
X75940Y188602D01*
X75979Y188912D01*
X75902Y189274D01*
X75634Y189532D01*
X75365Y189635D01*
X75020D01*
G01X75365D02*
X75595Y189790D01*
X75787Y190049D01*
X75864Y190359D01*
X75787Y190669D01*
X75595Y190927D01*
X75250Y191082D01*
X74905Y191030D01*
X74560Y190824D01*
G01X77545Y188344D02*
X77814Y188085D01*
X78120Y187982D01*
X78427Y188085D01*
X78695Y188395D01*
X78887Y188860D01*
X78964Y189325D01*
Y189894D01*
X78887Y190359D01*
X78695Y190772D01*
X78465Y190979D01*
X78197Y191082D01*
X77890Y190979D01*
X77660Y190772D01*
X77507Y190462D01*
X77430Y190049D01*
X77507Y189687D01*
X77699Y189325D01*
X77929Y189119D01*
X78197Y189067D01*
X78504Y189170D01*
X78734Y189429D01*
X78964Y189894D01*
G01X80569Y189274D02*
X80837Y189635D01*
X81067Y189842D01*
X81374Y189945D01*
X81642Y189842D01*
X81834Y189635D01*
X81987Y189325D01*
X82025Y188964D01*
X81987Y188654D01*
X81834Y188344D01*
X81604Y188085D01*
X81335Y187982D01*
X81029Y188085D01*
X80760Y188395D01*
X80607Y188860D01*
X80569Y189377D01*
X80645Y190049D01*
X80760Y190410D01*
X80952Y190772D01*
X81220Y191030D01*
X81489Y191082D01*
X81757Y190979D01*
X81949Y190720D01*
G01X71230Y183482D02*
Y186582D01*
X72189D01*
X72495Y186427D01*
X72687Y186220D01*
X72764Y185807D01*
X72687Y185394D01*
X72457Y185135D01*
X72189Y184980D01*
X71230D01*
G01X72189D02*
X72764Y183482D01*
G01X75557D02*
Y186582D01*
X74139Y184360D01*
X76055D01*
G01X77469Y186065D02*
X77699Y186375D01*
X77967Y186530D01*
X78274Y186582D01*
X78657Y186479D01*
X78925Y186220D01*
X79002Y185910D01*
X78964Y185600D01*
X78810Y185342D01*
X78044Y184825D01*
X77699Y184464D01*
X77469Y183947D01*
X77392Y183482D01*
X79002D01*
G01X81757D02*
Y186582D01*
X80339Y184360D01*
X82255D01*
G01X70657Y212120D02*
X70887Y211758D01*
X71193Y211552D01*
X71538Y211500D01*
X71845Y211552D01*
X72152Y211810D01*
X72343Y212120D01*
X72382Y212430D01*
X72305Y212792D01*
X72037Y213050D01*
X71768Y213153D01*
X71423D01*
G01X71768D02*
X71998Y213308D01*
X72190Y213567D01*
X72267Y213877D01*
X72190Y214187D01*
X71998Y214445D01*
X71653Y214600D01*
X71308Y214548D01*
X70963Y214342D01*
G01X76633Y208070D02*
X76825Y207760D01*
X77055Y207553D01*
X77323Y207450D01*
X77630Y207553D01*
X77860Y207760D01*
X78090Y208070D01*
X78167Y208483D01*
Y210550D01*
G01X80500Y207450D02*
Y210550D01*
X80040Y209930D01*
G01Y207450D02*
X80960D01*
G01X83600D02*
X83868Y207502D01*
X84175Y207657D01*
X84367Y207915D01*
X84443Y208277D01*
X84367Y208638D01*
X84137Y208948D01*
X83792Y209103D01*
X83408D01*
X83178Y209207D01*
X82987Y209465D01*
X82910Y209827D01*
X83025Y210188D01*
X83293Y210447D01*
X83600Y210550D01*
X83907Y210447D01*
X84175Y210188D01*
X84290Y209827D01*
X84213Y209465D01*
X84022Y209207D01*
X83792Y209103D01*
X83408D01*
X83063Y208948D01*
X82833Y208638D01*
X82757Y208277D01*
X82833Y207915D01*
X83025Y207657D01*
X83332Y207502D01*
X83600Y207450D01*
G01X70108Y223493D02*
X69953Y223263D01*
X69850Y222995D01*
Y222688D01*
X70005Y222343D01*
X70263Y222075D01*
X70573Y221883D01*
X71090Y221730D01*
X71555Y221692D01*
X72020Y221768D01*
X72330Y221883D01*
X72640Y222113D01*
X72847Y222382D01*
X72950Y222650D01*
Y222918D01*
X72847Y223187D01*
X72692Y223417D01*
X72485Y223608D01*
G01X72330Y224907D02*
X72692Y225137D01*
X72898Y225443D01*
X72950Y225788D01*
X72898Y226095D01*
X72640Y226402D01*
X72330Y226593D01*
X72020Y226632D01*
X71658Y226555D01*
X71400Y226287D01*
X71297Y226018D01*
Y225673D01*
G01Y226018D02*
X71142Y226248D01*
X70883Y226440D01*
X70573Y226517D01*
X70263Y226440D01*
X70005Y226248D01*
X69850Y225903D01*
X69902Y225558D01*
X70108Y225213D01*
G01X72950Y228850D02*
X69850D01*
X70470Y228390D01*
G01X72950D02*
Y229310D01*
G01X72330Y231107D02*
X72692Y231337D01*
X72898Y231643D01*
X72950Y231988D01*
X72898Y232295D01*
X72640Y232602D01*
X72330Y232793D01*
X72020Y232832D01*
X71658Y232755D01*
X71400Y232487D01*
X71297Y232218D01*
Y231873D01*
G01Y232218D02*
X71142Y232448D01*
X70883Y232640D01*
X70573Y232717D01*
X70263Y232640D01*
X70005Y232448D01*
X69850Y232103D01*
X69902Y231758D01*
X70108Y231413D01*
G01X70208Y238493D02*
X70053Y238263D01*
X69950Y237995D01*
Y237688D01*
X70105Y237343D01*
X70363Y237075D01*
X70673Y236883D01*
X71190Y236730D01*
X71655Y236692D01*
X72120Y236768D01*
X72430Y236883D01*
X72740Y237113D01*
X72947Y237382D01*
X73050Y237650D01*
Y237918D01*
X72947Y238187D01*
X72792Y238417D01*
X72585Y238608D01*
G01X72430Y239907D02*
X72792Y240137D01*
X72998Y240443D01*
X73050Y240788D01*
X72998Y241095D01*
X72740Y241402D01*
X72430Y241593D01*
X72120Y241632D01*
X71758Y241555D01*
X71500Y241287D01*
X71397Y241018D01*
Y240673D01*
G01Y241018D02*
X71242Y241248D01*
X70983Y241440D01*
X70673Y241517D01*
X70363Y241440D01*
X70105Y241248D01*
X69950Y240903D01*
X70002Y240558D01*
X70208Y240213D01*
G01X73050Y243850D02*
X69950D01*
X70570Y243390D01*
G01X73050D02*
Y244310D01*
G01X70467Y246222D02*
X70157Y246452D01*
X70002Y246720D01*
X69950Y247027D01*
X70053Y247410D01*
X70312Y247678D01*
X70622Y247755D01*
X70932Y247717D01*
X71190Y247563D01*
X71707Y246797D01*
X72068Y246452D01*
X72585Y246222D01*
X73050Y246145D01*
Y247755D01*
G01X78550Y247583D02*
X75450D01*
Y248542D01*
X75605Y248848D01*
X75812Y249040D01*
X76225Y249117D01*
X76638Y249040D01*
X76897Y248810D01*
X77052Y248542D01*
Y247583D01*
G01Y248542D02*
X78550Y249117D01*
G01X77930Y250607D02*
X78292Y250837D01*
X78498Y251143D01*
X78550Y251488D01*
X78498Y251795D01*
X78240Y252102D01*
X77930Y252293D01*
X77620Y252332D01*
X77258Y252255D01*
X77000Y251987D01*
X76897Y251718D01*
Y251373D01*
G01Y251718D02*
X76742Y251948D01*
X76483Y252140D01*
X76173Y252217D01*
X75863Y252140D01*
X75605Y251948D01*
X75450Y251603D01*
X75502Y251258D01*
X75708Y250913D01*
G01X78085Y253707D02*
X78343Y253937D01*
X78498Y254205D01*
X78550Y254550D01*
X78447Y254895D01*
X78240Y255163D01*
X77878Y255355D01*
X77465Y255393D01*
X77052Y255317D01*
X76793Y255125D01*
X76587Y254857D01*
X76535Y254588D01*
X76587Y254320D01*
X76793Y253975D01*
X75450Y254090D01*
Y255125D01*
G01Y257650D02*
X75553Y257343D01*
X75812Y257113D01*
X76122Y256960D01*
X76535Y256845D01*
X77000Y256807D01*
X77465Y256845D01*
X77878Y256960D01*
X78188Y257113D01*
X78447Y257343D01*
X78550Y257650D01*
X78447Y257957D01*
X78188Y258187D01*
X77878Y258340D01*
X77465Y258455D01*
X77000Y258493D01*
X76535Y258455D01*
X76122Y258340D01*
X75812Y258187D01*
X75553Y257957D01*
X75450Y257650D01*
G01X76000Y241450D02*
X76268Y241502D01*
X76575Y241657D01*
X76767Y241915D01*
X76843Y242277D01*
X76767Y242638D01*
X76537Y242948D01*
X76192Y243103D01*
X75808D01*
X75578Y243207D01*
X75387Y243465D01*
X75310Y243827D01*
X75425Y244188D01*
X75693Y244447D01*
X76000Y244550D01*
X76307Y244447D01*
X76575Y244188D01*
X76690Y243827D01*
X76613Y243465D01*
X76422Y243207D01*
X76192Y243103D01*
X75808D01*
X75463Y242948D01*
X75233Y242638D01*
X75157Y242277D01*
X75233Y241915D01*
X75425Y241657D01*
X75732Y241502D01*
X76000Y241450D01*
G01X80923Y258000D02*
X81000Y258672D01*
X81115Y259240D01*
X81268Y259757D01*
X81460Y260325D01*
X81767Y261100D01*
X80233D01*
G01X71657Y269620D02*
X71887Y269258D01*
X72193Y269052D01*
X72538Y269000D01*
X72845Y269052D01*
X73152Y269310D01*
X73343Y269620D01*
X73382Y269930D01*
X73305Y270292D01*
X73037Y270550D01*
X72768Y270653D01*
X72423D01*
G01X72768D02*
X72998Y270808D01*
X73190Y271067D01*
X73267Y271377D01*
X73190Y271687D01*
X72998Y271945D01*
X72653Y272100D01*
X72308Y272048D01*
X71963Y271842D01*
G01X72772Y259292D02*
X73040Y259653D01*
X73270Y259860D01*
X73577Y259963D01*
X73845Y259860D01*
X74037Y259653D01*
X74190Y259343D01*
X74228Y258982D01*
X74190Y258672D01*
X74037Y258362D01*
X73807Y258103D01*
X73538Y258000D01*
X73232Y258103D01*
X72963Y258413D01*
X72810Y258878D01*
X72772Y259395D01*
X72848Y260067D01*
X72963Y260428D01*
X73155Y260790D01*
X73423Y261048D01*
X73692Y261100D01*
X73960Y260997D01*
X74152Y260738D01*
G01X72657Y262965D02*
X72887Y262707D01*
X73155Y262552D01*
X73500Y262500D01*
X73845Y262603D01*
X74113Y262810D01*
X74305Y263172D01*
X74343Y263585D01*
X74267Y263998D01*
X74075Y264257D01*
X73807Y264463D01*
X73538Y264515D01*
X73270Y264463D01*
X72925Y264257D01*
X73040Y265600D01*
X74075D01*
G01X75005Y267650D02*
Y265428D01*
X75158Y264963D01*
X75465Y264653D01*
X75848Y264550D01*
X76231Y264653D01*
X76538Y264963D01*
X76691Y265428D01*
Y267650D01*
G01X78220Y267133D02*
X78450Y267443D01*
X78718Y267598D01*
X79025Y267650D01*
X79408Y267547D01*
X79676Y267288D01*
X79753Y266978D01*
X79715Y266668D01*
X79561Y266410D01*
X78795Y265893D01*
X78450Y265532D01*
X78220Y265015D01*
X78143Y264550D01*
X79753D01*
G01X82048D02*
X82316Y264602D01*
X82623Y264757D01*
X82815Y265015D01*
X82891Y265377D01*
X82815Y265738D01*
X82585Y266048D01*
X82240Y266203D01*
X81856D01*
X81626Y266307D01*
X81435Y266565D01*
X81358Y266927D01*
X81473Y267288D01*
X81741Y267547D01*
X82048Y267650D01*
X82355Y267547D01*
X82623Y267288D01*
X82738Y266927D01*
X82661Y266565D01*
X82470Y266307D01*
X82240Y266203D01*
X81856D01*
X81511Y266048D01*
X81281Y265738D01*
X81205Y265377D01*
X81281Y265015D01*
X81473Y264757D01*
X81780Y264602D01*
X82048Y264550D01*
G01X69633Y277450D02*
Y280550D01*
X70592D01*
X70898Y280395D01*
X71090Y280188D01*
X71167Y279775D01*
X71090Y279362D01*
X70860Y279103D01*
X70592Y278948D01*
X69633D01*
G01X70592D02*
X71167Y277450D01*
G01X73423D02*
X73500Y278122D01*
X73615Y278690D01*
X73768Y279207D01*
X73960Y279775D01*
X74267Y280550D01*
X72733D01*
G01X75757Y278070D02*
X75987Y277708D01*
X76293Y277502D01*
X76638Y277450D01*
X76945Y277502D01*
X77252Y277760D01*
X77443Y278070D01*
X77482Y278380D01*
X77405Y278742D01*
X77137Y279000D01*
X76868Y279103D01*
X76523D01*
G01X76868D02*
X77098Y279258D01*
X77290Y279517D01*
X77367Y279827D01*
X77290Y280137D01*
X77098Y280395D01*
X76753Y280550D01*
X76408Y280498D01*
X76063Y280292D01*
G01X82550Y277133D02*
X79450D01*
Y278092D01*
X79605Y278398D01*
X79812Y278590D01*
X80225Y278667D01*
X80638Y278590D01*
X80897Y278360D01*
X81052Y278092D01*
Y277133D01*
G01Y278092D02*
X82550Y278667D01*
G01Y280923D02*
X81878Y281000D01*
X81310Y281115D01*
X80793Y281268D01*
X80225Y281460D01*
X79450Y281767D01*
Y280233D01*
G01X82550Y284100D02*
X79450D01*
X80070Y283640D01*
G01X82550D02*
Y284560D01*
G01X75772Y274083D02*
X76002Y274393D01*
X76270Y274548D01*
X76577Y274600D01*
X76960Y274497D01*
X77228Y274238D01*
X77305Y273928D01*
X77267Y273618D01*
X77113Y273360D01*
X76347Y272843D01*
X76002Y272482D01*
X75772Y271965D01*
X75695Y271500D01*
X77305D01*
G01X67083Y318966D02*
Y322066D01*
X68042D01*
X68348Y321911D01*
X68540Y321704D01*
X68617Y321291D01*
X68540Y320878D01*
X68310Y320619D01*
X68042Y320464D01*
X67083D01*
G01X68042D02*
X68617Y318966D01*
G01X71410D02*
Y322066D01*
X69992Y319844D01*
X71908D01*
G01X73973Y318966D02*
X74050Y319638D01*
X74165Y320206D01*
X74318Y320723D01*
X74510Y321291D01*
X74817Y322066D01*
X73283D01*
G01X76422Y321549D02*
X76652Y321859D01*
X76920Y322014D01*
X77227Y322066D01*
X77610Y321963D01*
X77878Y321704D01*
X77955Y321394D01*
X77917Y321084D01*
X77763Y320826D01*
X76997Y320309D01*
X76652Y319948D01*
X76422Y319431D01*
X76345Y318966D01*
X77955D01*
G01X75708Y334661D02*
X75938Y334299D01*
X76244Y334093D01*
X76589Y334041D01*
X76896Y334093D01*
X77203Y334351D01*
X77394Y334661D01*
X77433Y334971D01*
X77356Y335333D01*
X77088Y335591D01*
X76819Y335694D01*
X76474D01*
G01X76819D02*
X77049Y335849D01*
X77241Y336108D01*
X77318Y336418D01*
X77241Y336728D01*
X77049Y336986D01*
X76704Y337141D01*
X76359Y337089D01*
X76014Y336883D01*
G01X67083Y323466D02*
Y326566D01*
X68042D01*
X68348Y326411D01*
X68540Y326204D01*
X68617Y325791D01*
X68540Y325378D01*
X68310Y325119D01*
X68042Y324964D01*
X67083D01*
G01X68042D02*
X68617Y323466D01*
G01X71410D02*
Y326566D01*
X69992Y324344D01*
X71908D01*
G01X73973Y323466D02*
X74050Y324138D01*
X74165Y324706D01*
X74318Y325223D01*
X74510Y325791D01*
X74817Y326566D01*
X73283D01*
G01X77150Y323466D02*
Y326566D01*
X76690Y325946D01*
G01Y323466D02*
X77610D01*
G01X69418Y341057D02*
X71640D01*
X72105Y341210D01*
X72415Y341517D01*
X72518Y341900D01*
X72415Y342283D01*
X72105Y342590D01*
X71640Y342743D01*
X69418D01*
G01X72518Y345000D02*
X69418D01*
X70038Y344540D01*
G01X72518D02*
Y345460D01*
G01Y348023D02*
X71846Y348100D01*
X71278Y348215D01*
X70761Y348368D01*
X70193Y348560D01*
X69418Y348867D01*
Y347333D01*
G01X75860Y353932D02*
Y357032D01*
X74442Y354810D01*
X76358D01*
G01X67072Y355024D02*
X67340Y355385D01*
X67570Y355592D01*
X67877Y355695D01*
X68145Y355592D01*
X68337Y355385D01*
X68490Y355075D01*
X68528Y354714D01*
X68490Y354404D01*
X68337Y354094D01*
X68107Y353835D01*
X67838Y353732D01*
X67532Y353835D01*
X67263Y354145D01*
X67110Y354610D01*
X67072Y355127D01*
X67148Y355799D01*
X67263Y356160D01*
X67455Y356522D01*
X67723Y356780D01*
X67992Y356832D01*
X68260Y356729D01*
X68452Y356470D01*
G01X69200Y362550D02*
Y365650D01*
X68740Y365030D01*
G01Y362550D02*
X69660D01*
G01X74493Y388992D02*
X74263Y389147D01*
X73995Y389250D01*
X73688D01*
X73343Y389095D01*
X73075Y388837D01*
X72883Y388527D01*
X72730Y388010D01*
X72692Y387545D01*
X72768Y387080D01*
X72883Y386770D01*
X73113Y386460D01*
X73382Y386253D01*
X73650Y386150D01*
X73918D01*
X74187Y386253D01*
X74417Y386408D01*
X74608Y386615D01*
G01X75983Y386150D02*
Y389250D01*
X76942D01*
X77248Y389095D01*
X77440Y388888D01*
X77517Y388475D01*
X77440Y388062D01*
X77210Y387803D01*
X76942Y387648D01*
X75983D01*
G01X76942D02*
X77517Y386150D01*
G01X79850D02*
Y389250D01*
X79390Y388630D01*
G01Y386150D02*
X80310D01*
G01X82222Y388733D02*
X82452Y389043D01*
X82720Y389198D01*
X83027Y389250D01*
X83410Y389147D01*
X83678Y388888D01*
X83755Y388578D01*
X83717Y388268D01*
X83563Y388010D01*
X82797Y387493D01*
X82452Y387132D01*
X82222Y386615D01*
X82145Y386150D01*
X83755D01*
G01X76757Y416770D02*
X76987Y416408D01*
X77293Y416202D01*
X77638Y416150D01*
X77945Y416202D01*
X78252Y416460D01*
X78443Y416770D01*
X78482Y417080D01*
X78405Y417442D01*
X78137Y417700D01*
X77868Y417803D01*
X77523D01*
G01X77868D02*
X78098Y417958D01*
X78290Y418217D01*
X78367Y418527D01*
X78290Y418837D01*
X78098Y419095D01*
X77753Y419250D01*
X77408Y419198D01*
X77063Y418992D01*
G01X89557Y64720D02*
X89787Y64358D01*
X90093Y64152D01*
X90438Y64100D01*
X90745Y64152D01*
X91052Y64410D01*
X91243Y64720D01*
X91282Y65030D01*
X91205Y65392D01*
X90937Y65650D01*
X90668Y65753D01*
X90323D01*
G01X90668D02*
X90898Y65908D01*
X91090Y66167D01*
X91167Y66477D01*
X91090Y66787D01*
X90898Y67045D01*
X90553Y67200D01*
X90208Y67148D01*
X89863Y66942D01*
G01X81480Y165573D02*
Y168673D01*
X81020Y168053D01*
G01Y165573D02*
X81940D01*
G01X83772Y219033D02*
X84002Y219343D01*
X84270Y219498D01*
X84577Y219550D01*
X84960Y219447D01*
X85228Y219188D01*
X85305Y218878D01*
X85267Y218568D01*
X85113Y218310D01*
X84347Y217793D01*
X84002Y217432D01*
X83772Y216915D01*
X83695Y216450D01*
X85305D01*
G01X89000Y208000D02*
Y211100D01*
X88540Y210480D01*
G01Y208000D02*
X89460D01*
G01X88460Y221450D02*
Y224550D01*
X87042Y222328D01*
X88958D01*
G01X80550Y229757D02*
X82772D01*
X83237Y229910D01*
X83547Y230217D01*
X83650Y230600D01*
X83547Y230983D01*
X83237Y231290D01*
X82772Y231443D01*
X80550D01*
G01X83030Y232857D02*
X83392Y233087D01*
X83598Y233393D01*
X83650Y233738D01*
X83598Y234045D01*
X83340Y234352D01*
X83030Y234543D01*
X82720Y234582D01*
X82358Y234505D01*
X82100Y234237D01*
X81997Y233968D01*
Y233623D01*
G01Y233968D02*
X81842Y234198D01*
X81583Y234390D01*
X81273Y234467D01*
X80963Y234390D01*
X80705Y234198D01*
X80550Y233853D01*
X80602Y233508D01*
X80808Y233163D01*
G01X81067Y236072D02*
X80757Y236302D01*
X80602Y236570D01*
X80550Y236877D01*
X80653Y237260D01*
X80912Y237528D01*
X81222Y237605D01*
X81532Y237567D01*
X81790Y237413D01*
X82307Y236647D01*
X82668Y236302D01*
X83185Y236072D01*
X83650Y235995D01*
Y237605D01*
G01X85050Y247583D02*
X81950D01*
Y248542D01*
X82105Y248848D01*
X82312Y249040D01*
X82725Y249117D01*
X83138Y249040D01*
X83397Y248810D01*
X83552Y248542D01*
Y247583D01*
G01Y248542D02*
X85050Y249117D01*
G01X84430Y250607D02*
X84792Y250837D01*
X84998Y251143D01*
X85050Y251488D01*
X84998Y251795D01*
X84740Y252102D01*
X84430Y252293D01*
X84120Y252332D01*
X83758Y252255D01*
X83500Y251987D01*
X83397Y251718D01*
Y251373D01*
G01Y251718D02*
X83242Y251948D01*
X82983Y252140D01*
X82673Y252217D01*
X82363Y252140D01*
X82105Y251948D01*
X81950Y251603D01*
X82002Y251258D01*
X82208Y250913D01*
G01X84585Y253707D02*
X84843Y253937D01*
X84998Y254205D01*
X85050Y254550D01*
X84947Y254895D01*
X84740Y255163D01*
X84378Y255355D01*
X83965Y255393D01*
X83552Y255317D01*
X83293Y255125D01*
X83087Y254857D01*
X83035Y254588D01*
X83087Y254320D01*
X83293Y253975D01*
X81950Y254090D01*
Y255125D01*
G01X85050Y257650D02*
X81950D01*
X82570Y257190D01*
G01X85050D02*
Y258110D01*
G01X87657Y241915D02*
X87887Y241657D01*
X88155Y241502D01*
X88500Y241450D01*
X88845Y241553D01*
X89113Y241760D01*
X89305Y242122D01*
X89343Y242535D01*
X89267Y242948D01*
X89075Y243207D01*
X88807Y243413D01*
X88538Y243465D01*
X88270Y243413D01*
X87925Y243207D01*
X88040Y244550D01*
X89075D01*
G01X88993Y259340D02*
X88763Y259495D01*
X88495Y259598D01*
X88188D01*
X87843Y259443D01*
X87575Y259185D01*
X87383Y258875D01*
X87230Y258358D01*
X87192Y257893D01*
X87268Y257428D01*
X87383Y257118D01*
X87613Y256808D01*
X87882Y256601D01*
X88150Y256498D01*
X88418D01*
X88687Y256601D01*
X88917Y256756D01*
X89108Y256963D01*
G01X90522Y259081D02*
X90752Y259391D01*
X91020Y259546D01*
X91327Y259598D01*
X91710Y259495D01*
X91978Y259236D01*
X92055Y258926D01*
X92017Y258616D01*
X91863Y258358D01*
X91097Y257841D01*
X90752Y257480D01*
X90522Y256963D01*
X90445Y256498D01*
X92055D01*
G01X94273D02*
X94350Y257170D01*
X94465Y257738D01*
X94618Y258255D01*
X94810Y258823D01*
X95117Y259598D01*
X93583D01*
G01X96722Y257790D02*
X96990Y258151D01*
X97220Y258358D01*
X97527Y258461D01*
X97795Y258358D01*
X97987Y258151D01*
X98140Y257841D01*
X98178Y257480D01*
X98140Y257170D01*
X97987Y256860D01*
X97757Y256601D01*
X97488Y256498D01*
X97182Y256601D01*
X96913Y256911D01*
X96760Y257376D01*
X96722Y257893D01*
X96798Y258565D01*
X96913Y258926D01*
X97105Y259288D01*
X97373Y259546D01*
X97642Y259598D01*
X97910Y259495D01*
X98102Y259236D01*
G01X92693Y269842D02*
X92463Y269997D01*
X92195Y270100D01*
X91888D01*
X91543Y269945D01*
X91275Y269687D01*
X91083Y269377D01*
X90930Y268860D01*
X90892Y268395D01*
X90968Y267930D01*
X91083Y267620D01*
X91313Y267310D01*
X91582Y267103D01*
X91850Y267000D01*
X92118D01*
X92387Y267103D01*
X92617Y267258D01*
X92808Y267465D01*
G01X94222Y269583D02*
X94452Y269893D01*
X94720Y270048D01*
X95027Y270100D01*
X95410Y269997D01*
X95678Y269738D01*
X95755Y269428D01*
X95717Y269118D01*
X95563Y268860D01*
X94797Y268343D01*
X94452Y267982D01*
X94222Y267465D01*
X94145Y267000D01*
X95755D01*
G01X97973D02*
X98050Y267672D01*
X98165Y268240D01*
X98318Y268757D01*
X98510Y269325D01*
X98817Y270100D01*
X97283D01*
G01X101150Y267000D02*
X101418Y267052D01*
X101725Y267207D01*
X101917Y267465D01*
X101993Y267827D01*
X101917Y268188D01*
X101687Y268498D01*
X101342Y268653D01*
X100958D01*
X100728Y268757D01*
X100537Y269015D01*
X100460Y269377D01*
X100575Y269738D01*
X100843Y269997D01*
X101150Y270100D01*
X101457Y269997D01*
X101725Y269738D01*
X101840Y269377D01*
X101763Y269015D01*
X101572Y268757D01*
X101342Y268653D01*
X100958D01*
X100613Y268498D01*
X100383Y268188D01*
X100307Y267827D01*
X100383Y267465D01*
X100575Y267207D01*
X100882Y267052D01*
X101150Y267000D01*
G01X85500Y262000D02*
X85768Y262052D01*
X86075Y262207D01*
X86267Y262465D01*
X86343Y262827D01*
X86267Y263188D01*
X86037Y263498D01*
X85692Y263653D01*
X85308D01*
X85078Y263757D01*
X84887Y264015D01*
X84810Y264377D01*
X84925Y264738D01*
X85193Y264997D01*
X85500Y265100D01*
X85807Y264997D01*
X86075Y264738D01*
X86190Y264377D01*
X86113Y264015D01*
X85922Y263757D01*
X85692Y263653D01*
X85308D01*
X84963Y263498D01*
X84733Y263188D01*
X84657Y262827D01*
X84733Y262465D01*
X84925Y262207D01*
X85232Y262052D01*
X85500Y262000D01*
G01X88681Y265266D02*
Y262166D01*
X90215D01*
G01X92548D02*
Y265266D01*
X92088Y264646D01*
G01Y262166D02*
X93008D01*
G01X95648D02*
X95916Y262218D01*
X96223Y262373D01*
X96415Y262631D01*
X96491Y262993D01*
X96415Y263354D01*
X96185Y263664D01*
X95840Y263819D01*
X95456D01*
X95226Y263923D01*
X95035Y264181D01*
X94958Y264543D01*
X95073Y264904D01*
X95341Y265163D01*
X95648Y265266D01*
X95955Y265163D01*
X96223Y264904D01*
X96338Y264543D01*
X96261Y264181D01*
X96070Y263923D01*
X95840Y263819D01*
X95456D01*
X95111Y263664D01*
X94881Y263354D01*
X94805Y262993D01*
X94881Y262631D01*
X95073Y262373D01*
X95380Y262218D01*
X95648Y262166D01*
G01X92693Y274342D02*
X92463Y274497D01*
X92195Y274600D01*
X91888D01*
X91543Y274445D01*
X91275Y274187D01*
X91083Y273877D01*
X90930Y273360D01*
X90892Y272895D01*
X90968Y272430D01*
X91083Y272120D01*
X91313Y271810D01*
X91582Y271603D01*
X91850Y271500D01*
X92118D01*
X92387Y271603D01*
X92617Y271758D01*
X92808Y271965D01*
G01X94222Y274083D02*
X94452Y274393D01*
X94720Y274548D01*
X95027Y274600D01*
X95410Y274497D01*
X95678Y274238D01*
X95755Y273928D01*
X95717Y273618D01*
X95563Y273360D01*
X94797Y272843D01*
X94452Y272482D01*
X94222Y271965D01*
X94145Y271500D01*
X95755D01*
G01X97973D02*
X98050Y272172D01*
X98165Y272740D01*
X98318Y273257D01*
X98510Y273825D01*
X98817Y274600D01*
X97283D01*
G01X101073Y271500D02*
X101150Y272172D01*
X101265Y272740D01*
X101418Y273257D01*
X101610Y273825D01*
X101917Y274600D01*
X100383D01*
G01X84450Y270500D02*
Y273600D01*
X83990Y272980D01*
G01Y270500D02*
X84910D01*
G01X87550Y273600D02*
X87243Y273497D01*
X87013Y273238D01*
X86860Y272928D01*
X86745Y272515D01*
X86707Y272050D01*
X86745Y271585D01*
X86860Y271172D01*
X87013Y270862D01*
X87243Y270603D01*
X87550Y270500D01*
X87857Y270603D01*
X88087Y270862D01*
X88240Y271172D01*
X88355Y271585D01*
X88393Y272050D01*
X88355Y272515D01*
X88240Y272928D01*
X88087Y273238D01*
X87857Y273497D01*
X87550Y273600D01*
G01X97907Y303065D02*
X98269Y303295D01*
X98475Y303601D01*
X98527Y303946D01*
X98475Y304253D01*
X98217Y304560D01*
X97907Y304751D01*
X97597Y304790D01*
X97235Y304713D01*
X96977Y304445D01*
X96874Y304176D01*
Y303831D01*
G01Y304176D02*
X96719Y304406D01*
X96460Y304598D01*
X96150Y304675D01*
X95840Y304598D01*
X95582Y304406D01*
X95427Y304061D01*
X95479Y303716D01*
X95685Y303371D01*
G01X97907Y306165D02*
X98269Y306395D01*
X98475Y306701D01*
X98527Y307046D01*
X98475Y307353D01*
X98217Y307660D01*
X97907Y307851D01*
X97597Y307890D01*
X97235Y307813D01*
X96977Y307545D01*
X96874Y307276D01*
Y306931D01*
G01Y307276D02*
X96719Y307506D01*
X96460Y307698D01*
X96150Y307775D01*
X95840Y307698D01*
X95582Y307506D01*
X95427Y307161D01*
X95479Y306816D01*
X95685Y306471D01*
G01X84053Y317286D02*
X84415Y317516D01*
X84621Y317822D01*
X84673Y318167D01*
X84621Y318474D01*
X84363Y318781D01*
X84053Y318972D01*
X83743Y319011D01*
X83381Y318934D01*
X83123Y318666D01*
X83020Y318397D01*
Y318052D01*
G01Y318397D02*
X82865Y318627D01*
X82606Y318819D01*
X82296Y318896D01*
X81986Y318819D01*
X81728Y318627D01*
X81573Y318282D01*
X81625Y317937D01*
X81831Y317592D01*
G01X82090Y320501D02*
X81780Y320731D01*
X81625Y320999D01*
X81573Y321306D01*
X81676Y321689D01*
X81935Y321957D01*
X82245Y322034D01*
X82555Y321996D01*
X82813Y321842D01*
X83330Y321076D01*
X83691Y320731D01*
X84208Y320501D01*
X84673Y320424D01*
Y322034D01*
G01X84650Y349001D02*
X81550D01*
X82170Y348541D01*
G01X84650D02*
Y349461D01*
G01Y352024D02*
X83978Y352101D01*
X83410Y352216D01*
X82893Y352369D01*
X82325Y352561D01*
X81550Y352868D01*
Y351334D01*
G01X86822Y365083D02*
X87052Y365393D01*
X87320Y365548D01*
X87627Y365600D01*
X88010Y365497D01*
X88278Y365238D01*
X88355Y364928D01*
X88317Y364618D01*
X88163Y364360D01*
X87397Y363843D01*
X87052Y363482D01*
X86822Y362965D01*
X86745Y362500D01*
X88355D01*
G01X96550Y361950D02*
X93450D01*
X94070Y361490D01*
G01X96550D02*
Y362410D01*
G01X95258Y364322D02*
X94897Y364590D01*
X94690Y364820D01*
X94587Y365127D01*
X94690Y365395D01*
X94897Y365587D01*
X95207Y365740D01*
X95568Y365778D01*
X95878Y365740D01*
X96188Y365587D01*
X96447Y365357D01*
X96550Y365088D01*
X96447Y364782D01*
X96137Y364513D01*
X95672Y364360D01*
X95155Y364322D01*
X94483Y364398D01*
X94122Y364513D01*
X93760Y364705D01*
X93502Y364973D01*
X93450Y365242D01*
X93553Y365510D01*
X93812Y365702D01*
G01X93733Y393391D02*
Y390291D01*
G01X92851Y393391D02*
X94615D01*
G01X96066Y390291D02*
Y393391D01*
X96986D01*
X97293Y393236D01*
X97523Y392874D01*
X97600Y392461D01*
X97523Y392048D01*
X97331Y391738D01*
X96986Y391583D01*
X96066D01*
G01X100393Y390291D02*
Y393391D01*
X98975Y391169D01*
X100891D01*
G01X102305Y392874D02*
X102535Y393184D01*
X102803Y393339D01*
X103110Y393391D01*
X103493Y393288D01*
X103761Y393029D01*
X103838Y392719D01*
X103800Y392409D01*
X103646Y392151D01*
X102880Y391634D01*
X102535Y391273D01*
X102305Y390756D01*
X102228Y390291D01*
X103838D01*
G01X115663Y62652D02*
X115433Y62807D01*
X115165Y62910D01*
X114858D01*
X114513Y62755D01*
X114245Y62497D01*
X114053Y62187D01*
X113900Y61670D01*
X113862Y61205D01*
X113938Y60740D01*
X114053Y60430D01*
X114283Y60120D01*
X114552Y59913D01*
X114820Y59810D01*
X115088D01*
X115357Y59913D01*
X115587Y60068D01*
X115778Y60275D01*
G01X117192Y62393D02*
X117422Y62703D01*
X117690Y62858D01*
X117997Y62910D01*
X118380Y62807D01*
X118648Y62548D01*
X118725Y62238D01*
X118687Y61928D01*
X118533Y61670D01*
X117767Y61153D01*
X117422Y60792D01*
X117192Y60275D01*
X117115Y59810D01*
X118725D01*
G01X120292Y62393D02*
X120522Y62703D01*
X120790Y62858D01*
X121097Y62910D01*
X121480Y62807D01*
X121748Y62548D01*
X121825Y62238D01*
X121787Y61928D01*
X121633Y61670D01*
X120867Y61153D01*
X120522Y60792D01*
X120292Y60275D01*
X120215Y59810D01*
X121825D01*
G01X123277Y60275D02*
X123507Y60017D01*
X123775Y59862D01*
X124120Y59810D01*
X124465Y59913D01*
X124733Y60120D01*
X124925Y60482D01*
X124963Y60895D01*
X124887Y61308D01*
X124695Y61567D01*
X124427Y61773D01*
X124158Y61825D01*
X123890Y61773D01*
X123545Y61567D01*
X123660Y62910D01*
X124695D01*
G01X114053Y64310D02*
Y67410D01*
X115012D01*
X115318Y67255D01*
X115510Y67048D01*
X115587Y66635D01*
X115510Y66222D01*
X115280Y65963D01*
X115012Y65808D01*
X114053D01*
G01X115012D02*
X115587Y64310D01*
G01X117077Y64930D02*
X117307Y64568D01*
X117613Y64362D01*
X117958Y64310D01*
X118265Y64362D01*
X118572Y64620D01*
X118763Y64930D01*
X118802Y65240D01*
X118725Y65602D01*
X118457Y65860D01*
X118188Y65963D01*
X117843D01*
G01X118188D02*
X118418Y66118D01*
X118610Y66377D01*
X118687Y66687D01*
X118610Y66997D01*
X118418Y67255D01*
X118073Y67410D01*
X117728Y67358D01*
X117383Y67152D01*
G01X121480Y64310D02*
Y67410D01*
X120062Y65188D01*
X121978D01*
G01X123277Y64775D02*
X123507Y64517D01*
X123775Y64362D01*
X124120Y64310D01*
X124465Y64413D01*
X124733Y64620D01*
X124925Y64982D01*
X124963Y65395D01*
X124887Y65808D01*
X124695Y66067D01*
X124427Y66273D01*
X124158Y66325D01*
X123890Y66273D01*
X123545Y66067D01*
X123660Y67410D01*
X124695D01*
G01X112503Y73810D02*
Y76910D01*
X113462D01*
X113768Y76755D01*
X113960Y76548D01*
X114037Y76135D01*
X113960Y75722D01*
X113730Y75463D01*
X113462Y75308D01*
X112503D01*
G01X113462D02*
X114037Y73810D01*
G01X116370D02*
Y76910D01*
X115910Y76290D01*
G01Y73810D02*
X116830D01*
G01X118818Y74172D02*
X119087Y73913D01*
X119393Y73810D01*
X119700Y73913D01*
X119968Y74223D01*
X120160Y74688D01*
X120237Y75153D01*
Y75722D01*
X120160Y76187D01*
X119968Y76600D01*
X119738Y76807D01*
X119470Y76910D01*
X119163Y76807D01*
X118933Y76600D01*
X118780Y76290D01*
X118703Y75877D01*
X118780Y75515D01*
X118972Y75153D01*
X119202Y74947D01*
X119470Y74895D01*
X119777Y74998D01*
X120007Y75257D01*
X120237Y75722D01*
G01X121918Y74172D02*
X122187Y73913D01*
X122493Y73810D01*
X122800Y73913D01*
X123068Y74223D01*
X123260Y74688D01*
X123337Y75153D01*
Y75722D01*
X123260Y76187D01*
X123068Y76600D01*
X122838Y76807D01*
X122570Y76910D01*
X122263Y76807D01*
X122033Y76600D01*
X121880Y76290D01*
X121803Y75877D01*
X121880Y75515D01*
X122072Y75153D01*
X122302Y74947D01*
X122570Y74895D01*
X122877Y74998D01*
X123107Y75257D01*
X123337Y75722D01*
G01X124942Y76393D02*
X125172Y76703D01*
X125440Y76858D01*
X125747Y76910D01*
X126130Y76807D01*
X126398Y76548D01*
X126475Y76238D01*
X126437Y75928D01*
X126283Y75670D01*
X125517Y75153D01*
X125172Y74792D01*
X124942Y74275D01*
X124865Y73810D01*
X126475D01*
G01X108557Y71465D02*
X108787Y71207D01*
X109055Y71052D01*
X109400Y71000D01*
X109745Y71103D01*
X110013Y71310D01*
X110205Y71672D01*
X110243Y72085D01*
X110167Y72498D01*
X109975Y72757D01*
X109707Y72963D01*
X109438Y73015D01*
X109170Y72963D01*
X108825Y72757D01*
X108940Y74100D01*
X109975D01*
G01X109860Y63400D02*
Y66500D01*
X108442Y64278D01*
X110358D01*
G01X99737Y70300D02*
Y68078D01*
X99890Y67613D01*
X100197Y67303D01*
X100580Y67200D01*
X100963Y67303D01*
X101270Y67613D01*
X101423Y68078D01*
Y70300D01*
G01X103603Y67200D02*
X103680Y67872D01*
X103795Y68440D01*
X103948Y68957D01*
X104140Y69525D01*
X104447Y70300D01*
X102913D01*
G01X106153Y103000D02*
Y106100D01*
X107150Y103517D01*
X108147Y106100D01*
Y103000D01*
G01X109292D02*
X110250Y106100D01*
X111208Y103000D01*
G01X110863Y104085D02*
X109637D01*
G01X114193Y105842D02*
X113963Y105997D01*
X113695Y106100D01*
X113388D01*
X113043Y105945D01*
X112775Y105687D01*
X112583Y105377D01*
X112430Y104860D01*
X112392Y104395D01*
X112468Y103930D01*
X112583Y103620D01*
X112813Y103310D01*
X113082Y103103D01*
X113350Y103000D01*
X113618D01*
X113887Y103103D01*
X114117Y103258D01*
X114308Y103465D01*
G01X115300Y101967D02*
X117600D01*
G01X118783Y103000D02*
Y106100D01*
X119703D01*
X120010Y105945D01*
X120240Y105583D01*
X120317Y105170D01*
X120240Y104757D01*
X120048Y104447D01*
X119703Y104292D01*
X118783D01*
G01X122190Y106100D02*
X123110D01*
G01X122650D02*
Y103000D01*
G01X122190D02*
X123110D01*
G01X124868D02*
Y106100D01*
X126632Y103000D01*
Y106100D01*
G01X128007Y103620D02*
X128237Y103258D01*
X128543Y103052D01*
X128888Y103000D01*
X129195Y103052D01*
X129502Y103310D01*
X129693Y103620D01*
X129732Y103930D01*
X129655Y104292D01*
X129387Y104550D01*
X129118Y104653D01*
X128773D01*
G01X129118D02*
X129348Y104808D01*
X129540Y105067D01*
X129617Y105377D01*
X129540Y105687D01*
X129348Y105945D01*
X129003Y106100D01*
X128658Y106048D01*
X128313Y105842D01*
G01X114220Y182493D02*
Y185593D01*
X115217Y183010D01*
X116214Y185593D01*
Y182493D01*
G01X117359D02*
X118317Y185593D01*
X119275Y182493D01*
G01X118930Y183578D02*
X117704D01*
G01X122260Y185335D02*
X122030Y185490D01*
X121762Y185593D01*
X121455D01*
X121110Y185438D01*
X120842Y185180D01*
X120650Y184870D01*
X120497Y184353D01*
X120459Y183888D01*
X120535Y183423D01*
X120650Y183113D01*
X120880Y182803D01*
X121149Y182596D01*
X121417Y182493D01*
X121685D01*
X121954Y182596D01*
X122184Y182751D01*
X122375Y182958D01*
G01X123367Y181460D02*
X125667D01*
G01X126850Y182493D02*
Y185593D01*
X127770D01*
X128077Y185438D01*
X128307Y185076D01*
X128384Y184663D01*
X128307Y184250D01*
X128115Y183940D01*
X127770Y183785D01*
X126850D01*
G01X130257Y185593D02*
X131177D01*
G01X130717D02*
Y182493D01*
G01X130257D02*
X131177D01*
G01X132935D02*
Y185593D01*
X134699Y182493D01*
Y185593D01*
G01X136189Y185076D02*
X136419Y185386D01*
X136687Y185541D01*
X136994Y185593D01*
X137377Y185490D01*
X137645Y185231D01*
X137722Y184921D01*
X137684Y184611D01*
X137530Y184353D01*
X136764Y183836D01*
X136419Y183475D01*
X136189Y182958D01*
X136112Y182493D01*
X137722D01*
G01X110153Y260000D02*
Y263100D01*
X111150Y260517D01*
X112147Y263100D01*
Y260000D01*
G01X113292D02*
X114250Y263100D01*
X115208Y260000D01*
G01X114863Y261085D02*
X113637D01*
G01X118193Y262842D02*
X117963Y262997D01*
X117695Y263100D01*
X117388D01*
X117043Y262945D01*
X116775Y262687D01*
X116583Y262377D01*
X116430Y261860D01*
X116392Y261395D01*
X116468Y260930D01*
X116583Y260620D01*
X116813Y260310D01*
X117082Y260103D01*
X117350Y260000D01*
X117618D01*
X117887Y260103D01*
X118117Y260258D01*
X118308Y260465D01*
G01X119300Y258967D02*
X121600D01*
G01X122783Y260000D02*
Y263100D01*
X123703D01*
X124010Y262945D01*
X124240Y262583D01*
X124317Y262170D01*
X124240Y261757D01*
X124048Y261447D01*
X123703Y261292D01*
X122783D01*
G01X126190Y263100D02*
X127110D01*
G01X126650D02*
Y260000D01*
G01X126190D02*
X127110D01*
G01X128868D02*
Y263100D01*
X130632Y260000D01*
Y263100D01*
G01X132850Y260000D02*
Y263100D01*
X132390Y262480D01*
G01Y260000D02*
X133310D01*
G01X108532Y290583D02*
X105432D01*
Y291542D01*
X105587Y291848D01*
X105794Y292040D01*
X106207Y292117D01*
X106620Y292040D01*
X106879Y291810D01*
X107034Y291542D01*
Y290583D01*
G01Y291542D02*
X108532Y292117D01*
G01X107912Y293607D02*
X108274Y293837D01*
X108480Y294143D01*
X108532Y294488D01*
X108480Y294795D01*
X108222Y295102D01*
X107912Y295293D01*
X107602Y295332D01*
X107240Y295255D01*
X106982Y294987D01*
X106879Y294718D01*
Y294373D01*
G01Y294718D02*
X106724Y294948D01*
X106465Y295140D01*
X106155Y295217D01*
X105845Y295140D01*
X105587Y294948D01*
X105432Y294603D01*
X105484Y294258D01*
X105690Y293913D01*
G01X108067Y296707D02*
X108325Y296937D01*
X108480Y297205D01*
X108532Y297550D01*
X108429Y297895D01*
X108222Y298163D01*
X107860Y298355D01*
X107447Y298393D01*
X107034Y298317D01*
X106775Y298125D01*
X106569Y297857D01*
X106517Y297588D01*
X106569Y297320D01*
X106775Y296975D01*
X105432Y297090D01*
Y298125D01*
G01X107912Y299807D02*
X108274Y300037D01*
X108480Y300343D01*
X108532Y300688D01*
X108480Y300995D01*
X108222Y301302D01*
X107912Y301493D01*
X107602Y301532D01*
X107240Y301455D01*
X106982Y301187D01*
X106879Y300918D01*
Y300573D01*
G01Y300918D02*
X106724Y301148D01*
X106465Y301340D01*
X106155Y301417D01*
X105845Y301340D01*
X105587Y301148D01*
X105432Y300803D01*
X105484Y300458D01*
X105690Y300113D01*
G01X113532Y290583D02*
X110432D01*
Y291542D01*
X110587Y291848D01*
X110794Y292040D01*
X111207Y292117D01*
X111620Y292040D01*
X111879Y291810D01*
X112034Y291542D01*
Y290583D01*
G01Y291542D02*
X113532Y292117D01*
G01X112912Y293607D02*
X113274Y293837D01*
X113480Y294143D01*
X113532Y294488D01*
X113480Y294795D01*
X113222Y295102D01*
X112912Y295293D01*
X112602Y295332D01*
X112240Y295255D01*
X111982Y294987D01*
X111879Y294718D01*
Y294373D01*
G01Y294718D02*
X111724Y294948D01*
X111465Y295140D01*
X111155Y295217D01*
X110845Y295140D01*
X110587Y294948D01*
X110432Y294603D01*
X110484Y294258D01*
X110690Y293913D01*
G01X113067Y296707D02*
X113325Y296937D01*
X113480Y297205D01*
X113532Y297550D01*
X113429Y297895D01*
X113222Y298163D01*
X112860Y298355D01*
X112447Y298393D01*
X112034Y298317D01*
X111775Y298125D01*
X111569Y297857D01*
X111517Y297588D01*
X111569Y297320D01*
X111775Y296975D01*
X110432Y297090D01*
Y298125D01*
G01X110949Y299922D02*
X110639Y300152D01*
X110484Y300420D01*
X110432Y300727D01*
X110535Y301110D01*
X110794Y301378D01*
X111104Y301455D01*
X111414Y301417D01*
X111672Y301263D01*
X112189Y300497D01*
X112550Y300152D01*
X113067Y299922D01*
X113532Y299845D01*
Y301455D01*
G01X103534Y290583D02*
X100434D01*
Y291542D01*
X100589Y291848D01*
X100796Y292040D01*
X101209Y292117D01*
X101622Y292040D01*
X101881Y291810D01*
X102036Y291542D01*
Y290583D01*
G01Y291542D02*
X103534Y292117D01*
G01Y294910D02*
X100434D01*
X102656Y293492D01*
Y295408D01*
G01X103534Y297550D02*
X103482Y297818D01*
X103327Y298125D01*
X103069Y298317D01*
X102707Y298393D01*
X102346Y298317D01*
X102036Y298087D01*
X101881Y297742D01*
Y297358D01*
X101777Y297128D01*
X101519Y296937D01*
X101157Y296860D01*
X100796Y296975D01*
X100537Y297243D01*
X100434Y297550D01*
X100537Y297857D01*
X100796Y298125D01*
X101157Y298240D01*
X101519Y298163D01*
X101777Y297972D01*
X101881Y297742D01*
Y297358D01*
X102036Y297013D01*
X102346Y296783D01*
X102707Y296707D01*
X103069Y296783D01*
X103327Y296975D01*
X103482Y297282D01*
X103534Y297550D01*
G01X100434Y300650D02*
X100537Y300343D01*
X100796Y300113D01*
X101106Y299960D01*
X101519Y299845D01*
X101984Y299807D01*
X102449Y299845D01*
X102862Y299960D01*
X103172Y300113D01*
X103431Y300343D01*
X103534Y300650D01*
X103431Y300957D01*
X103172Y301187D01*
X102862Y301340D01*
X102449Y301455D01*
X101984Y301493D01*
X101519Y301455D01*
X101106Y301340D01*
X100796Y301187D01*
X100537Y300957D01*
X100434Y300650D01*
G01X110386Y330747D02*
X112608D01*
X113073Y330900D01*
X113383Y331207D01*
X113486Y331590D01*
X113383Y331973D01*
X113073Y332280D01*
X112608Y332433D01*
X110386D01*
G01X113486Y334690D02*
X110386D01*
X111006Y334230D01*
G01X113486D02*
Y335150D01*
G01Y337790D02*
X113434Y338058D01*
X113279Y338365D01*
X113021Y338557D01*
X112659Y338633D01*
X112298Y338557D01*
X111988Y338327D01*
X111833Y337982D01*
Y337598D01*
X111729Y337368D01*
X111471Y337177D01*
X111109Y337100D01*
X110748Y337215D01*
X110489Y337483D01*
X110386Y337790D01*
X110489Y338097D01*
X110748Y338365D01*
X111109Y338480D01*
X111471Y338403D01*
X111729Y338212D01*
X111833Y337982D01*
Y337598D01*
X111988Y337253D01*
X112298Y337023D01*
X112659Y336947D01*
X113021Y337023D01*
X113279Y337215D01*
X113434Y337522D01*
X113486Y337790D01*
G01X111532Y365583D02*
X108432D01*
Y366542D01*
X108587Y366848D01*
X108794Y367040D01*
X109207Y367117D01*
X109620Y367040D01*
X109879Y366810D01*
X110034Y366542D01*
Y365583D01*
G01Y366542D02*
X111532Y367117D01*
G01Y369450D02*
X108432D01*
X109052Y368990D01*
G01X111532D02*
Y369910D01*
G01X108949Y371822D02*
X108639Y372052D01*
X108484Y372320D01*
X108432Y372627D01*
X108535Y373010D01*
X108794Y373278D01*
X109104Y373355D01*
X109414Y373317D01*
X109672Y373163D01*
X110189Y372397D01*
X110550Y372052D01*
X111067Y371822D01*
X111532Y371745D01*
Y373355D01*
G01X111170Y374998D02*
X111429Y375267D01*
X111532Y375573D01*
X111429Y375880D01*
X111119Y376148D01*
X110654Y376340D01*
X110189Y376417D01*
X109620D01*
X109155Y376340D01*
X108742Y376148D01*
X108535Y375918D01*
X108432Y375650D01*
X108535Y375343D01*
X108742Y375113D01*
X109052Y374960D01*
X109465Y374883D01*
X109827Y374960D01*
X110189Y375152D01*
X110395Y375382D01*
X110447Y375650D01*
X110344Y375957D01*
X110085Y376187D01*
X109620Y376417D01*
G01X116532Y365583D02*
X113432D01*
Y366542D01*
X113587Y366848D01*
X113794Y367040D01*
X114207Y367117D01*
X114620Y367040D01*
X114879Y366810D01*
X115034Y366542D01*
Y365583D01*
G01Y366542D02*
X116532Y367117D01*
G01Y369450D02*
X113432D01*
X114052Y368990D01*
G01X116532D02*
Y369910D01*
G01X113949Y371822D02*
X113639Y372052D01*
X113484Y372320D01*
X113432Y372627D01*
X113535Y373010D01*
X113794Y373278D01*
X114104Y373355D01*
X114414Y373317D01*
X114672Y373163D01*
X115189Y372397D01*
X115550Y372052D01*
X116067Y371822D01*
X116532Y371745D01*
Y373355D01*
G01Y375650D02*
X116480Y375918D01*
X116325Y376225D01*
X116067Y376417D01*
X115705Y376493D01*
X115344Y376417D01*
X115034Y376187D01*
X114879Y375842D01*
Y375458D01*
X114775Y375228D01*
X114517Y375037D01*
X114155Y374960D01*
X113794Y375075D01*
X113535Y375343D01*
X113432Y375650D01*
X113535Y375957D01*
X113794Y376225D01*
X114155Y376340D01*
X114517Y376263D01*
X114775Y376072D01*
X114879Y375842D01*
Y375458D01*
X115034Y375113D01*
X115344Y374883D01*
X115705Y374807D01*
X116067Y374883D01*
X116325Y375075D01*
X116480Y375382D01*
X116532Y375650D01*
G01X106532Y365583D02*
X103432D01*
Y366542D01*
X103587Y366848D01*
X103794Y367040D01*
X104207Y367117D01*
X104620Y367040D01*
X104879Y366810D01*
X105034Y366542D01*
Y365583D01*
G01Y366542D02*
X106532Y367117D01*
G01Y369910D02*
X103432D01*
X105654Y368492D01*
Y370408D01*
G01X106067Y371707D02*
X106325Y371937D01*
X106480Y372205D01*
X106532Y372550D01*
X106429Y372895D01*
X106222Y373163D01*
X105860Y373355D01*
X105447Y373393D01*
X105034Y373317D01*
X104775Y373125D01*
X104569Y372857D01*
X104517Y372588D01*
X104569Y372320D01*
X104775Y371975D01*
X103432Y372090D01*
Y373125D01*
G01X105240Y374922D02*
X104879Y375190D01*
X104672Y375420D01*
X104569Y375727D01*
X104672Y375995D01*
X104879Y376187D01*
X105189Y376340D01*
X105550Y376378D01*
X105860Y376340D01*
X106170Y376187D01*
X106429Y375957D01*
X106532Y375688D01*
X106429Y375382D01*
X106119Y375113D01*
X105654Y374960D01*
X105137Y374922D01*
X104465Y374998D01*
X104104Y375113D01*
X103742Y375305D01*
X103484Y375573D01*
X103432Y375842D01*
X103535Y376110D01*
X103794Y376302D01*
G01X97950Y367850D02*
X101050D01*
G01X97950Y366968D02*
Y368732D01*
G01X101050Y370183D02*
X97950D01*
Y371103D01*
X98105Y371410D01*
X98467Y371640D01*
X98880Y371717D01*
X99293Y371640D01*
X99603Y371448D01*
X99758Y371103D01*
Y370183D01*
G01X101050Y374050D02*
X97950D01*
X98570Y373590D01*
G01X101050D02*
Y374510D01*
G01Y377150D02*
X97950D01*
X98570Y376690D01*
G01X101050D02*
Y377610D01*
G01X127533Y59750D02*
Y62850D01*
X128492D01*
X128798Y62695D01*
X128990Y62488D01*
X129067Y62075D01*
X128990Y61662D01*
X128760Y61403D01*
X128492Y61248D01*
X127533D01*
G01X128492D02*
X129067Y59750D01*
G01X131400D02*
Y62850D01*
X130940Y62230D01*
G01Y59750D02*
X131860D01*
G01X134500D02*
X134768Y59802D01*
X135075Y59957D01*
X135267Y60215D01*
X135343Y60577D01*
X135267Y60938D01*
X135037Y61248D01*
X134692Y61403D01*
X134308D01*
X134078Y61507D01*
X133887Y61765D01*
X133810Y62127D01*
X133925Y62488D01*
X134193Y62747D01*
X134500Y62850D01*
X134807Y62747D01*
X135075Y62488D01*
X135190Y62127D01*
X135113Y61765D01*
X134922Y61507D01*
X134692Y61403D01*
X134308D01*
X133963Y61248D01*
X133733Y60938D01*
X133657Y60577D01*
X133733Y60215D01*
X133925Y59957D01*
X134232Y59802D01*
X134500Y59750D01*
G01X136757Y60370D02*
X136987Y60008D01*
X137293Y59802D01*
X137638Y59750D01*
X137945Y59802D01*
X138252Y60060D01*
X138443Y60370D01*
X138482Y60680D01*
X138405Y61042D01*
X138137Y61300D01*
X137868Y61403D01*
X137523D01*
G01X137868D02*
X138098Y61558D01*
X138290Y61817D01*
X138367Y62127D01*
X138290Y62437D01*
X138098Y62695D01*
X137753Y62850D01*
X137408Y62798D01*
X137063Y62592D01*
G01X115603Y69310D02*
Y72410D01*
X116562D01*
X116868Y72255D01*
X117060Y72048D01*
X117137Y71635D01*
X117060Y71222D01*
X116830Y70963D01*
X116562Y70808D01*
X115603D01*
G01X116562D02*
X117137Y69310D01*
G01X119470D02*
Y72410D01*
X119010Y71790D01*
G01Y69310D02*
X119930D01*
G01X121918Y69672D02*
X122187Y69413D01*
X122493Y69310D01*
X122800Y69413D01*
X123068Y69723D01*
X123260Y70188D01*
X123337Y70653D01*
Y71222D01*
X123260Y71687D01*
X123068Y72100D01*
X122838Y72307D01*
X122570Y72410D01*
X122263Y72307D01*
X122033Y72100D01*
X121880Y71790D01*
X121803Y71377D01*
X121880Y71015D01*
X122072Y70653D01*
X122302Y70447D01*
X122570Y70395D01*
X122877Y70498D01*
X123107Y70757D01*
X123337Y71222D01*
G01X127533Y64250D02*
Y67350D01*
X128492D01*
X128798Y67195D01*
X128990Y66988D01*
X129067Y66575D01*
X128990Y66162D01*
X128760Y65903D01*
X128492Y65748D01*
X127533D01*
G01X128492D02*
X129067Y64250D01*
G01X130557Y64870D02*
X130787Y64508D01*
X131093Y64302D01*
X131438Y64250D01*
X131745Y64302D01*
X132052Y64560D01*
X132243Y64870D01*
X132282Y65180D01*
X132205Y65542D01*
X131937Y65800D01*
X131668Y65903D01*
X131323D01*
G01X131668D02*
X131898Y66058D01*
X132090Y66317D01*
X132167Y66627D01*
X132090Y66937D01*
X131898Y67195D01*
X131553Y67350D01*
X131208Y67298D01*
X130863Y67092D01*
G01X134500Y64250D02*
Y67350D01*
X134040Y66730D01*
G01Y64250D02*
X134960D01*
G01X136872Y66833D02*
X137102Y67143D01*
X137370Y67298D01*
X137677Y67350D01*
X138060Y67247D01*
X138328Y66988D01*
X138405Y66678D01*
X138367Y66368D01*
X138213Y66110D01*
X137447Y65593D01*
X137102Y65232D01*
X136872Y64715D01*
X136795Y64250D01*
X138405D01*
G01X127553Y69250D02*
Y72350D01*
X128512D01*
X128818Y72195D01*
X129010Y71988D01*
X129087Y71575D01*
X129010Y71162D01*
X128780Y70903D01*
X128512Y70748D01*
X127553D01*
G01X128512D02*
X129087Y69250D01*
G01X131420D02*
Y72350D01*
X130960Y71730D01*
G01Y69250D02*
X131880D01*
G01X134520D02*
X134788Y69302D01*
X135095Y69457D01*
X135287Y69715D01*
X135363Y70077D01*
X135287Y70438D01*
X135057Y70748D01*
X134712Y70903D01*
X134328D01*
X134098Y71007D01*
X133907Y71265D01*
X133830Y71627D01*
X133945Y71988D01*
X134213Y72247D01*
X134520Y72350D01*
X134827Y72247D01*
X135095Y71988D01*
X135210Y71627D01*
X135133Y71265D01*
X134942Y71007D01*
X134712Y70903D01*
X134328D01*
X133983Y70748D01*
X133753Y70438D01*
X133677Y70077D01*
X133753Y69715D01*
X133945Y69457D01*
X134252Y69302D01*
X134520Y69250D01*
G01X138080D02*
Y72350D01*
X136662Y70128D01*
X138578D01*
G01X127553Y73750D02*
Y76850D01*
X128512D01*
X128818Y76695D01*
X129010Y76488D01*
X129087Y76075D01*
X129010Y75662D01*
X128780Y75403D01*
X128512Y75248D01*
X127553D01*
G01X128512D02*
X129087Y73750D01*
G01X130577Y74370D02*
X130807Y74008D01*
X131113Y73802D01*
X131458Y73750D01*
X131765Y73802D01*
X132072Y74060D01*
X132263Y74370D01*
X132302Y74680D01*
X132225Y75042D01*
X131957Y75300D01*
X131688Y75403D01*
X131343D01*
G01X131688D02*
X131918Y75558D01*
X132110Y75817D01*
X132187Y76127D01*
X132110Y76437D01*
X131918Y76695D01*
X131573Y76850D01*
X131228Y76798D01*
X130883Y76592D01*
G01X134520Y73750D02*
Y76850D01*
X134060Y76230D01*
G01Y73750D02*
X134980D01*
G01X136777Y74370D02*
X137007Y74008D01*
X137313Y73802D01*
X137658Y73750D01*
X137965Y73802D01*
X138272Y74060D01*
X138463Y74370D01*
X138502Y74680D01*
X138425Y75042D01*
X138157Y75300D01*
X137888Y75403D01*
X137543D01*
G01X137888D02*
X138118Y75558D01*
X138310Y75817D01*
X138387Y76127D01*
X138310Y76437D01*
X138118Y76695D01*
X137773Y76850D01*
X137428Y76798D01*
X137083Y76592D01*
G01X118532Y290583D02*
X115432D01*
Y291542D01*
X115587Y291848D01*
X115794Y292040D01*
X116207Y292117D01*
X116620Y292040D01*
X116879Y291810D01*
X117034Y291542D01*
Y290583D01*
G01Y291542D02*
X118532Y292117D01*
G01Y294910D02*
X115432D01*
X117654Y293492D01*
Y295408D01*
G01X118532Y297550D02*
X118480Y297818D01*
X118325Y298125D01*
X118067Y298317D01*
X117705Y298393D01*
X117344Y298317D01*
X117034Y298087D01*
X116879Y297742D01*
Y297358D01*
X116775Y297128D01*
X116517Y296937D01*
X116155Y296860D01*
X115794Y296975D01*
X115535Y297243D01*
X115432Y297550D01*
X115535Y297857D01*
X115794Y298125D01*
X116155Y298240D01*
X116517Y298163D01*
X116775Y297972D01*
X116879Y297742D01*
Y297358D01*
X117034Y297013D01*
X117344Y296783D01*
X117705Y296707D01*
X118067Y296783D01*
X118325Y296975D01*
X118480Y297282D01*
X118532Y297550D01*
G01Y300650D02*
X115432D01*
X116052Y300190D01*
G01X118532D02*
Y301110D01*
G01X128639Y304345D02*
X125539D01*
X127761Y302927D01*
Y304843D01*
G01X128639Y306985D02*
X128587Y307253D01*
X128432Y307560D01*
X128174Y307752D01*
X127812Y307828D01*
X127451Y307752D01*
X127141Y307522D01*
X126986Y307177D01*
Y306793D01*
X126882Y306563D01*
X126624Y306372D01*
X126262Y306295D01*
X125901Y306410D01*
X125642Y306678D01*
X125539Y306985D01*
X125642Y307292D01*
X125901Y307560D01*
X126262Y307675D01*
X126624Y307598D01*
X126882Y307407D01*
X126986Y307177D01*
Y306793D01*
X127141Y306448D01*
X127451Y306218D01*
X127812Y306142D01*
X128174Y306218D01*
X128432Y306410D01*
X128587Y306717D01*
X128639Y306985D01*
G01X115657Y382070D02*
X115887Y381708D01*
X116193Y381502D01*
X116538Y381450D01*
X116845Y381502D01*
X117152Y381760D01*
X117343Y382070D01*
X117382Y382380D01*
X117305Y382742D01*
X117037Y383000D01*
X116768Y383103D01*
X116423D01*
G01X116768D02*
X116998Y383258D01*
X117190Y383517D01*
X117267Y383827D01*
X117190Y384137D01*
X116998Y384395D01*
X116653Y384550D01*
X116308Y384498D01*
X115963Y384292D01*
G01X123950Y386950D02*
Y388345D01*
X123183Y390050D01*
G01X124717D02*
X123950Y388345D01*
G01X126322Y389533D02*
X126552Y389843D01*
X126820Y389998D01*
X127127Y390050D01*
X127510Y389947D01*
X127778Y389688D01*
X127855Y389378D01*
X127817Y389068D01*
X127663Y388810D01*
X126897Y388293D01*
X126552Y387932D01*
X126322Y387415D01*
X126245Y386950D01*
X127855D01*
G01X120243Y380292D02*
X120013Y380447D01*
X119745Y380550D01*
X119438D01*
X119093Y380395D01*
X118825Y380137D01*
X118633Y379827D01*
X118480Y379310D01*
X118442Y378845D01*
X118518Y378380D01*
X118633Y378070D01*
X118863Y377760D01*
X119132Y377553D01*
X119400Y377450D01*
X119668D01*
X119937Y377553D01*
X120167Y377708D01*
X120358Y377915D01*
G01X122500Y377450D02*
X122768Y377502D01*
X123075Y377657D01*
X123267Y377915D01*
X123343Y378277D01*
X123267Y378638D01*
X123037Y378948D01*
X122692Y379103D01*
X122308D01*
X122078Y379207D01*
X121887Y379465D01*
X121810Y379827D01*
X121925Y380188D01*
X122193Y380447D01*
X122500Y380550D01*
X122807Y380447D01*
X123075Y380188D01*
X123190Y379827D01*
X123113Y379465D01*
X122922Y379207D01*
X122692Y379103D01*
X122308D01*
X121963Y378948D01*
X121733Y378638D01*
X121657Y378277D01*
X121733Y377915D01*
X121925Y377657D01*
X122232Y377502D01*
X122500Y377450D01*
G01X125523D02*
X125600Y378122D01*
X125715Y378690D01*
X125868Y379207D01*
X126060Y379775D01*
X126367Y380550D01*
X124833D01*
G01X128700Y380442D02*
X128470Y380597D01*
X128202Y380700D01*
X127895D01*
X127550Y380545D01*
X127282Y380287D01*
X127090Y379977D01*
X126937Y379460D01*
X126899Y378995D01*
X126975Y378530D01*
X127090Y378220D01*
X127320Y377910D01*
X127589Y377703D01*
X127857Y377600D01*
X128125D01*
X128394Y377703D01*
X128624Y377858D01*
X128815Y378065D01*
G01X130957Y377600D02*
X131225Y377652D01*
X131532Y377807D01*
X131724Y378065D01*
X131800Y378427D01*
X131724Y378788D01*
X131494Y379098D01*
X131149Y379253D01*
X130765D01*
X130535Y379357D01*
X130344Y379615D01*
X130267Y379977D01*
X130382Y380338D01*
X130650Y380597D01*
X130957Y380700D01*
X131264Y380597D01*
X131532Y380338D01*
X131647Y379977D01*
X131570Y379615D01*
X131379Y379357D01*
X131149Y379253D01*
X130765D01*
X130420Y379098D01*
X130190Y378788D01*
X130114Y378427D01*
X130190Y378065D01*
X130382Y377807D01*
X130689Y377652D01*
X130957Y377600D01*
G01X133329Y378892D02*
X133597Y379253D01*
X133827Y379460D01*
X134134Y379563D01*
X134402Y379460D01*
X134594Y379253D01*
X134747Y378943D01*
X134785Y378582D01*
X134747Y378272D01*
X134594Y377962D01*
X134364Y377703D01*
X134095Y377600D01*
X133789Y377703D01*
X133520Y378013D01*
X133367Y378478D01*
X133329Y378995D01*
X133405Y379667D01*
X133520Y380028D01*
X133712Y380390D01*
X133980Y380648D01*
X134249Y380700D01*
X134517Y380597D01*
X134709Y380338D01*
G01X119583Y373966D02*
Y377066D01*
X120542D01*
X120848Y376911D01*
X121040Y376704D01*
X121117Y376291D01*
X121040Y375878D01*
X120810Y375619D01*
X120542Y375464D01*
X119583D01*
G01X120542D02*
X121117Y373966D01*
G01X123910D02*
Y377066D01*
X122492Y374844D01*
X124408D01*
G01X125707Y374431D02*
X125937Y374173D01*
X126205Y374018D01*
X126550Y373966D01*
X126895Y374069D01*
X127163Y374276D01*
X127355Y374638D01*
X127393Y375051D01*
X127317Y375464D01*
X127125Y375723D01*
X126857Y375929D01*
X126588Y375981D01*
X126320Y375929D01*
X125975Y375723D01*
X126090Y377066D01*
X127125D01*
G01X128807Y374431D02*
X129037Y374173D01*
X129305Y374018D01*
X129650Y373966D01*
X129995Y374069D01*
X130263Y374276D01*
X130455Y374638D01*
X130493Y375051D01*
X130417Y375464D01*
X130225Y375723D01*
X129957Y375929D01*
X129688Y375981D01*
X129420Y375929D01*
X129075Y375723D01*
X129190Y377066D01*
X130225D01*
G01X116272Y397533D02*
X116502Y397843D01*
X116770Y397998D01*
X117077Y398050D01*
X117460Y397947D01*
X117728Y397688D01*
X117805Y397378D01*
X117767Y397068D01*
X117613Y396810D01*
X116847Y396293D01*
X116502Y395932D01*
X116272Y395415D01*
X116195Y394950D01*
X117805D01*
G01X139470Y104493D02*
Y107593D01*
X140467Y105010D01*
X141464Y107593D01*
Y104493D01*
G01X144334D02*
X142800D01*
Y107593D01*
X144334D01*
G01X143720Y106095D02*
X142800D01*
G01X146590Y104493D02*
X146667Y105165D01*
X146782Y105733D01*
X146935Y106250D01*
X147127Y106818D01*
X147434Y107593D01*
X145900D01*
G01X141970Y266493D02*
Y269593D01*
X142967Y267010D01*
X143964Y269593D01*
Y266493D01*
G01X146834D02*
X145300D01*
Y269593D01*
X146834D01*
G01X146220Y268095D02*
X145300D01*
G01X148324Y266958D02*
X148554Y266700D01*
X148822Y266545D01*
X149167Y266493D01*
X149512Y266596D01*
X149780Y266803D01*
X149972Y267165D01*
X150010Y267578D01*
X149934Y267991D01*
X149742Y268250D01*
X149474Y268456D01*
X149205Y268508D01*
X148937Y268456D01*
X148592Y268250D01*
X148707Y269593D01*
X149742D01*
G01X144192Y300193D02*
X144037Y299963D01*
X143934Y299695D01*
Y299388D01*
X144089Y299043D01*
X144347Y298775D01*
X144657Y298583D01*
X145174Y298430D01*
X145639Y298392D01*
X146104Y298468D01*
X146414Y298583D01*
X146724Y298813D01*
X146931Y299082D01*
X147034Y299350D01*
Y299618D01*
X146931Y299887D01*
X146776Y300117D01*
X146569Y300308D01*
G01X146414Y301607D02*
X146776Y301837D01*
X146982Y302143D01*
X147034Y302488D01*
X146982Y302795D01*
X146724Y303102D01*
X146414Y303293D01*
X146104Y303332D01*
X145742Y303255D01*
X145484Y302987D01*
X145381Y302718D01*
Y302373D01*
G01Y302718D02*
X145226Y302948D01*
X144967Y303140D01*
X144657Y303217D01*
X144347Y303140D01*
X144089Y302948D01*
X143934Y302603D01*
X143986Y302258D01*
X144192Y301913D01*
G01X143934Y305550D02*
X144037Y305243D01*
X144296Y305013D01*
X144606Y304860D01*
X145019Y304745D01*
X145484Y304707D01*
X145949Y304745D01*
X146362Y304860D01*
X146672Y305013D01*
X146931Y305243D01*
X147034Y305550D01*
X146931Y305857D01*
X146672Y306087D01*
X146362Y306240D01*
X145949Y306355D01*
X145484Y306393D01*
X145019Y306355D01*
X144606Y306240D01*
X144296Y306087D01*
X144037Y305857D01*
X143934Y305550D01*
G01X147034Y308650D02*
X146982Y308918D01*
X146827Y309225D01*
X146569Y309417D01*
X146207Y309493D01*
X145846Y309417D01*
X145536Y309187D01*
X145381Y308842D01*
Y308458D01*
X145277Y308228D01*
X145019Y308037D01*
X144657Y307960D01*
X144296Y308075D01*
X144037Y308343D01*
X143934Y308650D01*
X144037Y308957D01*
X144296Y309225D01*
X144657Y309340D01*
X145019Y309263D01*
X145277Y309072D01*
X145381Y308842D01*
Y308458D01*
X145536Y308113D01*
X145846Y307883D01*
X146207Y307807D01*
X146569Y307883D01*
X146827Y308075D01*
X146982Y308382D01*
X147034Y308650D01*
G01X145083Y293966D02*
Y297066D01*
X146042D01*
X146348Y296911D01*
X146540Y296704D01*
X146617Y296291D01*
X146540Y295878D01*
X146310Y295619D01*
X146042Y295464D01*
X145083D01*
G01X146042D02*
X146617Y293966D01*
G01X149410D02*
Y297066D01*
X147992Y294844D01*
X149908D01*
G01X152050Y293966D02*
X152318Y294018D01*
X152625Y294173D01*
X152817Y294431D01*
X152893Y294793D01*
X152817Y295154D01*
X152587Y295464D01*
X152242Y295619D01*
X151858D01*
X151628Y295723D01*
X151437Y295981D01*
X151360Y296343D01*
X151475Y296704D01*
X151743Y296963D01*
X152050Y297066D01*
X152357Y296963D01*
X152625Y296704D01*
X152740Y296343D01*
X152663Y295981D01*
X152472Y295723D01*
X152242Y295619D01*
X151858D01*
X151513Y295464D01*
X151283Y295154D01*
X151207Y294793D01*
X151283Y294431D01*
X151475Y294173D01*
X151782Y294018D01*
X152050Y293966D01*
G01X154498Y294328D02*
X154767Y294069D01*
X155073Y293966D01*
X155380Y294069D01*
X155648Y294379D01*
X155840Y294844D01*
X155917Y295309D01*
Y295878D01*
X155840Y296343D01*
X155648Y296756D01*
X155418Y296963D01*
X155150Y297066D01*
X154843Y296963D01*
X154613Y296756D01*
X154460Y296446D01*
X154383Y296033D01*
X154460Y295671D01*
X154652Y295309D01*
X154882Y295103D01*
X155150Y295051D01*
X155457Y295154D01*
X155687Y295413D01*
X155917Y295878D01*
G01X149192Y314693D02*
X149037Y314463D01*
X148934Y314195D01*
Y313888D01*
X149089Y313543D01*
X149347Y313275D01*
X149657Y313083D01*
X150174Y312930D01*
X150639Y312892D01*
X151104Y312968D01*
X151414Y313083D01*
X151724Y313313D01*
X151931Y313582D01*
X152034Y313850D01*
Y314118D01*
X151931Y314387D01*
X151776Y314617D01*
X151569Y314808D01*
G01X151414Y316107D02*
X151776Y316337D01*
X151982Y316643D01*
X152034Y316988D01*
X151982Y317295D01*
X151724Y317602D01*
X151414Y317793D01*
X151104Y317832D01*
X150742Y317755D01*
X150484Y317487D01*
X150381Y317218D01*
Y316873D01*
G01Y317218D02*
X150226Y317448D01*
X149967Y317640D01*
X149657Y317717D01*
X149347Y317640D01*
X149089Y317448D01*
X148934Y317103D01*
X148986Y316758D01*
X149192Y316413D01*
G01X148934Y320050D02*
X149037Y319743D01*
X149296Y319513D01*
X149606Y319360D01*
X150019Y319245D01*
X150484Y319207D01*
X150949Y319245D01*
X151362Y319360D01*
X151672Y319513D01*
X151931Y319743D01*
X152034Y320050D01*
X151931Y320357D01*
X151672Y320587D01*
X151362Y320740D01*
X150949Y320855D01*
X150484Y320893D01*
X150019Y320855D01*
X149606Y320740D01*
X149296Y320587D01*
X149037Y320357D01*
X148934Y320050D01*
G01X151672Y322498D02*
X151931Y322767D01*
X152034Y323073D01*
X151931Y323380D01*
X151621Y323648D01*
X151156Y323840D01*
X150691Y323917D01*
X150122D01*
X149657Y323840D01*
X149244Y323648D01*
X149037Y323418D01*
X148934Y323150D01*
X149037Y322843D01*
X149244Y322613D01*
X149554Y322460D01*
X149967Y322383D01*
X150329Y322460D01*
X150691Y322652D01*
X150897Y322882D01*
X150949Y323150D01*
X150846Y323457D01*
X150587Y323687D01*
X150122Y323917D01*
G01X142999Y312414D02*
X146099D01*
Y313948D01*
G01X143516Y315553D02*
X143206Y315783D01*
X143051Y316051D01*
X142999Y316358D01*
X143102Y316741D01*
X143361Y317009D01*
X143671Y317086D01*
X143981Y317048D01*
X144239Y316894D01*
X144756Y316128D01*
X145117Y315783D01*
X145634Y315553D01*
X146099Y315476D01*
Y317086D01*
G01Y319841D02*
X142999D01*
X145221Y318423D01*
Y320339D01*
G01X142550Y318331D02*
X139450D01*
X141672Y316913D01*
Y318829D01*
G01X142188Y320319D02*
X142447Y320588D01*
X142550Y320894D01*
X142447Y321201D01*
X142137Y321469D01*
X141672Y321661D01*
X141207Y321738D01*
X140638D01*
X140173Y321661D01*
X139760Y321469D01*
X139553Y321239D01*
X139450Y320971D01*
X139553Y320664D01*
X139760Y320434D01*
X140070Y320281D01*
X140483Y320204D01*
X140845Y320281D01*
X141207Y320473D01*
X141413Y320703D01*
X141465Y320971D01*
X141362Y321278D01*
X141103Y321508D01*
X140638Y321738D01*
G01X141298Y348161D02*
X140937Y348429D01*
X140730Y348659D01*
X140627Y348966D01*
X140730Y349234D01*
X140937Y349426D01*
X141247Y349579D01*
X141608Y349617D01*
X141918Y349579D01*
X142228Y349426D01*
X142487Y349196D01*
X142590Y348927D01*
X142487Y348621D01*
X142177Y348352D01*
X141712Y348199D01*
X141195Y348161D01*
X140523Y348237D01*
X140162Y348352D01*
X139800Y348544D01*
X139542Y348812D01*
X139490Y349081D01*
X139593Y349349D01*
X139852Y349541D01*
G01X142590Y352449D02*
X139490D01*
X141712Y351031D01*
Y352947D01*
G01X143208Y370243D02*
X143053Y370013D01*
X142950Y369745D01*
Y369438D01*
X143105Y369093D01*
X143363Y368825D01*
X143673Y368633D01*
X144190Y368480D01*
X144655Y368442D01*
X145120Y368518D01*
X145430Y368633D01*
X145740Y368863D01*
X145947Y369132D01*
X146050Y369400D01*
Y369668D01*
X145947Y369937D01*
X145792Y370167D01*
X145585Y370358D01*
G01X146050Y372423D02*
X145378Y372500D01*
X144810Y372615D01*
X144293Y372768D01*
X143725Y372960D01*
X142950Y373267D01*
Y371733D01*
G01X146050Y376060D02*
X142950D01*
X145172Y374642D01*
Y376558D01*
G01X135460Y381950D02*
Y385050D01*
X134042Y382828D01*
X135958D01*
G01X143843Y391392D02*
X143613Y391547D01*
X143345Y391650D01*
X143038D01*
X142693Y391495D01*
X142425Y391237D01*
X142233Y390927D01*
X142080Y390410D01*
X142042Y389945D01*
X142118Y389480D01*
X142233Y389170D01*
X142463Y388860D01*
X142732Y388653D01*
X143000Y388550D01*
X143268D01*
X143537Y388653D01*
X143767Y388808D01*
X143958Y389015D01*
G01X146023Y388550D02*
X146100Y389222D01*
X146215Y389790D01*
X146368Y390307D01*
X146560Y390875D01*
X146867Y391650D01*
X145333D01*
G01X148357Y389015D02*
X148587Y388757D01*
X148855Y388602D01*
X149200Y388550D01*
X149545Y388653D01*
X149813Y388860D01*
X150005Y389222D01*
X150043Y389635D01*
X149967Y390048D01*
X149775Y390307D01*
X149507Y390513D01*
X149238Y390565D01*
X148970Y390513D01*
X148625Y390307D01*
X148740Y391650D01*
X149775D01*
G01X139183Y383550D02*
Y386650D01*
X140142D01*
X140448Y386495D01*
X140640Y386288D01*
X140717Y385875D01*
X140640Y385462D01*
X140410Y385203D01*
X140142Y385048D01*
X139183D01*
G01X140142D02*
X140717Y383550D01*
G01X142322Y386133D02*
X142552Y386443D01*
X142820Y386598D01*
X143127Y386650D01*
X143510Y386547D01*
X143778Y386288D01*
X143855Y385978D01*
X143817Y385668D01*
X143663Y385410D01*
X142897Y384893D01*
X142552Y384532D01*
X142322Y384015D01*
X142245Y383550D01*
X143855D01*
G01X145498Y383912D02*
X145767Y383653D01*
X146073Y383550D01*
X146380Y383653D01*
X146648Y383963D01*
X146840Y384428D01*
X146917Y384893D01*
Y385462D01*
X146840Y385927D01*
X146648Y386340D01*
X146418Y386547D01*
X146150Y386650D01*
X145843Y386547D01*
X145613Y386340D01*
X145460Y386030D01*
X145383Y385617D01*
X145460Y385255D01*
X145652Y384893D01*
X145882Y384687D01*
X146150Y384635D01*
X146457Y384738D01*
X146687Y384997D01*
X146917Y385462D01*
G01X149710Y383550D02*
Y386650D01*
X148292Y384428D01*
X150208D01*
G01X143343Y400392D02*
X143113Y400547D01*
X142845Y400650D01*
X142538D01*
X142193Y400495D01*
X141925Y400237D01*
X141733Y399927D01*
X141580Y399410D01*
X141542Y398945D01*
X141618Y398480D01*
X141733Y398170D01*
X141963Y397860D01*
X142232Y397653D01*
X142500Y397550D01*
X142768D01*
X143037Y397653D01*
X143267Y397808D01*
X143458Y398015D01*
G01X144757Y398170D02*
X144987Y397808D01*
X145293Y397602D01*
X145638Y397550D01*
X145945Y397602D01*
X146252Y397860D01*
X146443Y398170D01*
X146482Y398480D01*
X146405Y398842D01*
X146137Y399100D01*
X145868Y399203D01*
X145523D01*
G01X145868D02*
X146098Y399358D01*
X146290Y399617D01*
X146367Y399927D01*
X146290Y400237D01*
X146098Y400495D01*
X145753Y400650D01*
X145408Y400598D01*
X145063Y400392D01*
G01X148700Y397550D02*
Y400650D01*
X148240Y400030D01*
G01Y397550D02*
X149160D01*
G01X143343Y395892D02*
X143113Y396047D01*
X142845Y396150D01*
X142538D01*
X142193Y395995D01*
X141925Y395737D01*
X141733Y395427D01*
X141580Y394910D01*
X141542Y394445D01*
X141618Y393980D01*
X141733Y393670D01*
X141963Y393360D01*
X142232Y393153D01*
X142500Y393050D01*
X142768D01*
X143037Y393153D01*
X143267Y393308D01*
X143458Y393515D01*
G01X144872Y395633D02*
X145102Y395943D01*
X145370Y396098D01*
X145677Y396150D01*
X146060Y396047D01*
X146328Y395788D01*
X146405Y395478D01*
X146367Y395168D01*
X146213Y394910D01*
X145447Y394393D01*
X145102Y394032D01*
X144872Y393515D01*
X144795Y393050D01*
X146405D01*
G01X148048Y393412D02*
X148317Y393153D01*
X148623Y393050D01*
X148930Y393153D01*
X149198Y393463D01*
X149390Y393928D01*
X149467Y394393D01*
Y394962D01*
X149390Y395427D01*
X149198Y395840D01*
X148968Y396047D01*
X148700Y396150D01*
X148393Y396047D01*
X148163Y395840D01*
X148010Y395530D01*
X147933Y395117D01*
X148010Y394755D01*
X148202Y394393D01*
X148432Y394187D01*
X148700Y394135D01*
X149007Y394238D01*
X149237Y394497D01*
X149467Y394962D01*
G01X143843Y404392D02*
X143613Y404547D01*
X143345Y404650D01*
X143038D01*
X142693Y404495D01*
X142425Y404237D01*
X142233Y403927D01*
X142080Y403410D01*
X142042Y402945D01*
X142118Y402480D01*
X142233Y402170D01*
X142463Y401860D01*
X142732Y401653D01*
X143000Y401550D01*
X143268D01*
X143537Y401653D01*
X143767Y401808D01*
X143958Y402015D01*
G01X146560Y401550D02*
Y404650D01*
X145142Y402428D01*
X147058D01*
G01X148357Y402170D02*
X148587Y401808D01*
X148893Y401602D01*
X149238Y401550D01*
X149545Y401602D01*
X149852Y401860D01*
X150043Y402170D01*
X150082Y402480D01*
X150005Y402842D01*
X149737Y403100D01*
X149468Y403203D01*
X149123D01*
G01X149468D02*
X149698Y403358D01*
X149890Y403617D01*
X149967Y403927D01*
X149890Y404237D01*
X149698Y404495D01*
X149353Y404650D01*
X149008Y404598D01*
X148663Y404392D01*
G01X143343Y409892D02*
X143113Y410047D01*
X142845Y410150D01*
X142538D01*
X142193Y409995D01*
X141925Y409737D01*
X141733Y409427D01*
X141580Y408910D01*
X141542Y408445D01*
X141618Y407980D01*
X141733Y407670D01*
X141963Y407360D01*
X142232Y407153D01*
X142500Y407050D01*
X142768D01*
X143037Y407153D01*
X143267Y407308D01*
X143458Y407515D01*
G01X145600Y407050D02*
Y410150D01*
X145140Y409530D01*
G01Y407050D02*
X146060D01*
G01X148700D02*
Y410150D01*
X148240Y409530D01*
G01Y407050D02*
X149160D01*
G01X140050Y408183D02*
X136950D01*
Y409142D01*
X137105Y409448D01*
X137312Y409640D01*
X137725Y409717D01*
X138138Y409640D01*
X138397Y409410D01*
X138552Y409142D01*
Y408183D01*
G01Y409142D02*
X140050Y409717D01*
G01X138758Y411322D02*
X138397Y411590D01*
X138190Y411820D01*
X138087Y412127D01*
X138190Y412395D01*
X138397Y412587D01*
X138707Y412740D01*
X139068Y412778D01*
X139378Y412740D01*
X139688Y412587D01*
X139947Y412357D01*
X140050Y412088D01*
X139947Y411782D01*
X139637Y411513D01*
X139172Y411360D01*
X138655Y411322D01*
X137983Y411398D01*
X137622Y411513D01*
X137260Y411705D01*
X137002Y411973D01*
X136950Y412242D01*
X137053Y412510D01*
X137312Y412702D01*
G01X141733Y412650D02*
Y415750D01*
X142692D01*
X142998Y415595D01*
X143190Y415388D01*
X143267Y414975D01*
X143190Y414562D01*
X142960Y414303D01*
X142692Y414148D01*
X141733D01*
G01X142692D02*
X143267Y412650D01*
G01X144757Y413270D02*
X144987Y412908D01*
X145293Y412702D01*
X145638Y412650D01*
X145945Y412702D01*
X146252Y412960D01*
X146443Y413270D01*
X146482Y413580D01*
X146405Y413942D01*
X146137Y414200D01*
X145868Y414303D01*
X145523D01*
G01X145868D02*
X146098Y414458D01*
X146290Y414717D01*
X146367Y415027D01*
X146290Y415337D01*
X146098Y415595D01*
X145753Y415750D01*
X145408Y415698D01*
X145063Y415492D01*
G01X149160Y412650D02*
Y415750D01*
X147742Y413528D01*
X149658D01*
G01X162070Y56500D02*
X162338Y56552D01*
X162645Y56707D01*
X162837Y56965D01*
X162913Y57327D01*
X162837Y57688D01*
X162607Y57998D01*
X162262Y58153D01*
X161878D01*
X161648Y58257D01*
X161457Y58515D01*
X161380Y58877D01*
X161495Y59238D01*
X161763Y59497D01*
X162070Y59600D01*
X162377Y59497D01*
X162645Y59238D01*
X162760Y58877D01*
X162683Y58515D01*
X162492Y58257D01*
X162262Y58153D01*
X161878D01*
X161533Y57998D01*
X161303Y57688D01*
X161227Y57327D01*
X161303Y56965D01*
X161495Y56707D01*
X161802Y56552D01*
X162070Y56500D01*
G01X153508Y61963D02*
X153353Y61733D01*
X153250Y61465D01*
Y61158D01*
X153405Y60813D01*
X153663Y60545D01*
X153973Y60353D01*
X154490Y60200D01*
X154955Y60162D01*
X155420Y60238D01*
X155730Y60353D01*
X156040Y60583D01*
X156247Y60852D01*
X156350Y61120D01*
Y61388D01*
X156247Y61657D01*
X156092Y61887D01*
X155885Y62078D01*
G01X156350Y64220D02*
X153250D01*
X153870Y63760D01*
G01X156350D02*
Y64680D01*
G01Y67243D02*
X155678Y67320D01*
X155110Y67435D01*
X154593Y67588D01*
X154025Y67780D01*
X153250Y68087D01*
Y66553D01*
G01X161127Y71965D02*
X161357Y71707D01*
X161625Y71552D01*
X161970Y71500D01*
X162315Y71603D01*
X162583Y71810D01*
X162775Y72172D01*
X162813Y72585D01*
X162737Y72998D01*
X162545Y73257D01*
X162277Y73463D01*
X162008Y73515D01*
X161740Y73463D01*
X161395Y73257D01*
X161510Y74600D01*
X162545D01*
G01X168693Y291292D02*
X168463Y291447D01*
X168195Y291550D01*
X167888D01*
X167543Y291395D01*
X167275Y291137D01*
X167083Y290827D01*
X166930Y290310D01*
X166892Y289845D01*
X166968Y289380D01*
X167083Y289070D01*
X167313Y288760D01*
X167582Y288553D01*
X167850Y288450D01*
X168118D01*
X168387Y288553D01*
X168617Y288708D01*
X168808Y288915D01*
G01X170107Y289070D02*
X170337Y288708D01*
X170643Y288502D01*
X170988Y288450D01*
X171295Y288502D01*
X171602Y288760D01*
X171793Y289070D01*
X171832Y289380D01*
X171755Y289742D01*
X171487Y290000D01*
X171218Y290103D01*
X170873D01*
G01X171218D02*
X171448Y290258D01*
X171640Y290517D01*
X171717Y290827D01*
X171640Y291137D01*
X171448Y291395D01*
X171103Y291550D01*
X170758Y291498D01*
X170413Y291292D01*
G01X174050Y291550D02*
X173743Y291447D01*
X173513Y291188D01*
X173360Y290878D01*
X173245Y290465D01*
X173207Y290000D01*
X173245Y289535D01*
X173360Y289122D01*
X173513Y288812D01*
X173743Y288553D01*
X174050Y288450D01*
X174357Y288553D01*
X174587Y288812D01*
X174740Y289122D01*
X174855Y289535D01*
X174893Y290000D01*
X174855Y290465D01*
X174740Y290878D01*
X174587Y291188D01*
X174357Y291447D01*
X174050Y291550D01*
G01X177073Y288450D02*
X177150Y289122D01*
X177265Y289690D01*
X177418Y290207D01*
X177610Y290775D01*
X177917Y291550D01*
X176383D01*
G01X154550Y299083D02*
X151450D01*
Y300042D01*
X151605Y300348D01*
X151812Y300540D01*
X152225Y300617D01*
X152638Y300540D01*
X152897Y300310D01*
X153052Y300042D01*
Y299083D01*
G01Y300042D02*
X154550Y300617D01*
G01Y303410D02*
X151450D01*
X153672Y301992D01*
Y303908D01*
G01X154188Y305398D02*
X154447Y305667D01*
X154550Y305973D01*
X154447Y306280D01*
X154137Y306548D01*
X153672Y306740D01*
X153207Y306817D01*
X152638D01*
X152173Y306740D01*
X151760Y306548D01*
X151553Y306318D01*
X151450Y306050D01*
X151553Y305743D01*
X151760Y305513D01*
X152070Y305360D01*
X152483Y305283D01*
X152845Y305360D01*
X153207Y305552D01*
X153413Y305782D01*
X153465Y306050D01*
X153362Y306357D01*
X153103Y306587D01*
X152638Y306817D01*
G01X151450Y309150D02*
X151553Y308843D01*
X151812Y308613D01*
X152122Y308460D01*
X152535Y308345D01*
X153000Y308307D01*
X153465Y308345D01*
X153878Y308460D01*
X154188Y308613D01*
X154447Y308843D01*
X154550Y309150D01*
X154447Y309457D01*
X154188Y309687D01*
X153878Y309840D01*
X153465Y309955D01*
X153000Y309993D01*
X152535Y309955D01*
X152122Y309840D01*
X151812Y309687D01*
X151553Y309457D01*
X151450Y309150D01*
G01X157413Y295825D02*
X157573Y295617D01*
X157760Y295492D01*
X158000Y295450D01*
X158240Y295533D01*
X158427Y295700D01*
X158560Y295992D01*
X158587Y296325D01*
X158533Y296658D01*
X158400Y296867D01*
X158213Y297033D01*
X158027Y297075D01*
X157840Y297033D01*
X157600Y296867D01*
X157680Y297950D01*
X158400D01*
G01X165063Y302943D02*
Y300721D01*
X165216Y300256D01*
X165523Y299946D01*
X165906Y299843D01*
X166289Y299946D01*
X166596Y300256D01*
X166749Y300721D01*
Y302943D01*
G01X169466Y299843D02*
Y302943D01*
X168048Y300721D01*
X169964D01*
G01X172106Y299843D02*
Y302943D01*
X171646Y302323D01*
G01Y299843D02*
X172566D01*
G01X161743Y317774D02*
X161513Y317929D01*
X161245Y318032D01*
X160938D01*
X160593Y317877D01*
X160325Y317619D01*
X160133Y317309D01*
X159980Y316792D01*
X159942Y316327D01*
X160018Y315862D01*
X160133Y315552D01*
X160363Y315242D01*
X160632Y315035D01*
X160900Y314932D01*
X161168D01*
X161437Y315035D01*
X161667Y315190D01*
X161858Y315397D01*
G01X163233Y314932D02*
Y318032D01*
X164192D01*
X164498Y317877D01*
X164690Y317670D01*
X164767Y317257D01*
X164690Y316844D01*
X164460Y316585D01*
X164192Y316430D01*
X163233D01*
G01X164192D02*
X164767Y314932D01*
G01X166372Y317515D02*
X166602Y317825D01*
X166870Y317980D01*
X167177Y318032D01*
X167560Y317929D01*
X167828Y317670D01*
X167905Y317360D01*
X167867Y317050D01*
X167713Y316792D01*
X166947Y316275D01*
X166602Y315914D01*
X166372Y315397D01*
X166295Y314932D01*
X167905D01*
G01X154136Y316222D02*
X155094Y319322D01*
X156052Y316222D01*
G01X155707Y317307D02*
X154481D01*
G01X161743Y327774D02*
X161513Y327929D01*
X161245Y328032D01*
X160938D01*
X160593Y327877D01*
X160325Y327619D01*
X160133Y327309D01*
X159980Y326792D01*
X159942Y326327D01*
X160018Y325862D01*
X160133Y325552D01*
X160363Y325242D01*
X160632Y325035D01*
X160900Y324932D01*
X161168D01*
X161437Y325035D01*
X161667Y325190D01*
X161858Y325397D01*
G01X163233Y324932D02*
Y328032D01*
X164192D01*
X164498Y327877D01*
X164690Y327670D01*
X164767Y327257D01*
X164690Y326844D01*
X164460Y326585D01*
X164192Y326430D01*
X163233D01*
G01X164192D02*
X164767Y324932D01*
G01X167100D02*
Y328032D01*
X166640Y327412D01*
G01Y324932D02*
X167560D01*
G01X154136Y326222D02*
X155094Y329322D01*
X156052Y326222D01*
G01X155707Y327307D02*
X154481D01*
G01X167243Y384842D02*
X167013Y384997D01*
X166745Y385100D01*
X166438D01*
X166093Y384945D01*
X165825Y384687D01*
X165633Y384377D01*
X165480Y383860D01*
X165442Y383395D01*
X165518Y382930D01*
X165633Y382620D01*
X165863Y382310D01*
X166132Y382103D01*
X166400Y382000D01*
X166668D01*
X166937Y382103D01*
X167167Y382258D01*
X167358Y382465D01*
G01X169960Y382000D02*
Y385100D01*
X168542Y382878D01*
X170458D01*
G01X172600Y382000D02*
Y385100D01*
X172140Y384480D01*
G01Y382000D02*
X173060D01*
G01X168843Y378892D02*
X168613Y379047D01*
X168345Y379150D01*
X168038D01*
X167693Y378995D01*
X167425Y378737D01*
X167233Y378427D01*
X167080Y377910D01*
X167042Y377445D01*
X167118Y376980D01*
X167233Y376670D01*
X167463Y376360D01*
X167732Y376153D01*
X168000Y376050D01*
X168268D01*
X168537Y376153D01*
X168767Y376308D01*
X168958Y376515D01*
G01X170257Y376670D02*
X170487Y376308D01*
X170793Y376102D01*
X171138Y376050D01*
X171445Y376102D01*
X171752Y376360D01*
X171943Y376670D01*
X171982Y376980D01*
X171905Y377342D01*
X171637Y377600D01*
X171368Y377703D01*
X171023D01*
G01X171368D02*
X171598Y377858D01*
X171790Y378117D01*
X171867Y378427D01*
X171790Y378737D01*
X171598Y378995D01*
X171253Y379150D01*
X170908Y379098D01*
X170563Y378892D01*
G01X173472Y378633D02*
X173702Y378943D01*
X173970Y379098D01*
X174277Y379150D01*
X174660Y379047D01*
X174928Y378788D01*
X175005Y378478D01*
X174967Y378168D01*
X174813Y377910D01*
X174047Y377393D01*
X173702Y377032D01*
X173472Y376515D01*
X173395Y376050D01*
X175005D01*
G01X151950Y389500D02*
Y392600D01*
X151490Y391980D01*
G01Y389500D02*
X152410D01*
G01X155050D02*
X155318Y389552D01*
X155625Y389707D01*
X155817Y389965D01*
X155893Y390327D01*
X155817Y390688D01*
X155587Y390998D01*
X155242Y391153D01*
X154858D01*
X154628Y391257D01*
X154437Y391515D01*
X154360Y391877D01*
X154475Y392238D01*
X154743Y392497D01*
X155050Y392600D01*
X155357Y392497D01*
X155625Y392238D01*
X155740Y391877D01*
X155663Y391515D01*
X155472Y391257D01*
X155242Y391153D01*
X154858D01*
X154513Y390998D01*
X154283Y390688D01*
X154207Y390327D01*
X154283Y389965D01*
X154475Y389707D01*
X154782Y389552D01*
X155050Y389500D01*
G01X152452Y379233D02*
Y376133D01*
X153986D01*
G01X156242D02*
X156319Y376805D01*
X156434Y377373D01*
X156587Y377890D01*
X156779Y378458D01*
X157086Y379233D01*
X155552D01*
G01X162743Y410842D02*
X162513Y410997D01*
X162245Y411100D01*
X161938D01*
X161593Y410945D01*
X161325Y410687D01*
X161133Y410377D01*
X160980Y409860D01*
X160942Y409395D01*
X161018Y408930D01*
X161133Y408620D01*
X161363Y408310D01*
X161632Y408103D01*
X161900Y408000D01*
X162168D01*
X162437Y408103D01*
X162667Y408258D01*
X162858Y408465D01*
G01X164157Y408620D02*
X164387Y408258D01*
X164693Y408052D01*
X165038Y408000D01*
X165345Y408052D01*
X165652Y408310D01*
X165843Y408620D01*
X165882Y408930D01*
X165805Y409292D01*
X165537Y409550D01*
X165268Y409653D01*
X164923D01*
G01X165268D02*
X165498Y409808D01*
X165690Y410067D01*
X165767Y410377D01*
X165690Y410687D01*
X165498Y410945D01*
X165153Y411100D01*
X164808Y411048D01*
X164463Y410842D01*
G01X167257Y408620D02*
X167487Y408258D01*
X167793Y408052D01*
X168138Y408000D01*
X168445Y408052D01*
X168752Y408310D01*
X168943Y408620D01*
X168982Y408930D01*
X168905Y409292D01*
X168637Y409550D01*
X168368Y409653D01*
X168023D01*
G01X168368D02*
X168598Y409808D01*
X168790Y410067D01*
X168867Y410377D01*
X168790Y410687D01*
X168598Y410945D01*
X168253Y411100D01*
X167908Y411048D01*
X167563Y410842D01*
G01X156450Y405500D02*
Y408600D01*
X155990Y407980D01*
G01Y405500D02*
X156910D01*
G01X158822Y408083D02*
X159052Y408393D01*
X159320Y408548D01*
X159627Y408600D01*
X160010Y408497D01*
X160278Y408238D01*
X160355Y407928D01*
X160317Y407618D01*
X160163Y407360D01*
X159397Y406843D01*
X159052Y406482D01*
X158822Y405965D01*
X158745Y405500D01*
X160355D01*
G01X152450Y401500D02*
Y404600D01*
X151990Y403980D01*
G01Y401500D02*
X152910D01*
G01X154707Y402120D02*
X154937Y401758D01*
X155243Y401552D01*
X155588Y401500D01*
X155895Y401552D01*
X156202Y401810D01*
X156393Y402120D01*
X156432Y402430D01*
X156355Y402792D01*
X156087Y403050D01*
X155818Y403153D01*
X155473D01*
G01X155818D02*
X156048Y403308D01*
X156240Y403567D01*
X156317Y403877D01*
X156240Y404187D01*
X156048Y404445D01*
X155703Y404600D01*
X155358Y404548D01*
X155013Y404342D01*
G01X162558Y394207D02*
X164780D01*
X165245Y394360D01*
X165555Y394667D01*
X165658Y395050D01*
X165555Y395433D01*
X165245Y395740D01*
X164780Y395893D01*
X162558D01*
G01X165193Y397307D02*
X165451Y397537D01*
X165606Y397805D01*
X165658Y398150D01*
X165555Y398495D01*
X165348Y398763D01*
X164986Y398955D01*
X164573Y398993D01*
X164160Y398917D01*
X163901Y398725D01*
X163695Y398457D01*
X163643Y398188D01*
X163695Y397920D01*
X163901Y397575D01*
X162558Y397690D01*
Y398725D01*
G01X165843Y416392D02*
X165613Y416547D01*
X165345Y416650D01*
X165038D01*
X164693Y416495D01*
X164425Y416237D01*
X164233Y415927D01*
X164080Y415410D01*
X164042Y414945D01*
X164118Y414480D01*
X164233Y414170D01*
X164463Y413860D01*
X164732Y413653D01*
X165000Y413550D01*
X165268D01*
X165537Y413653D01*
X165767Y413808D01*
X165958Y414015D01*
G01X167257Y414170D02*
X167487Y413808D01*
X167793Y413602D01*
X168138Y413550D01*
X168445Y413602D01*
X168752Y413860D01*
X168943Y414170D01*
X168982Y414480D01*
X168905Y414842D01*
X168637Y415100D01*
X168368Y415203D01*
X168023D01*
G01X168368D02*
X168598Y415358D01*
X168790Y415617D01*
X168867Y415927D01*
X168790Y416237D01*
X168598Y416495D01*
X168253Y416650D01*
X167908Y416598D01*
X167563Y416392D01*
G01X171200Y416650D02*
X170893Y416547D01*
X170663Y416288D01*
X170510Y415978D01*
X170395Y415565D01*
X170357Y415100D01*
X170395Y414635D01*
X170510Y414222D01*
X170663Y413912D01*
X170893Y413653D01*
X171200Y413550D01*
X171507Y413653D01*
X171737Y413912D01*
X171890Y414222D01*
X172005Y414635D01*
X172043Y415100D01*
X172005Y415565D01*
X171890Y415978D01*
X171737Y416288D01*
X171507Y416547D01*
X171200Y416650D01*
G01X157150Y410233D02*
X154050D01*
Y411192D01*
X154205Y411498D01*
X154412Y411690D01*
X154825Y411767D01*
X155238Y411690D01*
X155497Y411460D01*
X155652Y411192D01*
Y410233D01*
G01Y411192D02*
X157150Y411767D01*
G01X154567Y413372D02*
X154257Y413602D01*
X154102Y413870D01*
X154050Y414177D01*
X154153Y414560D01*
X154412Y414828D01*
X154722Y414905D01*
X155032Y414867D01*
X155290Y414713D01*
X155807Y413947D01*
X156168Y413602D01*
X156685Y413372D01*
X157150Y413295D01*
Y414905D01*
G01X156788Y416548D02*
X157047Y416817D01*
X157150Y417123D01*
X157047Y417430D01*
X156737Y417698D01*
X156272Y417890D01*
X155807Y417967D01*
X155238D01*
X154773Y417890D01*
X154360Y417698D01*
X154153Y417468D01*
X154050Y417200D01*
X154153Y416893D01*
X154360Y416663D01*
X154670Y416510D01*
X155083Y416433D01*
X155445Y416510D01*
X155807Y416702D01*
X156013Y416932D01*
X156065Y417200D01*
X155962Y417507D01*
X155703Y417737D01*
X155238Y417967D01*
G01X179081Y28901D02*
X179234Y29056D01*
X179349Y29315D01*
X179426Y29676D01*
X179349Y29986D01*
X179196Y30193D01*
X178927Y30348D01*
X177892D01*
Y27248D01*
X179157D01*
X179426Y27455D01*
X179579Y27765D01*
X179656Y28126D01*
X179579Y28488D01*
X179349Y28798D01*
X179081Y28901D01*
X177892D01*
G01X181874Y27248D02*
Y30348D01*
X181414Y29728D01*
G01Y27248D02*
X182334D01*
G01X174877Y68050D02*
Y65828D01*
X175030Y65363D01*
X175337Y65053D01*
X175720Y64950D01*
X176103Y65053D01*
X176410Y65363D01*
X176563Y65828D01*
Y68050D01*
G01X178092Y67533D02*
X178322Y67843D01*
X178590Y67998D01*
X178897Y68050D01*
X179280Y67947D01*
X179548Y67688D01*
X179625Y67378D01*
X179587Y67068D01*
X179433Y66810D01*
X178667Y66293D01*
X178322Y65932D01*
X178092Y65415D01*
X178015Y64950D01*
X179625D01*
G01X183693Y305792D02*
X183463Y305947D01*
X183195Y306050D01*
X182888D01*
X182543Y305895D01*
X182275Y305637D01*
X182083Y305327D01*
X181930Y304810D01*
X181892Y304345D01*
X181968Y303880D01*
X182083Y303570D01*
X182313Y303260D01*
X182582Y303053D01*
X182850Y302950D01*
X183118D01*
X183387Y303053D01*
X183617Y303208D01*
X183808Y303415D01*
G01X185107Y303570D02*
X185337Y303208D01*
X185643Y303002D01*
X185988Y302950D01*
X186295Y303002D01*
X186602Y303260D01*
X186793Y303570D01*
X186832Y303880D01*
X186755Y304242D01*
X186487Y304500D01*
X186218Y304603D01*
X185873D01*
G01X186218D02*
X186448Y304758D01*
X186640Y305017D01*
X186717Y305327D01*
X186640Y305637D01*
X186448Y305895D01*
X186103Y306050D01*
X185758Y305998D01*
X185413Y305792D01*
G01X189050Y306050D02*
X188743Y305947D01*
X188513Y305688D01*
X188360Y305378D01*
X188245Y304965D01*
X188207Y304500D01*
X188245Y304035D01*
X188360Y303622D01*
X188513Y303312D01*
X188743Y303053D01*
X189050Y302950D01*
X189357Y303053D01*
X189587Y303312D01*
X189740Y303622D01*
X189855Y304035D01*
X189893Y304500D01*
X189855Y304965D01*
X189740Y305378D01*
X189587Y305688D01*
X189357Y305947D01*
X189050Y306050D01*
G01X192610Y302950D02*
Y306050D01*
X191192Y303828D01*
X193108D01*
G01X184534Y290583D02*
X181434D01*
Y291542D01*
X181589Y291848D01*
X181796Y292040D01*
X182209Y292117D01*
X182622Y292040D01*
X182881Y291810D01*
X183036Y291542D01*
Y290583D01*
G01Y291542D02*
X184534Y292117D01*
G01Y294910D02*
X181434D01*
X183656Y293492D01*
Y295408D01*
G01X184534Y297550D02*
X184482Y297818D01*
X184327Y298125D01*
X184069Y298317D01*
X183707Y298393D01*
X183346Y298317D01*
X183036Y298087D01*
X182881Y297742D01*
Y297358D01*
X182777Y297128D01*
X182519Y296937D01*
X182157Y296860D01*
X181796Y296975D01*
X181537Y297243D01*
X181434Y297550D01*
X181537Y297857D01*
X181796Y298125D01*
X182157Y298240D01*
X182519Y298163D01*
X182777Y297972D01*
X182881Y297742D01*
Y297358D01*
X183036Y297013D01*
X183346Y296783D01*
X183707Y296707D01*
X184069Y296783D01*
X184327Y296975D01*
X184482Y297282D01*
X184534Y297550D01*
G01Y300573D02*
X183862Y300650D01*
X183294Y300765D01*
X182777Y300918D01*
X182209Y301110D01*
X181434Y301417D01*
Y299883D01*
G01X176993Y295992D02*
X177180Y296283D01*
X177340Y296450D01*
X177553Y296533D01*
X177740Y296450D01*
X177873Y296283D01*
X177980Y296033D01*
X178007Y295742D01*
X177980Y295492D01*
X177873Y295242D01*
X177713Y295033D01*
X177527Y294950D01*
X177313Y295033D01*
X177127Y295283D01*
X177020Y295658D01*
X176993Y296075D01*
X177047Y296617D01*
X177127Y296908D01*
X177260Y297200D01*
X177447Y297408D01*
X177633Y297450D01*
X177820Y297367D01*
X177953Y297158D01*
G01X180193Y320808D02*
X179963Y320963D01*
X179695Y321066D01*
X179388D01*
X179043Y320911D01*
X178775Y320653D01*
X178583Y320343D01*
X178430Y319826D01*
X178392Y319361D01*
X178468Y318896D01*
X178583Y318586D01*
X178813Y318276D01*
X179082Y318069D01*
X179350Y317966D01*
X179618D01*
X179887Y318069D01*
X180117Y318224D01*
X180308Y318431D01*
G01X181722Y320549D02*
X181952Y320859D01*
X182220Y321014D01*
X182527Y321066D01*
X182910Y320963D01*
X183178Y320704D01*
X183255Y320394D01*
X183217Y320084D01*
X183063Y319826D01*
X182297Y319309D01*
X181952Y318948D01*
X181722Y318431D01*
X181645Y317966D01*
X183255D01*
G01X184898Y318328D02*
X185167Y318069D01*
X185473Y317966D01*
X185780Y318069D01*
X186048Y318379D01*
X186240Y318844D01*
X186317Y319309D01*
Y319878D01*
X186240Y320343D01*
X186048Y320756D01*
X185818Y320963D01*
X185550Y321066D01*
X185243Y320963D01*
X185013Y320756D01*
X184860Y320446D01*
X184783Y320033D01*
X184860Y319671D01*
X185052Y319309D01*
X185282Y319103D01*
X185550Y319051D01*
X185857Y319154D01*
X186087Y319413D01*
X186317Y319878D01*
G01X188650Y317966D02*
X188918Y318018D01*
X189225Y318173D01*
X189417Y318431D01*
X189493Y318793D01*
X189417Y319154D01*
X189187Y319464D01*
X188842Y319619D01*
X188458D01*
X188228Y319723D01*
X188037Y319981D01*
X187960Y320343D01*
X188075Y320704D01*
X188343Y320963D01*
X188650Y321066D01*
X188957Y320963D01*
X189225Y320704D01*
X189340Y320343D01*
X189263Y319981D01*
X189072Y319723D01*
X188842Y319619D01*
X188458D01*
X188113Y319464D01*
X187883Y319154D01*
X187807Y318793D01*
X187883Y318431D01*
X188075Y318173D01*
X188382Y318018D01*
X188650Y317966D01*
G01X183693Y311792D02*
X183463Y311947D01*
X183195Y312050D01*
X182888D01*
X182543Y311895D01*
X182275Y311637D01*
X182083Y311327D01*
X181930Y310810D01*
X181892Y310345D01*
X181968Y309880D01*
X182083Y309570D01*
X182313Y309260D01*
X182582Y309053D01*
X182850Y308950D01*
X183118D01*
X183387Y309053D01*
X183617Y309208D01*
X183808Y309415D01*
G01X185107Y309570D02*
X185337Y309208D01*
X185643Y309002D01*
X185988Y308950D01*
X186295Y309002D01*
X186602Y309260D01*
X186793Y309570D01*
X186832Y309880D01*
X186755Y310242D01*
X186487Y310500D01*
X186218Y310603D01*
X185873D01*
G01X186218D02*
X186448Y310758D01*
X186640Y311017D01*
X186717Y311327D01*
X186640Y311637D01*
X186448Y311895D01*
X186103Y312050D01*
X185758Y311998D01*
X185413Y311792D01*
G01X189050Y312050D02*
X188743Y311947D01*
X188513Y311688D01*
X188360Y311378D01*
X188245Y310965D01*
X188207Y310500D01*
X188245Y310035D01*
X188360Y309622D01*
X188513Y309312D01*
X188743Y309053D01*
X189050Y308950D01*
X189357Y309053D01*
X189587Y309312D01*
X189740Y309622D01*
X189855Y310035D01*
X189893Y310500D01*
X189855Y310965D01*
X189740Y311378D01*
X189587Y311688D01*
X189357Y311947D01*
X189050Y312050D01*
G01X192150D02*
X191843Y311947D01*
X191613Y311688D01*
X191460Y311378D01*
X191345Y310965D01*
X191307Y310500D01*
X191345Y310035D01*
X191460Y309622D01*
X191613Y309312D01*
X191843Y309053D01*
X192150Y308950D01*
X192457Y309053D01*
X192687Y309312D01*
X192840Y309622D01*
X192955Y310035D01*
X192993Y310500D01*
X192955Y310965D01*
X192840Y311378D01*
X192687Y311688D01*
X192457Y311947D01*
X192150Y312050D01*
G01X174450Y312133D02*
X177550D01*
Y313667D01*
G01X174967Y315272D02*
X174657Y315502D01*
X174502Y315770D01*
X174450Y316077D01*
X174553Y316460D01*
X174812Y316728D01*
X175122Y316805D01*
X175432Y316767D01*
X175690Y316613D01*
X176207Y315847D01*
X176568Y315502D01*
X177085Y315272D01*
X177550Y315195D01*
Y316805D01*
G01X176930Y318257D02*
X177292Y318487D01*
X177498Y318793D01*
X177550Y319138D01*
X177498Y319445D01*
X177240Y319752D01*
X176930Y319943D01*
X176620Y319982D01*
X176258Y319905D01*
X176000Y319637D01*
X175897Y319368D01*
Y319023D01*
G01Y319368D02*
X175742Y319598D01*
X175483Y319790D01*
X175173Y319867D01*
X174863Y319790D01*
X174605Y319598D01*
X174450Y319253D01*
X174502Y318908D01*
X174708Y318563D01*
G01X175900Y306950D02*
Y309450D01*
X175580Y308950D01*
G01Y306950D02*
X176220D01*
G01X178100Y309450D02*
X177887Y309367D01*
X177727Y309158D01*
X177620Y308908D01*
X177540Y308575D01*
X177513Y308200D01*
X177540Y307825D01*
X177620Y307492D01*
X177727Y307242D01*
X177887Y307033D01*
X178100Y306950D01*
X178313Y307033D01*
X178473Y307242D01*
X178580Y307492D01*
X178660Y307825D01*
X178687Y308200D01*
X178660Y308575D01*
X178580Y308908D01*
X178473Y309158D01*
X178313Y309367D01*
X178100Y309450D01*
G01X171843Y322292D02*
X171613Y322447D01*
X171345Y322550D01*
X171038D01*
X170693Y322395D01*
X170425Y322137D01*
X170233Y321827D01*
X170080Y321310D01*
X170042Y320845D01*
X170118Y320380D01*
X170233Y320070D01*
X170463Y319760D01*
X170732Y319553D01*
X171000Y319450D01*
X171268D01*
X171537Y319553D01*
X171767Y319708D01*
X171958Y319915D01*
G01X177693Y327808D02*
X177463Y327963D01*
X177195Y328066D01*
X176888D01*
X176543Y327911D01*
X176275Y327653D01*
X176083Y327343D01*
X175930Y326826D01*
X175892Y326361D01*
X175968Y325896D01*
X176083Y325586D01*
X176313Y325276D01*
X176582Y325069D01*
X176850Y324966D01*
X177118D01*
X177387Y325069D01*
X177617Y325224D01*
X177808Y325431D01*
G01X179222Y327549D02*
X179452Y327859D01*
X179720Y328014D01*
X180027Y328066D01*
X180410Y327963D01*
X180678Y327704D01*
X180755Y327394D01*
X180717Y327084D01*
X180563Y326826D01*
X179797Y326309D01*
X179452Y325948D01*
X179222Y325431D01*
X179145Y324966D01*
X180755D01*
G01X183050D02*
X183318Y325018D01*
X183625Y325173D01*
X183817Y325431D01*
X183893Y325793D01*
X183817Y326154D01*
X183587Y326464D01*
X183242Y326619D01*
X182858D01*
X182628Y326723D01*
X182437Y326981D01*
X182360Y327343D01*
X182475Y327704D01*
X182743Y327963D01*
X183050Y328066D01*
X183357Y327963D01*
X183625Y327704D01*
X183740Y327343D01*
X183663Y326981D01*
X183472Y326723D01*
X183242Y326619D01*
X182858D01*
X182513Y326464D01*
X182283Y326154D01*
X182207Y325793D01*
X182283Y325431D01*
X182475Y325173D01*
X182782Y325018D01*
X183050Y324966D01*
G01X186610D02*
Y328066D01*
X185192Y325844D01*
X187108D01*
G01X172343Y332792D02*
X172113Y332947D01*
X171845Y333050D01*
X171538D01*
X171193Y332895D01*
X170925Y332637D01*
X170733Y332327D01*
X170580Y331810D01*
X170542Y331345D01*
X170618Y330880D01*
X170733Y330570D01*
X170963Y330260D01*
X171232Y330053D01*
X171500Y329950D01*
X171768D01*
X172037Y330053D01*
X172267Y330208D01*
X172458Y330415D01*
G01X169157Y386465D02*
X169387Y386207D01*
X169655Y386052D01*
X170000Y386000D01*
X170345Y386103D01*
X170613Y386310D01*
X170805Y386672D01*
X170843Y387085D01*
X170767Y387498D01*
X170575Y387757D01*
X170307Y387963D01*
X170038Y388015D01*
X169770Y387963D01*
X169425Y387757D01*
X169540Y389100D01*
X170575D01*
G01X173272Y390292D02*
X173540Y390653D01*
X173770Y390860D01*
X174077Y390963D01*
X174345Y390860D01*
X174537Y390653D01*
X174690Y390343D01*
X174728Y389982D01*
X174690Y389672D01*
X174537Y389362D01*
X174307Y389103D01*
X174038Y389000D01*
X173732Y389103D01*
X173463Y389413D01*
X173310Y389878D01*
X173272Y390395D01*
X173348Y391067D01*
X173463Y391428D01*
X173655Y391790D01*
X173923Y392048D01*
X174192Y392100D01*
X174460Y391997D01*
X174652Y391738D01*
G01X179000Y395000D02*
Y398100D01*
X178540Y397480D01*
G01Y395000D02*
X179460D01*
G01X171000Y404500D02*
X171268Y404552D01*
X171575Y404707D01*
X171767Y404965D01*
X171843Y405327D01*
X171767Y405688D01*
X171537Y405998D01*
X171192Y406153D01*
X170808D01*
X170578Y406257D01*
X170387Y406515D01*
X170310Y406877D01*
X170425Y407238D01*
X170693Y407497D01*
X171000Y407600D01*
X171307Y407497D01*
X171575Y407238D01*
X171690Y406877D01*
X171613Y406515D01*
X171422Y406257D01*
X171192Y406153D01*
X170808D01*
X170463Y405998D01*
X170233Y405688D01*
X170157Y405327D01*
X170233Y404965D01*
X170425Y404707D01*
X170732Y404552D01*
X171000Y404500D01*
G01X173423Y400500D02*
X173500Y401172D01*
X173615Y401740D01*
X173768Y402257D01*
X173960Y402825D01*
X174267Y403600D01*
X172733D01*
G01X201320Y55683D02*
X198220D01*
Y56642D01*
X198375Y56948D01*
X198582Y57140D01*
X198995Y57217D01*
X199408Y57140D01*
X199667Y56910D01*
X199822Y56642D01*
Y55683D01*
G01Y56642D02*
X201320Y57217D01*
G01X200700Y58707D02*
X201062Y58937D01*
X201268Y59243D01*
X201320Y59588D01*
X201268Y59895D01*
X201010Y60202D01*
X200700Y60393D01*
X200390Y60432D01*
X200028Y60355D01*
X199770Y60087D01*
X199667Y59818D01*
Y59473D01*
G01Y59818D02*
X199512Y60048D01*
X199253Y60240D01*
X198943Y60317D01*
X198633Y60240D01*
X198375Y60048D01*
X198220Y59703D01*
X198272Y59358D01*
X198478Y59013D01*
G01X200855Y61807D02*
X201113Y62037D01*
X201268Y62305D01*
X201320Y62650D01*
X201217Y62995D01*
X201010Y63263D01*
X200648Y63455D01*
X200235Y63493D01*
X199822Y63417D01*
X199563Y63225D01*
X199357Y62957D01*
X199305Y62688D01*
X199357Y62420D01*
X199563Y62075D01*
X198220Y62190D01*
Y63225D01*
G01X201320Y66210D02*
X198220D01*
X200442Y64792D01*
Y66708D01*
G01X192460Y73000D02*
Y76100D01*
X191042Y73878D01*
X192958D01*
G01X186692Y292193D02*
X186537Y291963D01*
X186434Y291695D01*
Y291388D01*
X186589Y291043D01*
X186847Y290775D01*
X187157Y290583D01*
X187674Y290430D01*
X188139Y290392D01*
X188604Y290468D01*
X188914Y290583D01*
X189224Y290813D01*
X189431Y291082D01*
X189534Y291350D01*
Y291618D01*
X189431Y291887D01*
X189276Y292117D01*
X189069Y292308D01*
G01X188914Y293607D02*
X189276Y293837D01*
X189482Y294143D01*
X189534Y294488D01*
X189482Y294795D01*
X189224Y295102D01*
X188914Y295293D01*
X188604Y295332D01*
X188242Y295255D01*
X187984Y294987D01*
X187881Y294718D01*
Y294373D01*
G01Y294718D02*
X187726Y294948D01*
X187467Y295140D01*
X187157Y295217D01*
X186847Y295140D01*
X186589Y294948D01*
X186434Y294603D01*
X186486Y294258D01*
X186692Y293913D01*
G01X186434Y297550D02*
X186537Y297243D01*
X186796Y297013D01*
X187106Y296860D01*
X187519Y296745D01*
X187984Y296707D01*
X188449Y296745D01*
X188862Y296860D01*
X189172Y297013D01*
X189431Y297243D01*
X189534Y297550D01*
X189431Y297857D01*
X189172Y298087D01*
X188862Y298240D01*
X188449Y298355D01*
X187984Y298393D01*
X187519Y298355D01*
X187106Y298240D01*
X186796Y298087D01*
X186537Y297857D01*
X186434Y297550D01*
G01X186951Y299922D02*
X186641Y300152D01*
X186486Y300420D01*
X186434Y300727D01*
X186537Y301110D01*
X186796Y301378D01*
X187106Y301455D01*
X187416Y301417D01*
X187674Y301263D01*
X188191Y300497D01*
X188552Y300152D01*
X189069Y299922D01*
X189534Y299845D01*
Y301455D01*
G01X197450Y321383D02*
X194350D01*
Y322342D01*
X194505Y322648D01*
X194712Y322840D01*
X195125Y322917D01*
X195538Y322840D01*
X195797Y322610D01*
X195952Y322342D01*
Y321383D01*
G01Y322342D02*
X197450Y322917D01*
G01Y325710D02*
X194350D01*
X196572Y324292D01*
Y326208D01*
G01X194867Y327622D02*
X194557Y327852D01*
X194402Y328120D01*
X194350Y328427D01*
X194453Y328810D01*
X194712Y329078D01*
X195022Y329155D01*
X195332Y329117D01*
X195590Y328963D01*
X196107Y328197D01*
X196468Y327852D01*
X196985Y327622D01*
X197450Y327545D01*
Y329155D01*
G01X194867Y330722D02*
X194557Y330952D01*
X194402Y331220D01*
X194350Y331527D01*
X194453Y331910D01*
X194712Y332178D01*
X195022Y332255D01*
X195332Y332217D01*
X195590Y332063D01*
X196107Y331297D01*
X196468Y330952D01*
X196985Y330722D01*
X197450Y330645D01*
Y332255D01*
G01X200450Y322350D02*
X203550D01*
G01X200450Y321468D02*
Y323232D01*
G01X203550Y324683D02*
X200450D01*
Y325603D01*
X200605Y325910D01*
X200967Y326140D01*
X201380Y326217D01*
X201793Y326140D01*
X202103Y325948D01*
X202258Y325603D01*
Y324683D01*
G01X200967Y327822D02*
X200657Y328052D01*
X200502Y328320D01*
X200450Y328627D01*
X200553Y329010D01*
X200812Y329278D01*
X201122Y329355D01*
X201432Y329317D01*
X201690Y329163D01*
X202207Y328397D01*
X202568Y328052D01*
X203085Y327822D01*
X203550Y327745D01*
Y329355D01*
G01X202930Y330807D02*
X203292Y331037D01*
X203498Y331343D01*
X203550Y331688D01*
X203498Y331995D01*
X203240Y332302D01*
X202930Y332493D01*
X202620Y332532D01*
X202258Y332455D01*
X202000Y332187D01*
X201897Y331918D01*
Y331573D01*
G01Y331918D02*
X201742Y332148D01*
X201483Y332340D01*
X201173Y332417D01*
X200863Y332340D01*
X200605Y332148D01*
X200450Y331803D01*
X200502Y331458D01*
X200708Y331113D01*
G01X193783Y399150D02*
Y396050D01*
X195317D01*
G01X197650D02*
Y399150D01*
X197190Y398530D01*
G01Y396050D02*
X198110D01*
G01X209208Y57693D02*
X209053Y57463D01*
X208950Y57195D01*
Y56888D01*
X209105Y56543D01*
X209363Y56275D01*
X209673Y56083D01*
X210190Y55930D01*
X210655Y55892D01*
X211120Y55968D01*
X211430Y56083D01*
X211740Y56313D01*
X211947Y56582D01*
X212050Y56850D01*
Y57118D01*
X211947Y57387D01*
X211792Y57617D01*
X211585Y57808D01*
G01X209467Y59222D02*
X209157Y59452D01*
X209002Y59720D01*
X208950Y60027D01*
X209053Y60410D01*
X209312Y60678D01*
X209622Y60755D01*
X209932Y60717D01*
X210190Y60563D01*
X210707Y59797D01*
X211068Y59452D01*
X211585Y59222D01*
X212050Y59145D01*
Y60755D01*
G01Y63050D02*
X211998Y63318D01*
X211843Y63625D01*
X211585Y63817D01*
X211223Y63893D01*
X210862Y63817D01*
X210552Y63587D01*
X210397Y63242D01*
Y62858D01*
X210293Y62628D01*
X210035Y62437D01*
X209673Y62360D01*
X209312Y62475D01*
X209053Y62743D01*
X208950Y63050D01*
X209053Y63357D01*
X209312Y63625D01*
X209673Y63740D01*
X210035Y63663D01*
X210293Y63472D01*
X210397Y63242D01*
Y62858D01*
X210552Y62513D01*
X210862Y62283D01*
X211223Y62207D01*
X211585Y62283D01*
X211843Y62475D01*
X211998Y62782D01*
X212050Y63050D01*
G01Y66073D02*
X211378Y66150D01*
X210810Y66265D01*
X210293Y66418D01*
X209725Y66610D01*
X208950Y66917D01*
Y65383D01*
G01X213708Y57693D02*
X213553Y57463D01*
X213450Y57195D01*
Y56888D01*
X213605Y56543D01*
X213863Y56275D01*
X214173Y56083D01*
X214690Y55930D01*
X215155Y55892D01*
X215620Y55968D01*
X215930Y56083D01*
X216240Y56313D01*
X216447Y56582D01*
X216550Y56850D01*
Y57118D01*
X216447Y57387D01*
X216292Y57617D01*
X216085Y57808D01*
G01X213967Y59222D02*
X213657Y59452D01*
X213502Y59720D01*
X213450Y60027D01*
X213553Y60410D01*
X213812Y60678D01*
X214122Y60755D01*
X214432Y60717D01*
X214690Y60563D01*
X215207Y59797D01*
X215568Y59452D01*
X216085Y59222D01*
X216550Y59145D01*
Y60755D01*
G01Y63050D02*
X216498Y63318D01*
X216343Y63625D01*
X216085Y63817D01*
X215723Y63893D01*
X215362Y63817D01*
X215052Y63587D01*
X214897Y63242D01*
Y62858D01*
X214793Y62628D01*
X214535Y62437D01*
X214173Y62360D01*
X213812Y62475D01*
X213553Y62743D01*
X213450Y63050D01*
X213553Y63357D01*
X213812Y63625D01*
X214173Y63740D01*
X214535Y63663D01*
X214793Y63472D01*
X214897Y63242D01*
Y62858D01*
X215052Y62513D01*
X215362Y62283D01*
X215723Y62207D01*
X216085Y62283D01*
X216343Y62475D01*
X216498Y62782D01*
X216550Y63050D01*
G01Y66150D02*
X216498Y66418D01*
X216343Y66725D01*
X216085Y66917D01*
X215723Y66993D01*
X215362Y66917D01*
X215052Y66687D01*
X214897Y66342D01*
Y65958D01*
X214793Y65728D01*
X214535Y65537D01*
X214173Y65460D01*
X213812Y65575D01*
X213553Y65843D01*
X213450Y66150D01*
X213553Y66457D01*
X213812Y66725D01*
X214173Y66840D01*
X214535Y66763D01*
X214793Y66572D01*
X214897Y66342D01*
Y65958D01*
X215052Y65613D01*
X215362Y65383D01*
X215723Y65307D01*
X216085Y65383D01*
X216343Y65575D01*
X216498Y65882D01*
X216550Y66150D01*
G01X206320Y57233D02*
X203220D01*
Y58192D01*
X203375Y58498D01*
X203582Y58690D01*
X203995Y58767D01*
X204408Y58690D01*
X204667Y58460D01*
X204822Y58192D01*
Y57233D01*
G01Y58192D02*
X206320Y58767D01*
G01X203737Y60372D02*
X203427Y60602D01*
X203272Y60870D01*
X203220Y61177D01*
X203323Y61560D01*
X203582Y61828D01*
X203892Y61905D01*
X204202Y61867D01*
X204460Y61713D01*
X204977Y60947D01*
X205338Y60602D01*
X205855Y60372D01*
X206320Y60295D01*
Y61905D01*
G01X205855Y63357D02*
X206113Y63587D01*
X206268Y63855D01*
X206320Y64200D01*
X206217Y64545D01*
X206010Y64813D01*
X205648Y65005D01*
X205235Y65043D01*
X204822Y64967D01*
X204563Y64775D01*
X204357Y64507D01*
X204305Y64238D01*
X204357Y63970D01*
X204563Y63625D01*
X203220Y63740D01*
Y64775D01*
G01X219476Y291393D02*
X219321Y291163D01*
X219218Y290895D01*
Y290588D01*
X219373Y290243D01*
X219631Y289975D01*
X219941Y289783D01*
X220458Y289630D01*
X220923Y289592D01*
X221388Y289668D01*
X221698Y289783D01*
X222008Y290013D01*
X222215Y290282D01*
X222318Y290550D01*
Y290818D01*
X222215Y291087D01*
X222060Y291317D01*
X221853Y291508D01*
G01X221698Y292807D02*
X222060Y293037D01*
X222266Y293343D01*
X222318Y293688D01*
X222266Y293995D01*
X222008Y294302D01*
X221698Y294493D01*
X221388Y294532D01*
X221026Y294455D01*
X220768Y294187D01*
X220665Y293918D01*
Y293573D01*
G01Y293918D02*
X220510Y294148D01*
X220251Y294340D01*
X219941Y294417D01*
X219631Y294340D01*
X219373Y294148D01*
X219218Y293803D01*
X219270Y293458D01*
X219476Y293113D01*
G01X219218Y296750D02*
X219321Y296443D01*
X219580Y296213D01*
X219890Y296060D01*
X220303Y295945D01*
X220768Y295907D01*
X221233Y295945D01*
X221646Y296060D01*
X221956Y296213D01*
X222215Y296443D01*
X222318Y296750D01*
X222215Y297057D01*
X221956Y297287D01*
X221646Y297440D01*
X221233Y297555D01*
X220768Y297593D01*
X220303Y297555D01*
X219890Y297440D01*
X219580Y297287D01*
X219321Y297057D01*
X219218Y296750D01*
G01X221026Y299122D02*
X220665Y299390D01*
X220458Y299620D01*
X220355Y299927D01*
X220458Y300195D01*
X220665Y300387D01*
X220975Y300540D01*
X221336Y300578D01*
X221646Y300540D01*
X221956Y300387D01*
X222215Y300157D01*
X222318Y299888D01*
X222215Y299582D01*
X221905Y299313D01*
X221440Y299160D01*
X220923Y299122D01*
X220251Y299198D01*
X219890Y299313D01*
X219528Y299505D01*
X219270Y299773D01*
X219218Y300042D01*
X219321Y300310D01*
X219580Y300502D01*
G01X217818Y289783D02*
X214718D01*
Y290742D01*
X214873Y291048D01*
X215080Y291240D01*
X215493Y291317D01*
X215906Y291240D01*
X216165Y291010D01*
X216320Y290742D01*
Y289783D01*
G01Y290742D02*
X217818Y291317D01*
G01Y294110D02*
X214718D01*
X216940Y292692D01*
Y294608D01*
G01X217818Y296750D02*
X214718D01*
X215338Y296290D01*
G01X217818D02*
Y297210D01*
G01Y299850D02*
X217766Y300118D01*
X217611Y300425D01*
X217353Y300617D01*
X216991Y300693D01*
X216630Y300617D01*
X216320Y300387D01*
X216165Y300042D01*
Y299658D01*
X216061Y299428D01*
X215803Y299237D01*
X215441Y299160D01*
X215080Y299275D01*
X214821Y299543D01*
X214718Y299850D01*
X214821Y300157D01*
X215080Y300425D01*
X215441Y300540D01*
X215803Y300463D01*
X216061Y300272D01*
X216165Y300042D01*
Y299658D01*
X216320Y299313D01*
X216630Y299083D01*
X216991Y299007D01*
X217353Y299083D01*
X217611Y299275D01*
X217766Y299582D01*
X217818Y299850D01*
G01X213318Y289783D02*
X210218D01*
Y290742D01*
X210373Y291048D01*
X210580Y291240D01*
X210993Y291317D01*
X211406Y291240D01*
X211665Y291010D01*
X211820Y290742D01*
Y289783D01*
G01Y290742D02*
X213318Y291317D01*
G01Y294110D02*
X210218D01*
X212440Y292692D01*
Y294608D01*
G01X213318Y296750D02*
X210218D01*
X210838Y296290D01*
G01X213318D02*
Y297210D01*
G01X210735Y299122D02*
X210425Y299352D01*
X210270Y299620D01*
X210218Y299927D01*
X210321Y300310D01*
X210580Y300578D01*
X210890Y300655D01*
X211200Y300617D01*
X211458Y300463D01*
X211975Y299697D01*
X212336Y299352D01*
X212853Y299122D01*
X213318Y299045D01*
Y300655D01*
G01X208818Y289783D02*
X205718D01*
Y290742D01*
X205873Y291048D01*
X206080Y291240D01*
X206493Y291317D01*
X206906Y291240D01*
X207165Y291010D01*
X207320Y290742D01*
Y289783D01*
G01Y290742D02*
X208818Y291317D01*
G01Y294110D02*
X205718D01*
X207940Y292692D01*
Y294608D01*
G01X205718Y296750D02*
X205821Y296443D01*
X206080Y296213D01*
X206390Y296060D01*
X206803Y295945D01*
X207268Y295907D01*
X207733Y295945D01*
X208146Y296060D01*
X208456Y296213D01*
X208715Y296443D01*
X208818Y296750D01*
X208715Y297057D01*
X208456Y297287D01*
X208146Y297440D01*
X207733Y297555D01*
X207268Y297593D01*
X206803Y297555D01*
X206390Y297440D01*
X206080Y297287D01*
X205821Y297057D01*
X205718Y296750D01*
G01X208818Y299850D02*
X208766Y300118D01*
X208611Y300425D01*
X208353Y300617D01*
X207991Y300693D01*
X207630Y300617D01*
X207320Y300387D01*
X207165Y300042D01*
Y299658D01*
X207061Y299428D01*
X206803Y299237D01*
X206441Y299160D01*
X206080Y299275D01*
X205821Y299543D01*
X205718Y299850D01*
X205821Y300157D01*
X206080Y300425D01*
X206441Y300540D01*
X206803Y300463D01*
X207061Y300272D01*
X207165Y300042D01*
Y299658D01*
X207320Y299313D01*
X207630Y299083D01*
X207991Y299007D01*
X208353Y299083D01*
X208611Y299275D01*
X208766Y299582D01*
X208818Y299850D01*
G01X206157Y303915D02*
X206387Y303657D01*
X206655Y303502D01*
X207000Y303450D01*
X207345Y303553D01*
X207613Y303760D01*
X207805Y304122D01*
X207843Y304535D01*
X207767Y304948D01*
X207575Y305207D01*
X207307Y305413D01*
X207038Y305465D01*
X206770Y305413D01*
X206425Y305207D01*
X206540Y306550D01*
X207575D01*
G01X211450Y315057D02*
X213672D01*
X214137Y315210D01*
X214447Y315517D01*
X214550Y315900D01*
X214447Y316283D01*
X214137Y316590D01*
X213672Y316743D01*
X211450D01*
G01X213930Y318157D02*
X214292Y318387D01*
X214498Y318693D01*
X214550Y319038D01*
X214498Y319345D01*
X214240Y319652D01*
X213930Y319843D01*
X213620Y319882D01*
X213258Y319805D01*
X213000Y319537D01*
X212897Y319268D01*
Y318923D01*
G01Y319268D02*
X212742Y319498D01*
X212483Y319690D01*
X212173Y319767D01*
X211863Y319690D01*
X211605Y319498D01*
X211450Y319153D01*
X211502Y318808D01*
X211708Y318463D01*
G01X214085Y321257D02*
X214343Y321487D01*
X214498Y321755D01*
X214550Y322100D01*
X214447Y322445D01*
X214240Y322713D01*
X213878Y322905D01*
X213465Y322943D01*
X213052Y322867D01*
X212793Y322675D01*
X212587Y322407D01*
X212535Y322138D01*
X212587Y321870D01*
X212793Y321525D01*
X211450Y321640D01*
Y322675D01*
G01X207960Y328950D02*
Y332050D01*
X206542Y329828D01*
X208458D01*
G01X216308Y384343D02*
X216153Y384113D01*
X216050Y383845D01*
Y383538D01*
X216205Y383193D01*
X216463Y382925D01*
X216773Y382733D01*
X217290Y382580D01*
X217755Y382542D01*
X218220Y382618D01*
X218530Y382733D01*
X218840Y382963D01*
X219047Y383232D01*
X219150Y383500D01*
Y383768D01*
X219047Y384037D01*
X218892Y384267D01*
X218685Y384458D01*
G01X219150Y386600D02*
X216050D01*
X216670Y386140D01*
G01X219150D02*
Y387060D01*
G01X216567Y388972D02*
X216257Y389202D01*
X216102Y389470D01*
X216050Y389777D01*
X216153Y390160D01*
X216412Y390428D01*
X216722Y390505D01*
X217032Y390467D01*
X217290Y390313D01*
X217807Y389547D01*
X218168Y389202D01*
X218685Y388972D01*
X219150Y388895D01*
Y390505D01*
G01X217308Y404843D02*
X217153Y404613D01*
X217050Y404345D01*
Y404038D01*
X217205Y403693D01*
X217463Y403425D01*
X217773Y403233D01*
X218290Y403080D01*
X218755Y403042D01*
X219220Y403118D01*
X219530Y403233D01*
X219840Y403463D01*
X220047Y403732D01*
X220150Y404000D01*
Y404268D01*
X220047Y404537D01*
X219892Y404767D01*
X219685Y404958D01*
G01X220150Y407100D02*
X217050D01*
X217670Y406640D01*
G01X220150D02*
Y407560D01*
G01Y410660D02*
X217050D01*
X219272Y409242D01*
Y411158D01*
G01X213272Y398583D02*
X213502Y398893D01*
X213770Y399048D01*
X214077Y399100D01*
X214460Y398997D01*
X214728Y398738D01*
X214805Y398428D01*
X214767Y398118D01*
X214613Y397860D01*
X213847Y397343D01*
X213502Y396982D01*
X213272Y396465D01*
X213195Y396000D01*
X214805D01*
G01X220350Y397550D02*
Y394450D01*
G01X219468Y397550D02*
X221232D01*
G01X222683Y394450D02*
Y397550D01*
X223603D01*
X223910Y397395D01*
X224140Y397033D01*
X224217Y396620D01*
X224140Y396207D01*
X223948Y395897D01*
X223603Y395742D01*
X222683D01*
G01X225822D02*
X226090Y396103D01*
X226320Y396310D01*
X226627Y396413D01*
X226895Y396310D01*
X227087Y396103D01*
X227240Y395793D01*
X227278Y395432D01*
X227240Y395122D01*
X227087Y394812D01*
X226857Y394553D01*
X226588Y394450D01*
X226282Y394553D01*
X226013Y394863D01*
X225860Y395328D01*
X225822Y395845D01*
X225898Y396517D01*
X226013Y396878D01*
X226205Y397240D01*
X226473Y397498D01*
X226742Y397550D01*
X227010Y397447D01*
X227202Y397188D01*
G01X229650Y397550D02*
X229343Y397447D01*
X229113Y397188D01*
X228960Y396878D01*
X228845Y396465D01*
X228807Y396000D01*
X228845Y395535D01*
X228960Y395122D01*
X229113Y394812D01*
X229343Y394553D01*
X229650Y394450D01*
X229957Y394553D01*
X230187Y394812D01*
X230340Y395122D01*
X230455Y395535D01*
X230493Y396000D01*
X230455Y396465D01*
X230340Y396878D01*
X230187Y397188D01*
X229957Y397447D01*
X229650Y397550D01*
G01X225515Y50509D02*
Y47409D01*
G01X224633Y50509D02*
X226397D01*
G01X227848Y47409D02*
Y50509D01*
X228768D01*
X229075Y50354D01*
X229305Y49992D01*
X229382Y49579D01*
X229305Y49166D01*
X229113Y48856D01*
X228768Y48701D01*
X227848D01*
G01X232175Y47409D02*
Y50509D01*
X230757Y48287D01*
X232673D01*
G01X234815Y47409D02*
X235083Y47461D01*
X235390Y47616D01*
X235582Y47874D01*
X235658Y48236D01*
X235582Y48597D01*
X235352Y48907D01*
X235007Y49062D01*
X234623D01*
X234393Y49166D01*
X234202Y49424D01*
X234125Y49786D01*
X234240Y50147D01*
X234508Y50406D01*
X234815Y50509D01*
X235122Y50406D01*
X235390Y50147D01*
X235505Y49786D01*
X235428Y49424D01*
X235237Y49166D01*
X235007Y49062D01*
X234623D01*
X234278Y48907D01*
X234048Y48597D01*
X233972Y48236D01*
X234048Y47874D01*
X234240Y47616D01*
X234547Y47461D01*
X234815Y47409D01*
G01X229153Y92000D02*
Y95100D01*
X230150Y92517D01*
X231147Y95100D01*
Y92000D01*
G01X232292D02*
X233250Y95100D01*
X234208Y92000D01*
G01X233863Y93085D02*
X232637D01*
G01X237193Y94842D02*
X236963Y94997D01*
X236695Y95100D01*
X236388D01*
X236043Y94945D01*
X235775Y94687D01*
X235583Y94377D01*
X235430Y93860D01*
X235392Y93395D01*
X235468Y92930D01*
X235583Y92620D01*
X235813Y92310D01*
X236082Y92103D01*
X236350Y92000D01*
X236618D01*
X236887Y92103D01*
X237117Y92258D01*
X237308Y92465D01*
G01X238300Y90967D02*
X240600D01*
G01X241783Y92000D02*
Y95100D01*
X242703D01*
X243010Y94945D01*
X243240Y94583D01*
X243317Y94170D01*
X243240Y93757D01*
X243048Y93447D01*
X242703Y93292D01*
X241783D01*
G01X245190Y95100D02*
X246110D01*
G01X245650D02*
Y92000D01*
G01X245190D02*
X246110D01*
G01X247868D02*
Y95100D01*
X249632Y92000D01*
Y95100D01*
G01X251850Y92000D02*
X252118Y92052D01*
X252425Y92207D01*
X252617Y92465D01*
X252693Y92827D01*
X252617Y93188D01*
X252387Y93498D01*
X252042Y93653D01*
X251658D01*
X251428Y93757D01*
X251237Y94015D01*
X251160Y94377D01*
X251275Y94738D01*
X251543Y94997D01*
X251850Y95100D01*
X252157Y94997D01*
X252425Y94738D01*
X252540Y94377D01*
X252463Y94015D01*
X252272Y93757D01*
X252042Y93653D01*
X251658D01*
X251313Y93498D01*
X251083Y93188D01*
X251007Y92827D01*
X251083Y92465D01*
X251275Y92207D01*
X251582Y92052D01*
X251850Y92000D01*
G01X221000Y303450D02*
X221268Y303502D01*
X221575Y303657D01*
X221767Y303915D01*
X221843Y304277D01*
X221767Y304638D01*
X221537Y304948D01*
X221192Y305103D01*
X220808D01*
X220578Y305207D01*
X220387Y305465D01*
X220310Y305827D01*
X220425Y306188D01*
X220693Y306447D01*
X221000Y306550D01*
X221307Y306447D01*
X221575Y306188D01*
X221690Y305827D01*
X221613Y305465D01*
X221422Y305207D01*
X221192Y305103D01*
X220808D01*
X220463Y304948D01*
X220233Y304638D01*
X220157Y304277D01*
X220233Y303915D01*
X220425Y303657D01*
X220732Y303502D01*
X221000Y303450D01*
G01X227830Y321183D02*
X224730D01*
Y322142D01*
X224885Y322448D01*
X225092Y322640D01*
X225505Y322717D01*
X225918Y322640D01*
X226177Y322410D01*
X226332Y322142D01*
Y321183D01*
G01Y322142D02*
X227830Y322717D01*
G01Y325510D02*
X224730D01*
X226952Y324092D01*
Y326008D01*
G01X224730Y328150D02*
X224833Y327843D01*
X225092Y327613D01*
X225402Y327460D01*
X225815Y327345D01*
X226280Y327307D01*
X226745Y327345D01*
X227158Y327460D01*
X227468Y327613D01*
X227727Y327843D01*
X227830Y328150D01*
X227727Y328457D01*
X227468Y328687D01*
X227158Y328840D01*
X226745Y328955D01*
X226280Y328993D01*
X225815Y328955D01*
X225402Y328840D01*
X225092Y328687D01*
X224833Y328457D01*
X224730Y328150D01*
G01X226538Y330522D02*
X226177Y330790D01*
X225970Y331020D01*
X225867Y331327D01*
X225970Y331595D01*
X226177Y331787D01*
X226487Y331940D01*
X226848Y331978D01*
X227158Y331940D01*
X227468Y331787D01*
X227727Y331557D01*
X227830Y331288D01*
X227727Y330982D01*
X227417Y330713D01*
X226952Y330560D01*
X226435Y330522D01*
X225763Y330598D01*
X225402Y330713D01*
X225040Y330905D01*
X224782Y331173D01*
X224730Y331442D01*
X224833Y331710D01*
X225092Y331902D01*
G01X222308Y383843D02*
X222153Y383613D01*
X222050Y383345D01*
Y383038D01*
X222205Y382693D01*
X222463Y382425D01*
X222773Y382233D01*
X223290Y382080D01*
X223755Y382042D01*
X224220Y382118D01*
X224530Y382233D01*
X224840Y382463D01*
X225047Y382732D01*
X225150Y383000D01*
Y383268D01*
X225047Y383537D01*
X224892Y383767D01*
X224685Y383958D01*
G01X225150Y386100D02*
X222050D01*
X222670Y385640D01*
G01X225150D02*
Y386560D01*
G01X224530Y388357D02*
X224892Y388587D01*
X225098Y388893D01*
X225150Y389238D01*
X225098Y389545D01*
X224840Y389852D01*
X224530Y390043D01*
X224220Y390082D01*
X223858Y390005D01*
X223600Y389737D01*
X223497Y389468D01*
Y389123D01*
G01Y389468D02*
X223342Y389698D01*
X223083Y389890D01*
X222773Y389967D01*
X222463Y389890D01*
X222205Y389698D01*
X222050Y389353D01*
X222102Y389008D01*
X222308Y388663D01*
G01X224808Y404843D02*
X224653Y404613D01*
X224550Y404345D01*
Y404038D01*
X224705Y403693D01*
X224963Y403425D01*
X225273Y403233D01*
X225790Y403080D01*
X226255Y403042D01*
X226720Y403118D01*
X227030Y403233D01*
X227340Y403463D01*
X227547Y403732D01*
X227650Y404000D01*
Y404268D01*
X227547Y404537D01*
X227392Y404767D01*
X227185Y404958D01*
G01X227650Y407100D02*
X224550D01*
X225170Y406640D01*
G01X227650D02*
Y407560D01*
G01X227185Y409357D02*
X227443Y409587D01*
X227598Y409855D01*
X227650Y410200D01*
X227547Y410545D01*
X227340Y410813D01*
X226978Y411005D01*
X226565Y411043D01*
X226152Y410967D01*
X225893Y410775D01*
X225687Y410507D01*
X225635Y410238D01*
X225687Y409970D01*
X225893Y409625D01*
X224550Y409740D01*
Y410775D01*
G01X241814Y14756D02*
X242581D01*
Y13826D01*
X242351Y13516D01*
X242082Y13309D01*
X241699Y13206D01*
X241316Y13309D01*
X241047Y13516D01*
X240817Y13826D01*
X240664Y14188D01*
X240587Y14601D01*
Y14963D01*
X240664Y15273D01*
X240817Y15634D01*
X241047Y15944D01*
X241277Y16151D01*
X241584Y16306D01*
X241852D01*
X242159Y16203D01*
X242389Y15996D01*
G01X243956Y13206D02*
Y16306D01*
X245412D01*
G01X244876Y14808D02*
X243956D01*
G01X247784Y13206D02*
Y16306D01*
X247324Y15686D01*
G01Y13206D02*
X248244D01*
G01X252672Y56633D02*
X249572D01*
Y57592D01*
X249727Y57898D01*
X249934Y58090D01*
X250347Y58167D01*
X250760Y58090D01*
X251019Y57860D01*
X251174Y57592D01*
Y56633D01*
G01Y57592D02*
X252672Y58167D01*
G01X250089Y59772D02*
X249779Y60002D01*
X249624Y60270D01*
X249572Y60577D01*
X249675Y60960D01*
X249934Y61228D01*
X250244Y61305D01*
X250554Y61267D01*
X250812Y61113D01*
X251329Y60347D01*
X251690Y60002D01*
X252207Y59772D01*
X252672Y59695D01*
Y61305D01*
G01X250089Y62872D02*
X249779Y63102D01*
X249624Y63370D01*
X249572Y63677D01*
X249675Y64060D01*
X249934Y64328D01*
X250244Y64405D01*
X250554Y64367D01*
X250812Y64213D01*
X251329Y63447D01*
X251690Y63102D01*
X252207Y62872D01*
X252672Y62795D01*
Y64405D01*
G01X251809Y308096D02*
Y311196D01*
X252806Y308613D01*
X253803Y311196D01*
Y308096D01*
G01X256673D02*
X255139D01*
Y311196D01*
X256673D01*
G01X256059Y309698D02*
X255139D01*
G01X258278Y310679D02*
X258508Y310989D01*
X258776Y311144D01*
X259083Y311196D01*
X259466Y311093D01*
X259734Y310834D01*
X259811Y310524D01*
X259773Y310214D01*
X259619Y309956D01*
X258853Y309439D01*
X258508Y309078D01*
X258278Y308561D01*
X258201Y308096D01*
X259811D01*
G01X251809Y410458D02*
Y413558D01*
X252806Y410975D01*
X253803Y413558D01*
Y410458D01*
G01X256673D02*
X255139D01*
Y413558D01*
X256673D01*
G01X256059Y412060D02*
X255139D01*
G01X259006Y410458D02*
Y413558D01*
X258546Y412938D01*
G01Y410458D02*
X259466D01*
G01X270757Y56586D02*
X270987Y56224D01*
X271293Y56018D01*
X271638Y55966D01*
X271945Y56018D01*
X272252Y56276D01*
X272443Y56586D01*
X272482Y56896D01*
X272405Y57258D01*
X272137Y57516D01*
X271868Y57619D01*
X271523D01*
G01X271868D02*
X272098Y57774D01*
X272290Y58033D01*
X272367Y58343D01*
X272290Y58653D01*
X272098Y58911D01*
X271753Y59066D01*
X271408Y59014D01*
X271063Y58808D01*
G01X257733Y58950D02*
Y62050D01*
X258692D01*
X258998Y61895D01*
X259190Y61688D01*
X259267Y61275D01*
X259190Y60862D01*
X258960Y60603D01*
X258692Y60448D01*
X257733D01*
G01X258692D02*
X259267Y58950D01*
G01X260757Y59415D02*
X260987Y59157D01*
X261255Y59002D01*
X261600Y58950D01*
X261945Y59053D01*
X262213Y59260D01*
X262405Y59622D01*
X262443Y60035D01*
X262367Y60448D01*
X262175Y60707D01*
X261907Y60913D01*
X261638Y60965D01*
X261370Y60913D01*
X261025Y60707D01*
X261140Y62050D01*
X262175D01*
G01X263972Y60242D02*
X264240Y60603D01*
X264470Y60810D01*
X264777Y60913D01*
X265045Y60810D01*
X265237Y60603D01*
X265390Y60293D01*
X265428Y59932D01*
X265390Y59622D01*
X265237Y59312D01*
X265007Y59053D01*
X264738Y58950D01*
X264432Y59053D01*
X264163Y59363D01*
X264010Y59828D01*
X263972Y60345D01*
X264048Y61017D01*
X264163Y61378D01*
X264355Y61740D01*
X264623Y61998D01*
X264892Y62050D01*
X265160Y61947D01*
X265352Y61688D01*
G01X257733Y63950D02*
Y67050D01*
X258692D01*
X258998Y66895D01*
X259190Y66688D01*
X259267Y66275D01*
X259190Y65862D01*
X258960Y65603D01*
X258692Y65448D01*
X257733D01*
G01X258692D02*
X259267Y63950D01*
G01X260757Y64415D02*
X260987Y64157D01*
X261255Y64002D01*
X261600Y63950D01*
X261945Y64053D01*
X262213Y64260D01*
X262405Y64622D01*
X262443Y65035D01*
X262367Y65448D01*
X262175Y65707D01*
X261907Y65913D01*
X261638Y65965D01*
X261370Y65913D01*
X261025Y65707D01*
X261140Y67050D01*
X262175D01*
G01X263857Y64415D02*
X264087Y64157D01*
X264355Y64002D01*
X264700Y63950D01*
X265045Y64053D01*
X265313Y64260D01*
X265505Y64622D01*
X265543Y65035D01*
X265467Y65448D01*
X265275Y65707D01*
X265007Y65913D01*
X264738Y65965D01*
X264470Y65913D01*
X264125Y65707D01*
X264240Y67050D01*
X265275D01*
G01X266000Y76153D02*
X262900D01*
X265483Y77150D01*
X262900Y78147D01*
X266000D01*
G01Y79292D02*
X262900Y80250D01*
X266000Y81208D01*
G01X264915Y80863D02*
Y79637D01*
G01X263158Y84193D02*
X263003Y83963D01*
X262900Y83695D01*
Y83388D01*
X263055Y83043D01*
X263313Y82775D01*
X263623Y82583D01*
X264140Y82430D01*
X264605Y82392D01*
X265070Y82468D01*
X265380Y82583D01*
X265690Y82813D01*
X265897Y83082D01*
X266000Y83350D01*
Y83618D01*
X265897Y83887D01*
X265742Y84117D01*
X265535Y84308D01*
G01X267033Y85300D02*
Y87600D01*
G01X266000Y88783D02*
X262900D01*
Y89703D01*
X263055Y90010D01*
X263417Y90240D01*
X263830Y90317D01*
X264243Y90240D01*
X264553Y90048D01*
X264708Y89703D01*
Y88783D01*
G01X262900Y92190D02*
Y93110D01*
G01Y92650D02*
X266000D01*
G01Y92190D02*
Y93110D01*
G01Y94868D02*
X262900D01*
X266000Y96632D01*
X262900D01*
G01X266000Y98773D02*
X265328Y98850D01*
X264760Y98965D01*
X264243Y99118D01*
X263675Y99310D01*
X262900Y99617D01*
Y98083D01*
G01X264470Y110593D02*
Y113693D01*
X265467Y111110D01*
X266464Y113693D01*
Y110593D01*
G01X269334D02*
X267800D01*
Y113693D01*
X269334D01*
G01X268720Y112195D02*
X267800D01*
G01X271667Y110593D02*
X271935Y110645D01*
X272242Y110800D01*
X272434Y111058D01*
X272510Y111420D01*
X272434Y111781D01*
X272204Y112091D01*
X271859Y112246D01*
X271475D01*
X271245Y112350D01*
X271054Y112608D01*
X270977Y112970D01*
X271092Y113331D01*
X271360Y113590D01*
X271667Y113693D01*
X271974Y113590D01*
X272242Y113331D01*
X272357Y112970D01*
X272280Y112608D01*
X272089Y112350D01*
X271859Y112246D01*
X271475D01*
X271130Y112091D01*
X270900Y111781D01*
X270824Y111420D01*
X270900Y111058D01*
X271092Y110800D01*
X271399Y110645D01*
X271667Y110593D01*
G01X268450Y170500D02*
Y173600D01*
X267990Y172980D01*
G01Y170500D02*
X268910D01*
G01X270898Y170862D02*
X271167Y170603D01*
X271473Y170500D01*
X271780Y170603D01*
X272048Y170913D01*
X272240Y171378D01*
X272317Y171843D01*
Y172412D01*
X272240Y172877D01*
X272048Y173290D01*
X271818Y173497D01*
X271550Y173600D01*
X271243Y173497D01*
X271013Y173290D01*
X270860Y172980D01*
X270783Y172567D01*
X270860Y172205D01*
X271052Y171843D01*
X271282Y171637D01*
X271550Y171585D01*
X271857Y171688D01*
X272087Y171947D01*
X272317Y172412D01*
G01X272495Y193226D02*
Y196326D01*
X272035Y195706D01*
G01Y193226D02*
X272955D01*
G01X264470Y254393D02*
Y257493D01*
X265467Y254910D01*
X266464Y257493D01*
Y254393D01*
G01X269334D02*
X267800D01*
Y257493D01*
X269334D01*
G01X268720Y255995D02*
X267800D01*
G01X270939Y255685D02*
X271207Y256046D01*
X271437Y256253D01*
X271744Y256356D01*
X272012Y256253D01*
X272204Y256046D01*
X272357Y255736D01*
X272395Y255375D01*
X272357Y255065D01*
X272204Y254755D01*
X271974Y254496D01*
X271705Y254393D01*
X271399Y254496D01*
X271130Y254806D01*
X270977Y255271D01*
X270939Y255788D01*
X271015Y256460D01*
X271130Y256821D01*
X271322Y257183D01*
X271590Y257441D01*
X271859Y257493D01*
X272127Y257390D01*
X272319Y257131D01*
G01X277707Y62050D02*
Y59828D01*
X277860Y59363D01*
X278167Y59053D01*
X278550Y58950D01*
X278933Y59053D01*
X279240Y59363D01*
X279393Y59828D01*
Y62050D01*
G01X280807Y59570D02*
X281037Y59208D01*
X281343Y59002D01*
X281688Y58950D01*
X281995Y59002D01*
X282302Y59260D01*
X282493Y59570D01*
X282532Y59880D01*
X282455Y60242D01*
X282187Y60500D01*
X281918Y60603D01*
X281573D01*
G01X281918D02*
X282148Y60758D01*
X282340Y61017D01*
X282417Y61327D01*
X282340Y61637D01*
X282148Y61895D01*
X281803Y62050D01*
X281458Y61998D01*
X281113Y61792D01*
G01X289178Y56055D02*
Y59155D01*
X287760Y56933D01*
X289676D01*
G01X287757Y61932D02*
X287987Y61674D01*
X288255Y61519D01*
X288600Y61467D01*
X288945Y61570D01*
X289213Y61777D01*
X289405Y62139D01*
X289443Y62552D01*
X289367Y62965D01*
X289175Y63224D01*
X288907Y63430D01*
X288638Y63482D01*
X288370Y63430D01*
X288025Y63224D01*
X288140Y64567D01*
X289175D01*
G01X274653Y91000D02*
Y94100D01*
X275650Y91517D01*
X276647Y94100D01*
Y91000D01*
G01X277792D02*
X278750Y94100D01*
X279708Y91000D01*
G01X279363Y92085D02*
X278137D01*
G01X282693Y93842D02*
X282463Y93997D01*
X282195Y94100D01*
X281888D01*
X281543Y93945D01*
X281275Y93687D01*
X281083Y93377D01*
X280930Y92860D01*
X280892Y92395D01*
X280968Y91930D01*
X281083Y91620D01*
X281313Y91310D01*
X281582Y91103D01*
X281850Y91000D01*
X282118D01*
X282387Y91103D01*
X282617Y91258D01*
X282808Y91465D01*
G01X283800Y89967D02*
X286100D01*
G01X287283Y91000D02*
Y94100D01*
X288203D01*
X288510Y93945D01*
X288740Y93583D01*
X288817Y93170D01*
X288740Y92757D01*
X288548Y92447D01*
X288203Y92292D01*
X287283D01*
G01X290690Y94100D02*
X291610D01*
G01X291150D02*
Y91000D01*
G01X290690D02*
X291610D01*
G01X293368D02*
Y94100D01*
X295132Y91000D01*
Y94100D01*
G01X296622Y92292D02*
X296890Y92653D01*
X297120Y92860D01*
X297427Y92963D01*
X297695Y92860D01*
X297887Y92653D01*
X298040Y92343D01*
X298078Y91982D01*
X298040Y91672D01*
X297887Y91362D01*
X297657Y91103D01*
X297388Y91000D01*
X297082Y91103D01*
X296813Y91413D01*
X296660Y91878D01*
X296622Y92395D01*
X296698Y93067D01*
X296813Y93428D01*
X297005Y93790D01*
X297273Y94048D01*
X297542Y94100D01*
X297810Y93997D01*
X298002Y93738D01*
G01X284153Y102000D02*
Y105100D01*
X285150Y102517D01*
X286147Y105100D01*
Y102000D01*
G01X287292D02*
X288250Y105100D01*
X289208Y102000D01*
G01X288863Y103085D02*
X287637D01*
G01X292193Y104842D02*
X291963Y104997D01*
X291695Y105100D01*
X291388D01*
X291043Y104945D01*
X290775Y104687D01*
X290583Y104377D01*
X290430Y103860D01*
X290392Y103395D01*
X290468Y102930D01*
X290583Y102620D01*
X290813Y102310D01*
X291082Y102103D01*
X291350Y102000D01*
X291618D01*
X291887Y102103D01*
X292117Y102258D01*
X292308Y102465D01*
G01X293300Y100967D02*
X295600D01*
G01X296783Y102000D02*
Y105100D01*
X297703D01*
X298010Y104945D01*
X298240Y104583D01*
X298317Y104170D01*
X298240Y103757D01*
X298048Y103447D01*
X297703Y103292D01*
X296783D01*
G01X300190Y105100D02*
X301110D01*
G01X300650D02*
Y102000D01*
G01X300190D02*
X301110D01*
G01X302868D02*
Y105100D01*
X304632Y102000D01*
Y105100D01*
G01X307310Y102000D02*
Y105100D01*
X305892Y102878D01*
X307808D01*
G01X286410Y181725D02*
X283310D01*
Y182645D01*
X283465Y182952D01*
X283827Y183182D01*
X284240Y183259D01*
X284653Y183182D01*
X284963Y182990D01*
X285118Y182645D01*
Y181725D01*
G01X286410Y185592D02*
X283310D01*
X283930Y185132D01*
G01X286410D02*
Y186052D01*
G01X281153Y262500D02*
Y265600D01*
X282150Y263017D01*
X283147Y265600D01*
Y262500D01*
G01X284292D02*
X285250Y265600D01*
X286208Y262500D01*
G01X285863Y263585D02*
X284637D01*
G01X289193Y265342D02*
X288963Y265497D01*
X288695Y265600D01*
X288388D01*
X288043Y265445D01*
X287775Y265187D01*
X287583Y264877D01*
X287430Y264360D01*
X287392Y263895D01*
X287468Y263430D01*
X287583Y263120D01*
X287813Y262810D01*
X288082Y262603D01*
X288350Y262500D01*
X288618D01*
X288887Y262603D01*
X289117Y262758D01*
X289308Y262965D01*
G01X290300Y261467D02*
X292600D01*
G01X293783Y262500D02*
Y265600D01*
X294703D01*
X295010Y265445D01*
X295240Y265083D01*
X295317Y264670D01*
X295240Y264257D01*
X295048Y263947D01*
X294703Y263792D01*
X293783D01*
G01X297190Y265600D02*
X298110D01*
G01X297650D02*
Y262500D01*
G01X297190D02*
X298110D01*
G01X299868D02*
Y265600D01*
X301632Y262500D01*
Y265600D01*
G01X303007Y262965D02*
X303237Y262707D01*
X303505Y262552D01*
X303850Y262500D01*
X304195Y262603D01*
X304463Y262810D01*
X304655Y263172D01*
X304693Y263585D01*
X304617Y263998D01*
X304425Y264257D01*
X304157Y264463D01*
X303888Y264515D01*
X303620Y264463D01*
X303275Y264257D01*
X303390Y265600D01*
X304425D01*
G01X289343Y321892D02*
X289113Y322047D01*
X288845Y322150D01*
X288538D01*
X288193Y321995D01*
X287925Y321737D01*
X287733Y321427D01*
X287580Y320910D01*
X287542Y320445D01*
X287618Y319980D01*
X287733Y319670D01*
X287963Y319360D01*
X288232Y319153D01*
X288500Y319050D01*
X288768D01*
X289037Y319153D01*
X289267Y319308D01*
X289458Y319515D01*
G01X290757Y319670D02*
X290987Y319308D01*
X291293Y319102D01*
X291638Y319050D01*
X291945Y319102D01*
X292252Y319360D01*
X292443Y319670D01*
X292482Y319980D01*
X292405Y320342D01*
X292137Y320600D01*
X291868Y320703D01*
X291523D01*
G01X291868D02*
X292098Y320858D01*
X292290Y321117D01*
X292367Y321427D01*
X292290Y321737D01*
X292098Y321995D01*
X291753Y322150D01*
X291408Y322098D01*
X291063Y321892D01*
G01X294700Y319050D02*
X294968Y319102D01*
X295275Y319257D01*
X295467Y319515D01*
X295543Y319877D01*
X295467Y320238D01*
X295237Y320548D01*
X294892Y320703D01*
X294508D01*
X294278Y320807D01*
X294087Y321065D01*
X294010Y321427D01*
X294125Y321788D01*
X294393Y322047D01*
X294700Y322150D01*
X295007Y322047D01*
X295275Y321788D01*
X295390Y321427D01*
X295313Y321065D01*
X295122Y320807D01*
X294892Y320703D01*
X294508D01*
X294163Y320548D01*
X293933Y320238D01*
X293857Y319877D01*
X293933Y319515D01*
X294125Y319257D01*
X294432Y319102D01*
X294700Y319050D01*
G01X286183Y324350D02*
Y327450D01*
X287142D01*
X287448Y327295D01*
X287640Y327088D01*
X287717Y326675D01*
X287640Y326262D01*
X287410Y326003D01*
X287142Y325848D01*
X286183D01*
G01X287142D02*
X287717Y324350D01*
G01X289207Y324970D02*
X289437Y324608D01*
X289743Y324402D01*
X290088Y324350D01*
X290395Y324402D01*
X290702Y324660D01*
X290893Y324970D01*
X290932Y325280D01*
X290855Y325642D01*
X290587Y325900D01*
X290318Y326003D01*
X289973D01*
G01X290318D02*
X290548Y326158D01*
X290740Y326417D01*
X290817Y326727D01*
X290740Y327037D01*
X290548Y327295D01*
X290203Y327450D01*
X289858Y327398D01*
X289513Y327192D01*
G01X293150Y324350D02*
Y327450D01*
X292690Y326830D01*
G01Y324350D02*
X293610D01*
G01X296250Y327450D02*
X295943Y327347D01*
X295713Y327088D01*
X295560Y326778D01*
X295445Y326365D01*
X295407Y325900D01*
X295445Y325435D01*
X295560Y325022D01*
X295713Y324712D01*
X295943Y324453D01*
X296250Y324350D01*
X296557Y324453D01*
X296787Y324712D01*
X296940Y325022D01*
X297055Y325435D01*
X297093Y325900D01*
X297055Y326365D01*
X296940Y326778D01*
X296787Y327088D01*
X296557Y327347D01*
X296250Y327450D01*
G01X286283Y331650D02*
Y334750D01*
X287242D01*
X287548Y334595D01*
X287740Y334388D01*
X287817Y333975D01*
X287740Y333562D01*
X287510Y333303D01*
X287242Y333148D01*
X286283D01*
G01X287242D02*
X287817Y331650D01*
G01X289307Y332270D02*
X289537Y331908D01*
X289843Y331702D01*
X290188Y331650D01*
X290495Y331702D01*
X290802Y331960D01*
X290993Y332270D01*
X291032Y332580D01*
X290955Y332942D01*
X290687Y333200D01*
X290418Y333303D01*
X290073D01*
G01X290418D02*
X290648Y333458D01*
X290840Y333717D01*
X290917Y334027D01*
X290840Y334337D01*
X290648Y334595D01*
X290303Y334750D01*
X289958Y334698D01*
X289613Y334492D01*
G01X293250Y331650D02*
Y334750D01*
X292790Y334130D01*
G01Y331650D02*
X293710D01*
G01X296350D02*
Y334750D01*
X295890Y334130D01*
G01Y331650D02*
X296810D01*
G01X305131Y29101D02*
X305284Y29256D01*
X305399Y29515D01*
X305476Y29876D01*
X305399Y30186D01*
X305246Y30393D01*
X304977Y30548D01*
X303942D01*
Y27448D01*
X305207D01*
X305476Y27655D01*
X305629Y27965D01*
X305706Y28326D01*
X305629Y28688D01*
X305399Y28998D01*
X305131Y29101D01*
X303942D01*
G01X307081Y28068D02*
X307311Y27706D01*
X307617Y27500D01*
X307962Y27448D01*
X308269Y27500D01*
X308576Y27758D01*
X308767Y28068D01*
X308806Y28378D01*
X308729Y28740D01*
X308461Y28998D01*
X308192Y29101D01*
X307847D01*
G01X308192D02*
X308422Y29256D01*
X308614Y29515D01*
X308691Y29825D01*
X308614Y30135D01*
X308422Y30393D01*
X308077Y30548D01*
X307732Y30496D01*
X307387Y30290D01*
G01X310296Y30031D02*
X310526Y30341D01*
X310794Y30496D01*
X311101Y30548D01*
X311484Y30445D01*
X311752Y30186D01*
X311829Y29876D01*
X311791Y29566D01*
X311637Y29308D01*
X310871Y28791D01*
X310526Y28430D01*
X310296Y27913D01*
X310219Y27448D01*
X311829D01*
G01X293633Y55891D02*
Y58991D01*
X294592D01*
X294898Y58836D01*
X295090Y58629D01*
X295167Y58216D01*
X295090Y57803D01*
X294860Y57544D01*
X294592Y57389D01*
X293633D01*
G01X294592D02*
X295167Y55891D01*
G01X296657Y56356D02*
X296887Y56098D01*
X297155Y55943D01*
X297500Y55891D01*
X297845Y55994D01*
X298113Y56201D01*
X298305Y56563D01*
X298343Y56976D01*
X298267Y57389D01*
X298075Y57648D01*
X297807Y57854D01*
X297538Y57906D01*
X297270Y57854D01*
X296925Y57648D01*
X297040Y58991D01*
X298075D01*
G01X300523Y55891D02*
X300600Y56563D01*
X300715Y57131D01*
X300868Y57648D01*
X301060Y58216D01*
X301367Y58991D01*
X299833D01*
G01X295363Y68072D02*
X295133Y68227D01*
X294865Y68330D01*
X294558D01*
X294213Y68175D01*
X293945Y67917D01*
X293753Y67607D01*
X293600Y67090D01*
X293562Y66625D01*
X293638Y66160D01*
X293753Y65850D01*
X293983Y65540D01*
X294252Y65333D01*
X294520Y65230D01*
X294788D01*
X295057Y65333D01*
X295287Y65488D01*
X295478Y65695D01*
G01X296777Y65850D02*
X297007Y65488D01*
X297313Y65282D01*
X297658Y65230D01*
X297965Y65282D01*
X298272Y65540D01*
X298463Y65850D01*
X298502Y66160D01*
X298425Y66522D01*
X298157Y66780D01*
X297888Y66883D01*
X297543D01*
G01X297888D02*
X298118Y67038D01*
X298310Y67297D01*
X298387Y67607D01*
X298310Y67917D01*
X298118Y68175D01*
X297773Y68330D01*
X297428Y68278D01*
X297083Y68072D01*
G01X300643Y65230D02*
X300720Y65902D01*
X300835Y66470D01*
X300988Y66987D01*
X301180Y67555D01*
X301487Y68330D01*
X299953D01*
G01X293733Y60550D02*
Y63650D01*
X294692D01*
X294998Y63495D01*
X295190Y63288D01*
X295267Y62875D01*
X295190Y62462D01*
X294960Y62203D01*
X294692Y62048D01*
X293733D01*
G01X294692D02*
X295267Y60550D01*
G01X296872Y61842D02*
X297140Y62203D01*
X297370Y62410D01*
X297677Y62513D01*
X297945Y62410D01*
X298137Y62203D01*
X298290Y61893D01*
X298328Y61532D01*
X298290Y61222D01*
X298137Y60912D01*
X297907Y60653D01*
X297638Y60550D01*
X297332Y60653D01*
X297063Y60963D01*
X296910Y61428D01*
X296872Y61945D01*
X296948Y62617D01*
X297063Y62978D01*
X297255Y63340D01*
X297523Y63598D01*
X297792Y63650D01*
X298060Y63547D01*
X298252Y63288D01*
G01X299857Y61170D02*
X300087Y60808D01*
X300393Y60602D01*
X300738Y60550D01*
X301045Y60602D01*
X301352Y60860D01*
X301543Y61170D01*
X301582Y61480D01*
X301505Y61842D01*
X301237Y62100D01*
X300968Y62203D01*
X300623D01*
G01X300968D02*
X301198Y62358D01*
X301390Y62617D01*
X301467Y62927D01*
X301390Y63237D01*
X301198Y63495D01*
X300853Y63650D01*
X300508Y63598D01*
X300163Y63392D01*
G01X297902Y173496D02*
X298132Y173806D01*
X298400Y173961D01*
X298707Y174013D01*
X299090Y173910D01*
X299358Y173651D01*
X299435Y173341D01*
X299397Y173031D01*
X299243Y172773D01*
X298477Y172256D01*
X298132Y171895D01*
X297902Y171378D01*
X297825Y170913D01*
X299435D01*
G01X301730Y174013D02*
X301423Y173910D01*
X301193Y173651D01*
X301040Y173341D01*
X300925Y172928D01*
X300887Y172463D01*
X300925Y171998D01*
X301040Y171585D01*
X301193Y171275D01*
X301423Y171016D01*
X301730Y170913D01*
X302037Y171016D01*
X302267Y171275D01*
X302420Y171585D01*
X302535Y171998D01*
X302573Y172463D01*
X302535Y172928D01*
X302420Y173341D01*
X302267Y173651D01*
X302037Y173910D01*
X301730Y174013D01*
G01X304950Y168350D02*
X308050D01*
G01X304950Y167468D02*
Y169232D01*
G01X308050Y170683D02*
X304950D01*
Y171603D01*
X305105Y171910D01*
X305467Y172140D01*
X305880Y172217D01*
X306293Y172140D01*
X306603Y171948D01*
X306758Y171603D01*
Y170683D01*
G01X307585Y173707D02*
X307843Y173937D01*
X307998Y174205D01*
X308050Y174550D01*
X307947Y174895D01*
X307740Y175163D01*
X307378Y175355D01*
X306965Y175393D01*
X306552Y175317D01*
X306293Y175125D01*
X306087Y174857D01*
X306035Y174588D01*
X306087Y174320D01*
X306293Y173975D01*
X304950Y174090D01*
Y175125D01*
G01X308050Y177650D02*
X304950D01*
X305570Y177190D01*
G01X308050D02*
Y178110D01*
G01X299291Y192614D02*
X299521Y192924D01*
X299789Y193079D01*
X300096Y193131D01*
X300479Y193028D01*
X300747Y192769D01*
X300824Y192459D01*
X300786Y192149D01*
X300632Y191891D01*
X299866Y191374D01*
X299521Y191013D01*
X299291Y190496D01*
X299214Y190031D01*
X300824D01*
G01X302450Y320500D02*
Y323600D01*
X301990Y322980D01*
G01Y320500D02*
X302910D01*
G01X304822Y321792D02*
X305090Y322153D01*
X305320Y322360D01*
X305627Y322463D01*
X305895Y322360D01*
X306087Y322153D01*
X306240Y321843D01*
X306278Y321482D01*
X306240Y321172D01*
X306087Y320862D01*
X305857Y320603D01*
X305588Y320500D01*
X305282Y320603D01*
X305013Y320913D01*
X304860Y321378D01*
X304822Y321895D01*
X304898Y322567D01*
X305013Y322928D01*
X305205Y323290D01*
X305473Y323548D01*
X305742Y323600D01*
X306010Y323497D01*
X306202Y323238D01*
G01X303848Y339362D02*
X304117Y339103D01*
X304423Y339000D01*
X304730Y339103D01*
X304998Y339413D01*
X305190Y339878D01*
X305267Y340343D01*
Y340912D01*
X305190Y341377D01*
X304998Y341790D01*
X304768Y341997D01*
X304500Y342100D01*
X304193Y341997D01*
X303963Y341790D01*
X303810Y341480D01*
X303733Y341067D01*
X303810Y340705D01*
X304002Y340343D01*
X304232Y340137D01*
X304500Y340085D01*
X304807Y340188D01*
X305037Y340447D01*
X305267Y340912D01*
G01X304272Y369583D02*
X304502Y369893D01*
X304770Y370048D01*
X305077Y370100D01*
X305460Y369997D01*
X305728Y369738D01*
X305805Y369428D01*
X305767Y369118D01*
X305613Y368860D01*
X304847Y368343D01*
X304502Y367982D01*
X304272Y367465D01*
X304195Y367000D01*
X305805D01*
G01X303450Y384183D02*
X306550D01*
Y385717D01*
G01X303967Y387322D02*
X303657Y387552D01*
X303502Y387820D01*
X303450Y388127D01*
X303553Y388510D01*
X303812Y388778D01*
X304122Y388855D01*
X304432Y388817D01*
X304690Y388663D01*
X305207Y387897D01*
X305568Y387552D01*
X306085Y387322D01*
X306550Y387245D01*
Y388855D01*
G01X305000Y403500D02*
Y406600D01*
X304540Y405980D01*
G01Y403500D02*
X305460D01*
G01X309083Y162950D02*
Y166050D01*
X310042D01*
X310348Y165895D01*
X310540Y165688D01*
X310617Y165275D01*
X310540Y164862D01*
X310310Y164603D01*
X310042Y164448D01*
X309083D01*
G01X310042D02*
X310617Y162950D01*
G01X312222Y165533D02*
X312452Y165843D01*
X312720Y165998D01*
X313027Y166050D01*
X313410Y165947D01*
X313678Y165688D01*
X313755Y165378D01*
X313717Y165068D01*
X313563Y164810D01*
X312797Y164293D01*
X312452Y163932D01*
X312222Y163415D01*
X312145Y162950D01*
X313755D01*
G01X316050D02*
X316318Y163002D01*
X316625Y163157D01*
X316817Y163415D01*
X316893Y163777D01*
X316817Y164138D01*
X316587Y164448D01*
X316242Y164603D01*
X315858D01*
X315628Y164707D01*
X315437Y164965D01*
X315360Y165327D01*
X315475Y165688D01*
X315743Y165947D01*
X316050Y166050D01*
X316357Y165947D01*
X316625Y165688D01*
X316740Y165327D01*
X316663Y164965D01*
X316472Y164707D01*
X316242Y164603D01*
X315858D01*
X315513Y164448D01*
X315283Y164138D01*
X315207Y163777D01*
X315283Y163415D01*
X315475Y163157D01*
X315782Y163002D01*
X316050Y162950D01*
G01X319073D02*
X319150Y163622D01*
X319265Y164190D01*
X319418Y164707D01*
X319610Y165275D01*
X319917Y166050D01*
X318383D01*
G01X310533Y178450D02*
Y181550D01*
X311492D01*
X311798Y181395D01*
X311990Y181188D01*
X312067Y180775D01*
X311990Y180362D01*
X311760Y180103D01*
X311492Y179948D01*
X310533D01*
G01X311492D02*
X312067Y178450D01*
G01X314400D02*
X314668Y178502D01*
X314975Y178657D01*
X315167Y178915D01*
X315243Y179277D01*
X315167Y179638D01*
X314937Y179948D01*
X314592Y180103D01*
X314208D01*
X313978Y180207D01*
X313787Y180465D01*
X313710Y180827D01*
X313825Y181188D01*
X314093Y181447D01*
X314400Y181550D01*
X314707Y181447D01*
X314975Y181188D01*
X315090Y180827D01*
X315013Y180465D01*
X314822Y180207D01*
X314592Y180103D01*
X314208D01*
X313863Y179948D01*
X313633Y179638D01*
X313557Y179277D01*
X313633Y178915D01*
X313825Y178657D01*
X314132Y178502D01*
X314400Y178450D01*
G01X317423D02*
X317500Y179122D01*
X317615Y179690D01*
X317768Y180207D01*
X317960Y180775D01*
X318267Y181550D01*
X316733D01*
G01X310633Y167950D02*
Y171050D01*
X311592D01*
X311898Y170895D01*
X312090Y170688D01*
X312167Y170275D01*
X312090Y169862D01*
X311860Y169603D01*
X311592Y169448D01*
X310633D01*
G01X311592D02*
X312167Y167950D01*
G01X313848Y168312D02*
X314117Y168053D01*
X314423Y167950D01*
X314730Y168053D01*
X314998Y168363D01*
X315190Y168828D01*
X315267Y169293D01*
Y169862D01*
X315190Y170327D01*
X314998Y170740D01*
X314768Y170947D01*
X314500Y171050D01*
X314193Y170947D01*
X313963Y170740D01*
X313810Y170430D01*
X313733Y170017D01*
X313810Y169655D01*
X314002Y169293D01*
X314232Y169087D01*
X314500Y169035D01*
X314807Y169138D01*
X315037Y169397D01*
X315267Y169862D01*
G01X316872Y169242D02*
X317140Y169603D01*
X317370Y169810D01*
X317677Y169913D01*
X317945Y169810D01*
X318137Y169603D01*
X318290Y169293D01*
X318328Y168932D01*
X318290Y168622D01*
X318137Y168312D01*
X317907Y168053D01*
X317638Y167950D01*
X317332Y168053D01*
X317063Y168363D01*
X316910Y168828D01*
X316872Y169345D01*
X316948Y170017D01*
X317063Y170378D01*
X317255Y170740D01*
X317523Y170998D01*
X317792Y171050D01*
X318060Y170947D01*
X318252Y170688D01*
G01X310533Y173450D02*
Y176550D01*
X311492D01*
X311798Y176395D01*
X311990Y176188D01*
X312067Y175775D01*
X311990Y175362D01*
X311760Y175103D01*
X311492Y174948D01*
X310533D01*
G01X311492D02*
X312067Y173450D01*
G01X314400D02*
X314668Y173502D01*
X314975Y173657D01*
X315167Y173915D01*
X315243Y174277D01*
X315167Y174638D01*
X314937Y174948D01*
X314592Y175103D01*
X314208D01*
X313978Y175207D01*
X313787Y175465D01*
X313710Y175827D01*
X313825Y176188D01*
X314093Y176447D01*
X314400Y176550D01*
X314707Y176447D01*
X314975Y176188D01*
X315090Y175827D01*
X315013Y175465D01*
X314822Y175207D01*
X314592Y175103D01*
X314208D01*
X313863Y174948D01*
X313633Y174638D01*
X313557Y174277D01*
X313633Y173915D01*
X313825Y173657D01*
X314132Y173502D01*
X314400Y173450D01*
G01X317500D02*
X317768Y173502D01*
X318075Y173657D01*
X318267Y173915D01*
X318343Y174277D01*
X318267Y174638D01*
X318037Y174948D01*
X317692Y175103D01*
X317308D01*
X317078Y175207D01*
X316887Y175465D01*
X316810Y175827D01*
X316925Y176188D01*
X317193Y176447D01*
X317500Y176550D01*
X317807Y176447D01*
X318075Y176188D01*
X318190Y175827D01*
X318113Y175465D01*
X317922Y175207D01*
X317692Y175103D01*
X317308D01*
X316963Y174948D01*
X316733Y174638D01*
X316657Y174277D01*
X316733Y173915D01*
X316925Y173657D01*
X317232Y173502D01*
X317500Y173450D01*
G01X315033Y194950D02*
Y198050D01*
X315992D01*
X316298Y197895D01*
X316490Y197688D01*
X316567Y197275D01*
X316490Y196862D01*
X316260Y196603D01*
X315992Y196448D01*
X315033D01*
G01X315992D02*
X316567Y194950D01*
G01X318900D02*
X319168Y195002D01*
X319475Y195157D01*
X319667Y195415D01*
X319743Y195777D01*
X319667Y196138D01*
X319437Y196448D01*
X319092Y196603D01*
X318708D01*
X318478Y196707D01*
X318287Y196965D01*
X318210Y197327D01*
X318325Y197688D01*
X318593Y197947D01*
X318900Y198050D01*
X319207Y197947D01*
X319475Y197688D01*
X319590Y197327D01*
X319513Y196965D01*
X319322Y196707D01*
X319092Y196603D01*
X318708D01*
X318363Y196448D01*
X318133Y196138D01*
X318057Y195777D01*
X318133Y195415D01*
X318325Y195157D01*
X318632Y195002D01*
X318900Y194950D01*
G01X321272Y196242D02*
X321540Y196603D01*
X321770Y196810D01*
X322077Y196913D01*
X322345Y196810D01*
X322537Y196603D01*
X322690Y196293D01*
X322728Y195932D01*
X322690Y195622D01*
X322537Y195312D01*
X322307Y195053D01*
X322038Y194950D01*
X321732Y195053D01*
X321463Y195363D01*
X321310Y195828D01*
X321272Y196345D01*
X321348Y197017D01*
X321463Y197378D01*
X321655Y197740D01*
X321923Y197998D01*
X322192Y198050D01*
X322460Y197947D01*
X322652Y197688D01*
G01X310133Y187950D02*
Y191050D01*
X311092D01*
X311398Y190895D01*
X311590Y190688D01*
X311667Y190275D01*
X311590Y189862D01*
X311360Y189603D01*
X311092Y189448D01*
X310133D01*
G01X311092D02*
X311667Y187950D01*
G01X313348Y188312D02*
X313617Y188053D01*
X313923Y187950D01*
X314230Y188053D01*
X314498Y188363D01*
X314690Y188828D01*
X314767Y189293D01*
Y189862D01*
X314690Y190327D01*
X314498Y190740D01*
X314268Y190947D01*
X314000Y191050D01*
X313693Y190947D01*
X313463Y190740D01*
X313310Y190430D01*
X313233Y190017D01*
X313310Y189655D01*
X313502Y189293D01*
X313732Y189087D01*
X314000Y189035D01*
X314307Y189138D01*
X314537Y189397D01*
X314767Y189862D01*
G01X317023Y187950D02*
X317100Y188622D01*
X317215Y189190D01*
X317368Y189707D01*
X317560Y190275D01*
X317867Y191050D01*
X316333D01*
G01X310133Y183450D02*
Y186550D01*
X311092D01*
X311398Y186395D01*
X311590Y186188D01*
X311667Y185775D01*
X311590Y185362D01*
X311360Y185103D01*
X311092Y184948D01*
X310133D01*
G01X311092D02*
X311667Y183450D01*
G01X313348Y183812D02*
X313617Y183553D01*
X313923Y183450D01*
X314230Y183553D01*
X314498Y183863D01*
X314690Y184328D01*
X314767Y184793D01*
Y185362D01*
X314690Y185827D01*
X314498Y186240D01*
X314268Y186447D01*
X314000Y186550D01*
X313693Y186447D01*
X313463Y186240D01*
X313310Y185930D01*
X313233Y185517D01*
X313310Y185155D01*
X313502Y184793D01*
X313732Y184587D01*
X314000Y184535D01*
X314307Y184638D01*
X314537Y184897D01*
X314767Y185362D01*
G01X317100Y183450D02*
X317368Y183502D01*
X317675Y183657D01*
X317867Y183915D01*
X317943Y184277D01*
X317867Y184638D01*
X317637Y184948D01*
X317292Y185103D01*
X316908D01*
X316678Y185207D01*
X316487Y185465D01*
X316410Y185827D01*
X316525Y186188D01*
X316793Y186447D01*
X317100Y186550D01*
X317407Y186447D01*
X317675Y186188D01*
X317790Y185827D01*
X317713Y185465D01*
X317522Y185207D01*
X317292Y185103D01*
X316908D01*
X316563Y184948D01*
X316333Y184638D01*
X316257Y184277D01*
X316333Y183915D01*
X316525Y183657D01*
X316832Y183502D01*
X317100Y183450D01*
G01X322083Y214950D02*
Y218050D01*
X323042D01*
X323348Y217895D01*
X323540Y217688D01*
X323617Y217275D01*
X323540Y216862D01*
X323310Y216603D01*
X323042Y216448D01*
X322083D01*
G01X323042D02*
X323617Y214950D01*
G01X325222Y217533D02*
X325452Y217843D01*
X325720Y217998D01*
X326027Y218050D01*
X326410Y217947D01*
X326678Y217688D01*
X326755Y217378D01*
X326717Y217068D01*
X326563Y216810D01*
X325797Y216293D01*
X325452Y215932D01*
X325222Y215415D01*
X325145Y214950D01*
X326755D01*
G01X328398Y215312D02*
X328667Y215053D01*
X328973Y214950D01*
X329280Y215053D01*
X329548Y215363D01*
X329740Y215828D01*
X329817Y216293D01*
Y216862D01*
X329740Y217327D01*
X329548Y217740D01*
X329318Y217947D01*
X329050Y218050D01*
X328743Y217947D01*
X328513Y217740D01*
X328360Y217430D01*
X328283Y217017D01*
X328360Y216655D01*
X328552Y216293D01*
X328782Y216087D01*
X329050Y216035D01*
X329357Y216138D01*
X329587Y216397D01*
X329817Y216862D01*
G01X332150Y218050D02*
X331843Y217947D01*
X331613Y217688D01*
X331460Y217378D01*
X331345Y216965D01*
X331307Y216500D01*
X331345Y216035D01*
X331460Y215622D01*
X331613Y215312D01*
X331843Y215053D01*
X332150Y214950D01*
X332457Y215053D01*
X332687Y215312D01*
X332840Y215622D01*
X332955Y216035D01*
X332993Y216500D01*
X332955Y216965D01*
X332840Y217378D01*
X332687Y217688D01*
X332457Y217947D01*
X332150Y218050D01*
G01X315033Y199950D02*
Y203050D01*
X315992D01*
X316298Y202895D01*
X316490Y202688D01*
X316567Y202275D01*
X316490Y201862D01*
X316260Y201603D01*
X315992Y201448D01*
X315033D01*
G01X315992D02*
X316567Y199950D01*
G01X318900D02*
X319168Y200002D01*
X319475Y200157D01*
X319667Y200415D01*
X319743Y200777D01*
X319667Y201138D01*
X319437Y201448D01*
X319092Y201603D01*
X318708D01*
X318478Y201707D01*
X318287Y201965D01*
X318210Y202327D01*
X318325Y202688D01*
X318593Y202947D01*
X318900Y203050D01*
X319207Y202947D01*
X319475Y202688D01*
X319590Y202327D01*
X319513Y201965D01*
X319322Y201707D01*
X319092Y201603D01*
X318708D01*
X318363Y201448D01*
X318133Y201138D01*
X318057Y200777D01*
X318133Y200415D01*
X318325Y200157D01*
X318632Y200002D01*
X318900Y199950D01*
G01X321157Y200415D02*
X321387Y200157D01*
X321655Y200002D01*
X322000Y199950D01*
X322345Y200053D01*
X322613Y200260D01*
X322805Y200622D01*
X322843Y201035D01*
X322767Y201448D01*
X322575Y201707D01*
X322307Y201913D01*
X322038Y201965D01*
X321770Y201913D01*
X321425Y201707D01*
X321540Y203050D01*
X322575D01*
G01X315033Y204450D02*
Y207550D01*
X315992D01*
X316298Y207395D01*
X316490Y207188D01*
X316567Y206775D01*
X316490Y206362D01*
X316260Y206103D01*
X315992Y205948D01*
X315033D01*
G01X315992D02*
X316567Y204450D01*
G01X318900D02*
X319168Y204502D01*
X319475Y204657D01*
X319667Y204915D01*
X319743Y205277D01*
X319667Y205638D01*
X319437Y205948D01*
X319092Y206103D01*
X318708D01*
X318478Y206207D01*
X318287Y206465D01*
X318210Y206827D01*
X318325Y207188D01*
X318593Y207447D01*
X318900Y207550D01*
X319207Y207447D01*
X319475Y207188D01*
X319590Y206827D01*
X319513Y206465D01*
X319322Y206207D01*
X319092Y206103D01*
X318708D01*
X318363Y205948D01*
X318133Y205638D01*
X318057Y205277D01*
X318133Y204915D01*
X318325Y204657D01*
X318632Y204502D01*
X318900Y204450D01*
G01X322460D02*
Y207550D01*
X321042Y205328D01*
X322958D01*
G01X315033Y209450D02*
Y212550D01*
X315992D01*
X316298Y212395D01*
X316490Y212188D01*
X316567Y211775D01*
X316490Y211362D01*
X316260Y211103D01*
X315992Y210948D01*
X315033D01*
G01X315992D02*
X316567Y209450D01*
G01X318900D02*
X319168Y209502D01*
X319475Y209657D01*
X319667Y209915D01*
X319743Y210277D01*
X319667Y210638D01*
X319437Y210948D01*
X319092Y211103D01*
X318708D01*
X318478Y211207D01*
X318287Y211465D01*
X318210Y211827D01*
X318325Y212188D01*
X318593Y212447D01*
X318900Y212550D01*
X319207Y212447D01*
X319475Y212188D01*
X319590Y211827D01*
X319513Y211465D01*
X319322Y211207D01*
X319092Y211103D01*
X318708D01*
X318363Y210948D01*
X318133Y210638D01*
X318057Y210277D01*
X318133Y209915D01*
X318325Y209657D01*
X318632Y209502D01*
X318900Y209450D01*
G01X321157Y210070D02*
X321387Y209708D01*
X321693Y209502D01*
X322038Y209450D01*
X322345Y209502D01*
X322652Y209760D01*
X322843Y210070D01*
X322882Y210380D01*
X322805Y210742D01*
X322537Y211000D01*
X322268Y211103D01*
X321923D01*
G01X322268D02*
X322498Y211258D01*
X322690Y211517D01*
X322767Y211827D01*
X322690Y212137D01*
X322498Y212395D01*
X322153Y212550D01*
X321808Y212498D01*
X321463Y212292D01*
G01X309583Y215350D02*
Y218450D01*
X310542D01*
X310848Y218295D01*
X311040Y218088D01*
X311117Y217675D01*
X311040Y217262D01*
X310810Y217003D01*
X310542Y216848D01*
X309583D01*
G01X310542D02*
X311117Y215350D01*
G01X312607Y215970D02*
X312837Y215608D01*
X313143Y215402D01*
X313488Y215350D01*
X313795Y215402D01*
X314102Y215660D01*
X314293Y215970D01*
X314332Y216280D01*
X314255Y216642D01*
X313987Y216900D01*
X313718Y217003D01*
X313373D01*
G01X313718D02*
X313948Y217158D01*
X314140Y217417D01*
X314217Y217727D01*
X314140Y218037D01*
X313948Y218295D01*
X313603Y218450D01*
X313258Y218398D01*
X312913Y218192D01*
G01X316550Y218450D02*
X316243Y218347D01*
X316013Y218088D01*
X315860Y217778D01*
X315745Y217365D01*
X315707Y216900D01*
X315745Y216435D01*
X315860Y216022D01*
X316013Y215712D01*
X316243Y215453D01*
X316550Y215350D01*
X316857Y215453D01*
X317087Y215712D01*
X317240Y216022D01*
X317355Y216435D01*
X317393Y216900D01*
X317355Y217365D01*
X317240Y217778D01*
X317087Y218088D01*
X316857Y218347D01*
X316550Y218450D01*
G01X318922Y217933D02*
X319152Y218243D01*
X319420Y218398D01*
X319727Y218450D01*
X320110Y218347D01*
X320378Y218088D01*
X320455Y217778D01*
X320417Y217468D01*
X320263Y217210D01*
X319497Y216693D01*
X319152Y216332D01*
X318922Y215815D01*
X318845Y215350D01*
X320455D01*
G01X309583Y219850D02*
Y222950D01*
X310542D01*
X310848Y222795D01*
X311040Y222588D01*
X311117Y222175D01*
X311040Y221762D01*
X310810Y221503D01*
X310542Y221348D01*
X309583D01*
G01X310542D02*
X311117Y219850D01*
G01X312722Y222433D02*
X312952Y222743D01*
X313220Y222898D01*
X313527Y222950D01*
X313910Y222847D01*
X314178Y222588D01*
X314255Y222278D01*
X314217Y221968D01*
X314063Y221710D01*
X313297Y221193D01*
X312952Y220832D01*
X312722Y220315D01*
X312645Y219850D01*
X314255D01*
G01X316550D02*
X316818Y219902D01*
X317125Y220057D01*
X317317Y220315D01*
X317393Y220677D01*
X317317Y221038D01*
X317087Y221348D01*
X316742Y221503D01*
X316358D01*
X316128Y221607D01*
X315937Y221865D01*
X315860Y222227D01*
X315975Y222588D01*
X316243Y222847D01*
X316550Y222950D01*
X316857Y222847D01*
X317125Y222588D01*
X317240Y222227D01*
X317163Y221865D01*
X316972Y221607D01*
X316742Y221503D01*
X316358D01*
X316013Y221348D01*
X315783Y221038D01*
X315707Y220677D01*
X315783Y220315D01*
X315975Y220057D01*
X316282Y219902D01*
X316550Y219850D01*
G01X318998Y220212D02*
X319267Y219953D01*
X319573Y219850D01*
X319880Y219953D01*
X320148Y220263D01*
X320340Y220728D01*
X320417Y221193D01*
Y221762D01*
X320340Y222227D01*
X320148Y222640D01*
X319918Y222847D01*
X319650Y222950D01*
X319343Y222847D01*
X319113Y222640D01*
X318960Y222330D01*
X318883Y221917D01*
X318960Y221555D01*
X319152Y221193D01*
X319382Y220987D01*
X319650Y220935D01*
X319957Y221038D01*
X320187Y221297D01*
X320417Y221762D01*
G01X312583Y232850D02*
Y235950D01*
X313542D01*
X313848Y235795D01*
X314040Y235588D01*
X314117Y235175D01*
X314040Y234762D01*
X313810Y234503D01*
X313542Y234348D01*
X312583D01*
G01X313542D02*
X314117Y232850D01*
G01X315607Y233470D02*
X315837Y233108D01*
X316143Y232902D01*
X316488Y232850D01*
X316795Y232902D01*
X317102Y233160D01*
X317293Y233470D01*
X317332Y233780D01*
X317255Y234142D01*
X316987Y234400D01*
X316718Y234503D01*
X316373D01*
G01X316718D02*
X316948Y234658D01*
X317140Y234917D01*
X317217Y235227D01*
X317140Y235537D01*
X316948Y235795D01*
X316603Y235950D01*
X316258Y235898D01*
X315913Y235692D01*
G01X319550Y235950D02*
X319243Y235847D01*
X319013Y235588D01*
X318860Y235278D01*
X318745Y234865D01*
X318707Y234400D01*
X318745Y233935D01*
X318860Y233522D01*
X319013Y233212D01*
X319243Y232953D01*
X319550Y232850D01*
X319857Y232953D01*
X320087Y233212D01*
X320240Y233522D01*
X320355Y233935D01*
X320393Y234400D01*
X320355Y234865D01*
X320240Y235278D01*
X320087Y235588D01*
X319857Y235847D01*
X319550Y235950D01*
G01X322650Y232850D02*
Y235950D01*
X322190Y235330D01*
G01Y232850D02*
X323110D01*
G01X314133Y228350D02*
Y231450D01*
X315092D01*
X315398Y231295D01*
X315590Y231088D01*
X315667Y230675D01*
X315590Y230262D01*
X315360Y230003D01*
X315092Y229848D01*
X314133D01*
G01X315092D02*
X315667Y228350D01*
G01X317923D02*
X318000Y229022D01*
X318115Y229590D01*
X318268Y230107D01*
X318460Y230675D01*
X318767Y231450D01*
X317233D01*
G01X321100Y228350D02*
X321368Y228402D01*
X321675Y228557D01*
X321867Y228815D01*
X321943Y229177D01*
X321867Y229538D01*
X321637Y229848D01*
X321292Y230003D01*
X320908D01*
X320678Y230107D01*
X320487Y230365D01*
X320410Y230727D01*
X320525Y231088D01*
X320793Y231347D01*
X321100Y231450D01*
X321407Y231347D01*
X321675Y231088D01*
X321790Y230727D01*
X321713Y230365D01*
X321522Y230107D01*
X321292Y230003D01*
X320908D01*
X320563Y229848D01*
X320333Y229538D01*
X320257Y229177D01*
X320333Y228815D01*
X320525Y228557D01*
X320832Y228402D01*
X321100Y228350D01*
G01X314133Y223850D02*
Y226950D01*
X315092D01*
X315398Y226795D01*
X315590Y226588D01*
X315667Y226175D01*
X315590Y225762D01*
X315360Y225503D01*
X315092Y225348D01*
X314133D01*
G01X315092D02*
X315667Y223850D01*
G01X317923D02*
X318000Y224522D01*
X318115Y225090D01*
X318268Y225607D01*
X318460Y226175D01*
X318767Y226950D01*
X317233D01*
G01X320448Y224212D02*
X320717Y223953D01*
X321023Y223850D01*
X321330Y223953D01*
X321598Y224263D01*
X321790Y224728D01*
X321867Y225193D01*
Y225762D01*
X321790Y226227D01*
X321598Y226640D01*
X321368Y226847D01*
X321100Y226950D01*
X320793Y226847D01*
X320563Y226640D01*
X320410Y226330D01*
X320333Y225917D01*
X320410Y225555D01*
X320602Y225193D01*
X320832Y224987D01*
X321100Y224935D01*
X321407Y225038D01*
X321637Y225297D01*
X321867Y225762D01*
G01X314193Y253692D02*
X313963Y253847D01*
X313695Y253950D01*
X313388D01*
X313043Y253795D01*
X312775Y253537D01*
X312583Y253227D01*
X312430Y252710D01*
X312392Y252245D01*
X312468Y251780D01*
X312583Y251470D01*
X312813Y251160D01*
X313082Y250953D01*
X313350Y250850D01*
X313618D01*
X313887Y250953D01*
X314117Y251108D01*
X314308Y251315D01*
G01X315722Y253433D02*
X315952Y253743D01*
X316220Y253898D01*
X316527Y253950D01*
X316910Y253847D01*
X317178Y253588D01*
X317255Y253278D01*
X317217Y252968D01*
X317063Y252710D01*
X316297Y252193D01*
X315952Y251832D01*
X315722Y251315D01*
X315645Y250850D01*
X317255D01*
G01X319550D02*
X319818Y250902D01*
X320125Y251057D01*
X320317Y251315D01*
X320393Y251677D01*
X320317Y252038D01*
X320087Y252348D01*
X319742Y252503D01*
X319358D01*
X319128Y252607D01*
X318937Y252865D01*
X318860Y253227D01*
X318975Y253588D01*
X319243Y253847D01*
X319550Y253950D01*
X319857Y253847D01*
X320125Y253588D01*
X320240Y253227D01*
X320163Y252865D01*
X319972Y252607D01*
X319742Y252503D01*
X319358D01*
X319013Y252348D01*
X318783Y252038D01*
X318707Y251677D01*
X318783Y251315D01*
X318975Y251057D01*
X319282Y250902D01*
X319550Y250850D01*
G01X321807Y251315D02*
X322037Y251057D01*
X322305Y250902D01*
X322650Y250850D01*
X322995Y250953D01*
X323263Y251160D01*
X323455Y251522D01*
X323493Y251935D01*
X323417Y252348D01*
X323225Y252607D01*
X322957Y252813D01*
X322688Y252865D01*
X322420Y252813D01*
X322075Y252607D01*
X322190Y253950D01*
X323225D01*
G01X312583Y246350D02*
Y249450D01*
X313542D01*
X313848Y249295D01*
X314040Y249088D01*
X314117Y248675D01*
X314040Y248262D01*
X313810Y248003D01*
X313542Y247848D01*
X312583D01*
G01X313542D02*
X314117Y246350D01*
G01X315607Y246970D02*
X315837Y246608D01*
X316143Y246402D01*
X316488Y246350D01*
X316795Y246402D01*
X317102Y246660D01*
X317293Y246970D01*
X317332Y247280D01*
X317255Y247642D01*
X316987Y247900D01*
X316718Y248003D01*
X316373D01*
G01X316718D02*
X316948Y248158D01*
X317140Y248417D01*
X317217Y248727D01*
X317140Y249037D01*
X316948Y249295D01*
X316603Y249450D01*
X316258Y249398D01*
X315913Y249192D01*
G01X319550Y249450D02*
X319243Y249347D01*
X319013Y249088D01*
X318860Y248778D01*
X318745Y248365D01*
X318707Y247900D01*
X318745Y247435D01*
X318860Y247022D01*
X319013Y246712D01*
X319243Y246453D01*
X319550Y246350D01*
X319857Y246453D01*
X320087Y246712D01*
X320240Y247022D01*
X320355Y247435D01*
X320393Y247900D01*
X320355Y248365D01*
X320240Y248778D01*
X320087Y249088D01*
X319857Y249347D01*
X319550Y249450D01*
G01X322573Y246350D02*
X322650Y247022D01*
X322765Y247590D01*
X322918Y248107D01*
X323110Y248675D01*
X323417Y249450D01*
X321883D01*
G01X312583Y237350D02*
Y240450D01*
X313542D01*
X313848Y240295D01*
X314040Y240088D01*
X314117Y239675D01*
X314040Y239262D01*
X313810Y239003D01*
X313542Y238848D01*
X312583D01*
G01X313542D02*
X314117Y237350D01*
G01X315722Y239933D02*
X315952Y240243D01*
X316220Y240398D01*
X316527Y240450D01*
X316910Y240347D01*
X317178Y240088D01*
X317255Y239778D01*
X317217Y239468D01*
X317063Y239210D01*
X316297Y238693D01*
X315952Y238332D01*
X315722Y237815D01*
X315645Y237350D01*
X317255D01*
G01X318898Y237712D02*
X319167Y237453D01*
X319473Y237350D01*
X319780Y237453D01*
X320048Y237763D01*
X320240Y238228D01*
X320317Y238693D01*
Y239262D01*
X320240Y239727D01*
X320048Y240140D01*
X319818Y240347D01*
X319550Y240450D01*
X319243Y240347D01*
X319013Y240140D01*
X318860Y239830D01*
X318783Y239417D01*
X318860Y239055D01*
X319052Y238693D01*
X319282Y238487D01*
X319550Y238435D01*
X319857Y238538D01*
X320087Y238797D01*
X320317Y239262D01*
G01X322650Y237350D02*
Y240450D01*
X322190Y239830D01*
G01Y237350D02*
X323110D01*
G01X312583Y241850D02*
Y244950D01*
X313542D01*
X313848Y244795D01*
X314040Y244588D01*
X314117Y244175D01*
X314040Y243762D01*
X313810Y243503D01*
X313542Y243348D01*
X312583D01*
G01X313542D02*
X314117Y241850D01*
G01X315607Y242470D02*
X315837Y242108D01*
X316143Y241902D01*
X316488Y241850D01*
X316795Y241902D01*
X317102Y242160D01*
X317293Y242470D01*
X317332Y242780D01*
X317255Y243142D01*
X316987Y243400D01*
X316718Y243503D01*
X316373D01*
G01X316718D02*
X316948Y243658D01*
X317140Y243917D01*
X317217Y244227D01*
X317140Y244537D01*
X316948Y244795D01*
X316603Y244950D01*
X316258Y244898D01*
X315913Y244692D01*
G01X319550Y244950D02*
X319243Y244847D01*
X319013Y244588D01*
X318860Y244278D01*
X318745Y243865D01*
X318707Y243400D01*
X318745Y242935D01*
X318860Y242522D01*
X319013Y242212D01*
X319243Y241953D01*
X319550Y241850D01*
X319857Y241953D01*
X320087Y242212D01*
X320240Y242522D01*
X320355Y242935D01*
X320393Y243400D01*
X320355Y243865D01*
X320240Y244278D01*
X320087Y244588D01*
X319857Y244847D01*
X319550Y244950D01*
G01X321922Y243142D02*
X322190Y243503D01*
X322420Y243710D01*
X322727Y243813D01*
X322995Y243710D01*
X323187Y243503D01*
X323340Y243193D01*
X323378Y242832D01*
X323340Y242522D01*
X323187Y242212D01*
X322957Y241953D01*
X322688Y241850D01*
X322382Y241953D01*
X322113Y242263D01*
X321960Y242728D01*
X321922Y243245D01*
X321998Y243917D01*
X322113Y244278D01*
X322305Y244640D01*
X322573Y244898D01*
X322842Y244950D01*
X323110Y244847D01*
X323302Y244588D01*
G01X312583Y255350D02*
Y258450D01*
X313542D01*
X313848Y258295D01*
X314040Y258088D01*
X314117Y257675D01*
X314040Y257262D01*
X313810Y257003D01*
X313542Y256848D01*
X312583D01*
G01X313542D02*
X314117Y255350D01*
G01X315607Y255970D02*
X315837Y255608D01*
X316143Y255402D01*
X316488Y255350D01*
X316795Y255402D01*
X317102Y255660D01*
X317293Y255970D01*
X317332Y256280D01*
X317255Y256642D01*
X316987Y256900D01*
X316718Y257003D01*
X316373D01*
G01X316718D02*
X316948Y257158D01*
X317140Y257417D01*
X317217Y257727D01*
X317140Y258037D01*
X316948Y258295D01*
X316603Y258450D01*
X316258Y258398D01*
X315913Y258192D01*
G01X319550Y258450D02*
X319243Y258347D01*
X319013Y258088D01*
X318860Y257778D01*
X318745Y257365D01*
X318707Y256900D01*
X318745Y256435D01*
X318860Y256022D01*
X319013Y255712D01*
X319243Y255453D01*
X319550Y255350D01*
X319857Y255453D01*
X320087Y255712D01*
X320240Y256022D01*
X320355Y256435D01*
X320393Y256900D01*
X320355Y257365D01*
X320240Y257778D01*
X320087Y258088D01*
X319857Y258347D01*
X319550Y258450D01*
G01X321807Y255815D02*
X322037Y255557D01*
X322305Y255402D01*
X322650Y255350D01*
X322995Y255453D01*
X323263Y255660D01*
X323455Y256022D01*
X323493Y256435D01*
X323417Y256848D01*
X323225Y257107D01*
X322957Y257313D01*
X322688Y257365D01*
X322420Y257313D01*
X322075Y257107D01*
X322190Y258450D01*
X323225D01*
G01X321950Y260850D02*
X325050D01*
G01X321950Y259968D02*
Y261732D01*
G01X325050Y263183D02*
X321950D01*
Y264103D01*
X322105Y264410D01*
X322467Y264640D01*
X322880Y264717D01*
X323293Y264640D01*
X323603Y264448D01*
X323758Y264103D01*
Y263183D01*
G01X325050Y267050D02*
X321950D01*
X322570Y266590D01*
G01X325050D02*
Y267510D01*
G01X323758Y269422D02*
X323397Y269690D01*
X323190Y269920D01*
X323087Y270227D01*
X323190Y270495D01*
X323397Y270687D01*
X323707Y270840D01*
X324068Y270878D01*
X324378Y270840D01*
X324688Y270687D01*
X324947Y270457D01*
X325050Y270188D01*
X324947Y269882D01*
X324637Y269613D01*
X324172Y269460D01*
X323655Y269422D01*
X322983Y269498D01*
X322622Y269613D01*
X322260Y269805D01*
X322002Y270073D01*
X321950Y270342D01*
X322053Y270610D01*
X322312Y270802D01*
G01X320779Y284472D02*
Y287572D01*
X319361Y285350D01*
X321277D01*
G01X319722Y276125D02*
X319952Y276435D01*
X320220Y276590D01*
X320527Y276642D01*
X320910Y276539D01*
X321178Y276280D01*
X321255Y275970D01*
X321217Y275660D01*
X321063Y275402D01*
X320297Y274885D01*
X319952Y274524D01*
X319722Y274007D01*
X319645Y273542D01*
X321255D01*
G01X313807Y333050D02*
Y330828D01*
X313960Y330363D01*
X314267Y330053D01*
X314650Y329950D01*
X315033Y330053D01*
X315340Y330363D01*
X315493Y330828D01*
Y333050D01*
G01X318210Y329950D02*
Y333050D01*
X316792Y330828D01*
X318708D01*
G01X327500Y191083D02*
X324400D01*
Y192042D01*
X324555Y192348D01*
X324762Y192540D01*
X325175Y192617D01*
X325588Y192540D01*
X325847Y192310D01*
X326002Y192042D01*
Y191083D01*
G01Y192042D02*
X327500Y192617D01*
G01X324917Y194222D02*
X324607Y194452D01*
X324452Y194720D01*
X324400Y195027D01*
X324503Y195410D01*
X324762Y195678D01*
X325072Y195755D01*
X325382Y195717D01*
X325640Y195563D01*
X326157Y194797D01*
X326518Y194452D01*
X327035Y194222D01*
X327500Y194145D01*
Y195755D01*
G01Y197973D02*
X326828Y198050D01*
X326260Y198165D01*
X325743Y198318D01*
X325175Y198510D01*
X324400Y198817D01*
Y197283D01*
G01X326208Y200422D02*
X325847Y200690D01*
X325640Y200920D01*
X325537Y201227D01*
X325640Y201495D01*
X325847Y201687D01*
X326157Y201840D01*
X326518Y201878D01*
X326828Y201840D01*
X327138Y201687D01*
X327397Y201457D01*
X327500Y201188D01*
X327397Y200882D01*
X327087Y200613D01*
X326622Y200460D01*
X326105Y200422D01*
X325433Y200498D01*
X325072Y200613D01*
X324710Y200805D01*
X324452Y201073D01*
X324400Y201342D01*
X324503Y201610D01*
X324762Y201802D01*
G01X327450Y203083D02*
X324350D01*
Y204042D01*
X324505Y204348D01*
X324712Y204540D01*
X325125Y204617D01*
X325538Y204540D01*
X325797Y204310D01*
X325952Y204042D01*
Y203083D01*
G01Y204042D02*
X327450Y204617D01*
G01X324867Y206222D02*
X324557Y206452D01*
X324402Y206720D01*
X324350Y207027D01*
X324453Y207410D01*
X324712Y207678D01*
X325022Y207755D01*
X325332Y207717D01*
X325590Y207563D01*
X326107Y206797D01*
X326468Y206452D01*
X326985Y206222D01*
X327450Y206145D01*
Y207755D01*
G01Y209973D02*
X326778Y210050D01*
X326210Y210165D01*
X325693Y210318D01*
X325125Y210510D01*
X324350Y210817D01*
Y209283D01*
G01X327450Y213073D02*
X326778Y213150D01*
X326210Y213265D01*
X325693Y213418D01*
X325125Y213610D01*
X324350Y213917D01*
Y212383D01*
G01X335085Y216785D02*
Y219885D01*
X334625Y219265D01*
G01Y216785D02*
X335545D01*
G01X337457Y218077D02*
X337725Y218438D01*
X337955Y218645D01*
X338262Y218748D01*
X338530Y218645D01*
X338722Y218438D01*
X338875Y218128D01*
X338913Y217767D01*
X338875Y217457D01*
X338722Y217147D01*
X338492Y216888D01*
X338223Y216785D01*
X337917Y216888D01*
X337648Y217198D01*
X337495Y217663D01*
X337457Y218180D01*
X337533Y218852D01*
X337648Y219213D01*
X337840Y219575D01*
X338108Y219833D01*
X338377Y219885D01*
X338645Y219782D01*
X338837Y219523D01*
G01X335850Y215050D02*
Y211950D01*
G01X334968Y215050D02*
X336732D01*
G01X338183Y211950D02*
Y215050D01*
X339103D01*
X339410Y214895D01*
X339640Y214533D01*
X339717Y214120D01*
X339640Y213707D01*
X339448Y213397D01*
X339103Y213242D01*
X338183D01*
G01X341322D02*
X341590Y213603D01*
X341820Y213810D01*
X342127Y213913D01*
X342395Y213810D01*
X342587Y213603D01*
X342740Y213293D01*
X342778Y212932D01*
X342740Y212622D01*
X342587Y212312D01*
X342357Y212053D01*
X342088Y211950D01*
X341782Y212053D01*
X341513Y212363D01*
X341360Y212828D01*
X341322Y213345D01*
X341398Y214017D01*
X341513Y214378D01*
X341705Y214740D01*
X341973Y214998D01*
X342242Y215050D01*
X342510Y214947D01*
X342702Y214688D01*
G01X345150Y211950D02*
Y215050D01*
X344690Y214430D01*
G01Y211950D02*
X345610D01*
G01X325088Y220666D02*
Y223766D01*
X324628Y223146D01*
G01Y220666D02*
X325548D01*
G01X327345Y221131D02*
X327575Y220873D01*
X327843Y220718D01*
X328188Y220666D01*
X328533Y220769D01*
X328801Y220976D01*
X328993Y221338D01*
X329031Y221751D01*
X328955Y222164D01*
X328763Y222423D01*
X328495Y222629D01*
X328226Y222681D01*
X327958Y222629D01*
X327613Y222423D01*
X327728Y223766D01*
X328763D01*
G01X335057Y232950D02*
Y230728D01*
X335210Y230263D01*
X335517Y229953D01*
X335900Y229850D01*
X336283Y229953D01*
X336590Y230263D01*
X336743Y230728D01*
Y232950D01*
G01X338272Y232433D02*
X338502Y232743D01*
X338770Y232898D01*
X339077Y232950D01*
X339460Y232847D01*
X339728Y232588D01*
X339805Y232278D01*
X339767Y231968D01*
X339613Y231710D01*
X338847Y231193D01*
X338502Y230832D01*
X338272Y230315D01*
X338195Y229850D01*
X339805D01*
G01X341448Y230212D02*
X341717Y229953D01*
X342023Y229850D01*
X342330Y229953D01*
X342598Y230263D01*
X342790Y230728D01*
X342867Y231193D01*
Y231762D01*
X342790Y232227D01*
X342598Y232640D01*
X342368Y232847D01*
X342100Y232950D01*
X341793Y232847D01*
X341563Y232640D01*
X341410Y232330D01*
X341333Y231917D01*
X341410Y231555D01*
X341602Y231193D01*
X341832Y230987D01*
X342100Y230935D01*
X342407Y231038D01*
X342637Y231297D01*
X342867Y231762D01*
G01X337192Y249393D02*
X337037Y249163D01*
X336934Y248895D01*
Y248588D01*
X337089Y248243D01*
X337347Y247975D01*
X337657Y247783D01*
X338174Y247630D01*
X338639Y247592D01*
X339104Y247668D01*
X339414Y247783D01*
X339724Y248013D01*
X339931Y248282D01*
X340034Y248550D01*
Y248818D01*
X339931Y249087D01*
X339776Y249317D01*
X339569Y249508D01*
G01X337451Y250922D02*
X337141Y251152D01*
X336986Y251420D01*
X336934Y251727D01*
X337037Y252110D01*
X337296Y252378D01*
X337606Y252455D01*
X337916Y252417D01*
X338174Y252263D01*
X338691Y251497D01*
X339052Y251152D01*
X339569Y250922D01*
X340034Y250845D01*
Y252455D01*
G01Y254750D02*
X339982Y255018D01*
X339827Y255325D01*
X339569Y255517D01*
X339207Y255593D01*
X338846Y255517D01*
X338536Y255287D01*
X338381Y254942D01*
Y254558D01*
X338277Y254328D01*
X338019Y254137D01*
X337657Y254060D01*
X337296Y254175D01*
X337037Y254443D01*
X336934Y254750D01*
X337037Y255057D01*
X337296Y255325D01*
X337657Y255440D01*
X338019Y255363D01*
X338277Y255172D01*
X338381Y254942D01*
Y254558D01*
X338536Y254213D01*
X338846Y253983D01*
X339207Y253907D01*
X339569Y253983D01*
X339827Y254175D01*
X339982Y254482D01*
X340034Y254750D01*
G01X336934Y257850D02*
X337037Y257543D01*
X337296Y257313D01*
X337606Y257160D01*
X338019Y257045D01*
X338484Y257007D01*
X338949Y257045D01*
X339362Y257160D01*
X339672Y257313D01*
X339931Y257543D01*
X340034Y257850D01*
X339931Y258157D01*
X339672Y258387D01*
X339362Y258540D01*
X338949Y258655D01*
X338484Y258693D01*
X338019Y258655D01*
X337606Y258540D01*
X337296Y258387D01*
X337037Y258157D01*
X336934Y257850D01*
G01X335050Y247783D02*
X331950D01*
Y248742D01*
X332105Y249048D01*
X332312Y249240D01*
X332725Y249317D01*
X333138Y249240D01*
X333397Y249010D01*
X333552Y248742D01*
Y247783D01*
G01Y248742D02*
X335050Y249317D01*
G01X334430Y250807D02*
X334792Y251037D01*
X334998Y251343D01*
X335050Y251688D01*
X334998Y251995D01*
X334740Y252302D01*
X334430Y252493D01*
X334120Y252532D01*
X333758Y252455D01*
X333500Y252187D01*
X333397Y251918D01*
Y251573D01*
G01Y251918D02*
X333242Y252148D01*
X332983Y252340D01*
X332673Y252417D01*
X332363Y252340D01*
X332105Y252148D01*
X331950Y251803D01*
X332002Y251458D01*
X332208Y251113D01*
G01X331950Y254750D02*
X332053Y254443D01*
X332312Y254213D01*
X332622Y254060D01*
X333035Y253945D01*
X333500Y253907D01*
X333965Y253945D01*
X334378Y254060D01*
X334688Y254213D01*
X334947Y254443D01*
X335050Y254750D01*
X334947Y255057D01*
X334688Y255287D01*
X334378Y255440D01*
X333965Y255555D01*
X333500Y255593D01*
X333035Y255555D01*
X332622Y255440D01*
X332312Y255287D01*
X332053Y255057D01*
X331950Y254750D01*
G01X335050Y258310D02*
X331950D01*
X334172Y256892D01*
Y258808D01*
G01X330050Y247783D02*
X326950D01*
Y248742D01*
X327105Y249048D01*
X327312Y249240D01*
X327725Y249317D01*
X328138Y249240D01*
X328397Y249010D01*
X328552Y248742D01*
Y247783D01*
G01Y248742D02*
X330050Y249317D01*
G01X329430Y250807D02*
X329792Y251037D01*
X329998Y251343D01*
X330050Y251688D01*
X329998Y251995D01*
X329740Y252302D01*
X329430Y252493D01*
X329120Y252532D01*
X328758Y252455D01*
X328500Y252187D01*
X328397Y251918D01*
Y251573D01*
G01Y251918D02*
X328242Y252148D01*
X327983Y252340D01*
X327673Y252417D01*
X327363Y252340D01*
X327105Y252148D01*
X326950Y251803D01*
X327002Y251458D01*
X327208Y251113D01*
G01X326950Y254750D02*
X327053Y254443D01*
X327312Y254213D01*
X327622Y254060D01*
X328035Y253945D01*
X328500Y253907D01*
X328965Y253945D01*
X329378Y254060D01*
X329688Y254213D01*
X329947Y254443D01*
X330050Y254750D01*
X329947Y255057D01*
X329688Y255287D01*
X329378Y255440D01*
X328965Y255555D01*
X328500Y255593D01*
X328035Y255555D01*
X327622Y255440D01*
X327312Y255287D01*
X327053Y255057D01*
X326950Y254750D01*
G01X329430Y257007D02*
X329792Y257237D01*
X329998Y257543D01*
X330050Y257888D01*
X329998Y258195D01*
X329740Y258502D01*
X329430Y258693D01*
X329120Y258732D01*
X328758Y258655D01*
X328500Y258387D01*
X328397Y258118D01*
Y257773D01*
G01Y258118D02*
X328242Y258348D01*
X327983Y258540D01*
X327673Y258617D01*
X327363Y258540D01*
X327105Y258348D01*
X326950Y258003D01*
X327002Y257658D01*
X327208Y257313D01*
G01X341493Y245605D02*
X341723Y245915D01*
X341991Y246070D01*
X342298Y246122D01*
X342681Y246019D01*
X342949Y245760D01*
X343026Y245450D01*
X342988Y245140D01*
X342834Y244882D01*
X342068Y244365D01*
X341723Y244004D01*
X341493Y243487D01*
X341416Y243022D01*
X343026D01*
G01X334560Y243219D02*
X334790Y242961D01*
X335058Y242806D01*
X335403Y242754D01*
X335748Y242857D01*
X336016Y243064D01*
X336208Y243426D01*
X336246Y243839D01*
X336170Y244252D01*
X335978Y244511D01*
X335710Y244717D01*
X335441Y244769D01*
X335173Y244717D01*
X334828Y244511D01*
X334943Y245854D01*
X335978D01*
G01X327244Y240746D02*
X327512Y241107D01*
X327742Y241314D01*
X328049Y241417D01*
X328317Y241314D01*
X328509Y241107D01*
X328662Y240797D01*
X328700Y240436D01*
X328662Y240126D01*
X328509Y239816D01*
X328279Y239557D01*
X328010Y239454D01*
X327704Y239557D01*
X327435Y239867D01*
X327282Y240332D01*
X327244Y240849D01*
X327320Y241521D01*
X327435Y241882D01*
X327627Y242244D01*
X327895Y242502D01*
X328164Y242554D01*
X328432Y242451D01*
X328624Y242192D01*
G01X328950Y260850D02*
X332050D01*
G01X328950Y259968D02*
Y261732D01*
G01X332050Y263183D02*
X328950D01*
Y264103D01*
X329105Y264410D01*
X329467Y264640D01*
X329880Y264717D01*
X330293Y264640D01*
X330603Y264448D01*
X330758Y264103D01*
Y263183D01*
G01X332050Y267050D02*
X328950D01*
X329570Y266590D01*
G01X332050D02*
Y267510D01*
G01Y270073D02*
X331378Y270150D01*
X330810Y270265D01*
X330293Y270418D01*
X329725Y270610D01*
X328950Y270917D01*
Y269383D01*
G01X335950Y261350D02*
X339050D01*
G01X335950Y260468D02*
Y262232D01*
G01X339050Y263683D02*
X335950D01*
Y264603D01*
X336105Y264910D01*
X336467Y265140D01*
X336880Y265217D01*
X337293Y265140D01*
X337603Y264948D01*
X337758Y264603D01*
Y263683D01*
G01X339050Y267550D02*
X335950D01*
X336570Y267090D01*
G01X339050D02*
Y268010D01*
G01Y270650D02*
X338998Y270918D01*
X338843Y271225D01*
X338585Y271417D01*
X338223Y271493D01*
X337862Y271417D01*
X337552Y271187D01*
X337397Y270842D01*
Y270458D01*
X337293Y270228D01*
X337035Y270037D01*
X336673Y269960D01*
X336312Y270075D01*
X336053Y270343D01*
X335950Y270650D01*
X336053Y270957D01*
X336312Y271225D01*
X336673Y271340D01*
X337035Y271263D01*
X337293Y271072D01*
X337397Y270842D01*
Y270458D01*
X337552Y270113D01*
X337862Y269883D01*
X338223Y269807D01*
X338585Y269883D01*
X338843Y270075D01*
X338998Y270382D01*
X339050Y270650D01*
G01X334930Y277633D02*
X335240Y277825D01*
X335447Y278055D01*
X335550Y278323D01*
X335447Y278630D01*
X335240Y278860D01*
X334930Y279090D01*
X334517Y279167D01*
X332450D01*
G01X335550Y281500D02*
X332450D01*
X333070Y281040D01*
G01X335550D02*
Y281960D01*
G01Y284523D02*
X334878Y284600D01*
X334310Y284715D01*
X333793Y284868D01*
X333225Y285060D01*
X332450Y285367D01*
Y283833D01*
G01X327000Y339500D02*
X327268Y339552D01*
X327575Y339707D01*
X327767Y339965D01*
X327843Y340327D01*
X327767Y340688D01*
X327537Y340998D01*
X327192Y341153D01*
X326808D01*
X326578Y341257D01*
X326387Y341515D01*
X326310Y341877D01*
X326425Y342238D01*
X326693Y342497D01*
X327000Y342600D01*
X327307Y342497D01*
X327575Y342238D01*
X327690Y341877D01*
X327613Y341515D01*
X327422Y341257D01*
X327192Y341153D01*
X326808D01*
X326463Y340998D01*
X326233Y340688D01*
X326157Y340327D01*
X326233Y339965D01*
X326425Y339707D01*
X326732Y339552D01*
X327000Y339500D01*
G01X332933Y345591D02*
Y342491D01*
G01X332051Y345591D02*
X333815D01*
G01X335266Y342491D02*
Y345591D01*
X336186D01*
X336493Y345436D01*
X336723Y345074D01*
X336800Y344661D01*
X336723Y344248D01*
X336531Y343938D01*
X336186Y343783D01*
X335266D01*
G01X338405Y345074D02*
X338635Y345384D01*
X338903Y345539D01*
X339210Y345591D01*
X339593Y345488D01*
X339861Y345229D01*
X339938Y344919D01*
X339900Y344609D01*
X339746Y344351D01*
X338980Y343834D01*
X338635Y343473D01*
X338405Y342956D01*
X338328Y342491D01*
X339938D01*
G01X342233D02*
Y345591D01*
X341773Y344971D01*
G01Y342491D02*
X342693D01*
G01X324208Y366243D02*
X324053Y366013D01*
X323950Y365745D01*
Y365438D01*
X324105Y365093D01*
X324363Y364825D01*
X324673Y364633D01*
X325190Y364480D01*
X325655Y364442D01*
X326120Y364518D01*
X326430Y364633D01*
X326740Y364863D01*
X326947Y365132D01*
X327050Y365400D01*
Y365668D01*
X326947Y365937D01*
X326792Y366167D01*
X326585Y366358D01*
G01X327050Y368500D02*
X323950D01*
X324570Y368040D01*
G01X327050D02*
Y368960D01*
G01Y371600D02*
X326998Y371868D01*
X326843Y372175D01*
X326585Y372367D01*
X326223Y372443D01*
X325862Y372367D01*
X325552Y372137D01*
X325397Y371792D01*
Y371408D01*
X325293Y371178D01*
X325035Y370987D01*
X324673Y370910D01*
X324312Y371025D01*
X324053Y371293D01*
X323950Y371600D01*
X324053Y371907D01*
X324312Y372175D01*
X324673Y372290D01*
X325035Y372213D01*
X325293Y372022D01*
X325397Y371792D01*
Y371408D01*
X325552Y371063D01*
X325862Y370833D01*
X326223Y370757D01*
X326585Y370833D01*
X326843Y371025D01*
X326998Y371332D01*
X327050Y371600D01*
G01X338708Y366243D02*
X338553Y366013D01*
X338450Y365745D01*
Y365438D01*
X338605Y365093D01*
X338863Y364825D01*
X339173Y364633D01*
X339690Y364480D01*
X340155Y364442D01*
X340620Y364518D01*
X340930Y364633D01*
X341240Y364863D01*
X341447Y365132D01*
X341550Y365400D01*
Y365668D01*
X341447Y365937D01*
X341292Y366167D01*
X341085Y366358D01*
G01X338967Y367772D02*
X338657Y368002D01*
X338502Y368270D01*
X338450Y368577D01*
X338553Y368960D01*
X338812Y369228D01*
X339122Y369305D01*
X339432Y369267D01*
X339690Y369113D01*
X340207Y368347D01*
X340568Y368002D01*
X341085Y367772D01*
X341550Y367695D01*
Y369305D01*
G01X338967Y370872D02*
X338657Y371102D01*
X338502Y371370D01*
X338450Y371677D01*
X338553Y372060D01*
X338812Y372328D01*
X339122Y372405D01*
X339432Y372367D01*
X339690Y372213D01*
X340207Y371447D01*
X340568Y371102D01*
X341085Y370872D01*
X341550Y370795D01*
Y372405D01*
G01X330708Y366243D02*
X330553Y366013D01*
X330450Y365745D01*
Y365438D01*
X330605Y365093D01*
X330863Y364825D01*
X331173Y364633D01*
X331690Y364480D01*
X332155Y364442D01*
X332620Y364518D01*
X332930Y364633D01*
X333240Y364863D01*
X333447Y365132D01*
X333550Y365400D01*
Y365668D01*
X333447Y365937D01*
X333292Y366167D01*
X333085Y366358D01*
G01X330967Y367772D02*
X330657Y368002D01*
X330502Y368270D01*
X330450Y368577D01*
X330553Y368960D01*
X330812Y369228D01*
X331122Y369305D01*
X331432Y369267D01*
X331690Y369113D01*
X332207Y368347D01*
X332568Y368002D01*
X333085Y367772D01*
X333550Y367695D01*
Y369305D01*
G01Y371600D02*
X330450D01*
X331070Y371140D01*
G01X333550D02*
Y372060D01*
G01X330543Y389992D02*
X330313Y390147D01*
X330045Y390250D01*
X329738D01*
X329393Y390095D01*
X329125Y389837D01*
X328933Y389527D01*
X328780Y389010D01*
X328742Y388545D01*
X328818Y388080D01*
X328933Y387770D01*
X329163Y387460D01*
X329432Y387253D01*
X329700Y387150D01*
X329968D01*
X330237Y387253D01*
X330467Y387408D01*
X330658Y387615D01*
G01X331957D02*
X332187Y387357D01*
X332455Y387202D01*
X332800Y387150D01*
X333145Y387253D01*
X333413Y387460D01*
X333605Y387822D01*
X333643Y388235D01*
X333567Y388648D01*
X333375Y388907D01*
X333107Y389113D01*
X332838Y389165D01*
X332570Y389113D01*
X332225Y388907D01*
X332340Y390250D01*
X333375D01*
G01X335172Y389733D02*
X335402Y390043D01*
X335670Y390198D01*
X335977Y390250D01*
X336360Y390147D01*
X336628Y389888D01*
X336705Y389578D01*
X336667Y389268D01*
X336513Y389010D01*
X335747Y388493D01*
X335402Y388132D01*
X335172Y387615D01*
X335095Y387150D01*
X336705D01*
G01X329543Y383992D02*
X329313Y384147D01*
X329045Y384250D01*
X328738D01*
X328393Y384095D01*
X328125Y383837D01*
X327933Y383527D01*
X327780Y383010D01*
X327742Y382545D01*
X327818Y382080D01*
X327933Y381770D01*
X328163Y381460D01*
X328432Y381253D01*
X328700Y381150D01*
X328968D01*
X329237Y381253D01*
X329467Y381408D01*
X329658Y381615D01*
G01X332260Y381150D02*
Y384250D01*
X330842Y382028D01*
X332758D01*
G01X334900Y381150D02*
X335168Y381202D01*
X335475Y381357D01*
X335667Y381615D01*
X335743Y381977D01*
X335667Y382338D01*
X335437Y382648D01*
X335092Y382803D01*
X334708D01*
X334478Y382907D01*
X334287Y383165D01*
X334210Y383527D01*
X334325Y383888D01*
X334593Y384147D01*
X334900Y384250D01*
X335207Y384147D01*
X335475Y383888D01*
X335590Y383527D01*
X335513Y383165D01*
X335322Y382907D01*
X335092Y382803D01*
X334708D01*
X334363Y382648D01*
X334133Y382338D01*
X334057Y381977D01*
X334133Y381615D01*
X334325Y381357D01*
X334632Y381202D01*
X334900Y381150D01*
G01X338450Y390500D02*
Y393600D01*
X337990Y392980D01*
G01Y390500D02*
X338910D01*
G01X340822Y393083D02*
X341052Y393393D01*
X341320Y393548D01*
X341627Y393600D01*
X342010Y393497D01*
X342278Y393238D01*
X342355Y392928D01*
X342317Y392618D01*
X342163Y392360D01*
X341397Y391843D01*
X341052Y391482D01*
X340822Y390965D01*
X340745Y390500D01*
X342355D01*
G01X328000D02*
X328268Y390552D01*
X328575Y390707D01*
X328767Y390965D01*
X328843Y391327D01*
X328767Y391688D01*
X328537Y391998D01*
X328192Y392153D01*
X327808D01*
X327578Y392257D01*
X327387Y392515D01*
X327310Y392877D01*
X327425Y393238D01*
X327693Y393497D01*
X328000Y393600D01*
X328307Y393497D01*
X328575Y393238D01*
X328690Y392877D01*
X328613Y392515D01*
X328422Y392257D01*
X328192Y392153D01*
X327808D01*
X327463Y391998D01*
X327233Y391688D01*
X327157Y391327D01*
X327233Y390965D01*
X327425Y390707D01*
X327732Y390552D01*
X328000Y390500D01*
G01X325923Y395500D02*
X326000Y396172D01*
X326115Y396740D01*
X326268Y397257D01*
X326460Y397825D01*
X326767Y398600D01*
X325233D01*
G01X325272Y405292D02*
X325540Y405653D01*
X325770Y405860D01*
X326077Y405963D01*
X326345Y405860D01*
X326537Y405653D01*
X326690Y405343D01*
X326728Y404982D01*
X326690Y404672D01*
X326537Y404362D01*
X326307Y404103D01*
X326038Y404000D01*
X325732Y404103D01*
X325463Y404413D01*
X325310Y404878D01*
X325272Y405395D01*
X325348Y406067D01*
X325463Y406428D01*
X325655Y406790D01*
X325923Y407048D01*
X326192Y407100D01*
X326460Y406997D01*
X326652Y406738D01*
G01X326157Y408465D02*
X326387Y408207D01*
X326655Y408052D01*
X327000Y408000D01*
X327345Y408103D01*
X327613Y408310D01*
X327805Y408672D01*
X327843Y409085D01*
X327767Y409498D01*
X327575Y409757D01*
X327307Y409963D01*
X327038Y410015D01*
X326770Y409963D01*
X326425Y409757D01*
X326540Y411100D01*
X327575D01*
G01X334242Y398807D02*
X336464D01*
X336929Y398960D01*
X337239Y399267D01*
X337342Y399650D01*
X337239Y400033D01*
X336929Y400340D01*
X336464Y400493D01*
X334242D01*
G01X336050Y402022D02*
X335689Y402290D01*
X335482Y402520D01*
X335379Y402827D01*
X335482Y403095D01*
X335689Y403287D01*
X335999Y403440D01*
X336360Y403478D01*
X336670Y403440D01*
X336980Y403287D01*
X337239Y403057D01*
X337342Y402788D01*
X337239Y402482D01*
X336929Y402213D01*
X336464Y402060D01*
X335947Y402022D01*
X335275Y402098D01*
X334914Y402213D01*
X334552Y402405D01*
X334294Y402673D01*
X334242Y402942D01*
X334345Y403210D01*
X334604Y403402D01*
G01X328543Y414992D02*
X328313Y415147D01*
X328045Y415250D01*
X327738D01*
X327393Y415095D01*
X327125Y414837D01*
X326933Y414527D01*
X326780Y414010D01*
X326742Y413545D01*
X326818Y413080D01*
X326933Y412770D01*
X327163Y412460D01*
X327432Y412253D01*
X327700Y412150D01*
X327968D01*
X328237Y412253D01*
X328467Y412408D01*
X328658Y412615D01*
G01X329957D02*
X330187Y412357D01*
X330455Y412202D01*
X330800Y412150D01*
X331145Y412253D01*
X331413Y412460D01*
X331605Y412822D01*
X331643Y413235D01*
X331567Y413648D01*
X331375Y413907D01*
X331107Y414113D01*
X330838Y414165D01*
X330570Y414113D01*
X330225Y413907D01*
X330340Y415250D01*
X331375D01*
G01X333057Y412770D02*
X333287Y412408D01*
X333593Y412202D01*
X333938Y412150D01*
X334245Y412202D01*
X334552Y412460D01*
X334743Y412770D01*
X334782Y413080D01*
X334705Y413442D01*
X334437Y413700D01*
X334168Y413803D01*
X333823D01*
G01X334168D02*
X334398Y413958D01*
X334590Y414217D01*
X334667Y414527D01*
X334590Y414837D01*
X334398Y415095D01*
X334053Y415250D01*
X333708Y415198D01*
X333363Y414992D01*
G01X326543Y421492D02*
X326313Y421647D01*
X326045Y421750D01*
X325738D01*
X325393Y421595D01*
X325125Y421337D01*
X324933Y421027D01*
X324780Y420510D01*
X324742Y420045D01*
X324818Y419580D01*
X324933Y419270D01*
X325163Y418960D01*
X325432Y418753D01*
X325700Y418650D01*
X325968D01*
X326237Y418753D01*
X326467Y418908D01*
X326658Y419115D01*
G01X327957D02*
X328187Y418857D01*
X328455Y418702D01*
X328800Y418650D01*
X329145Y418753D01*
X329413Y418960D01*
X329605Y419322D01*
X329643Y419735D01*
X329567Y420148D01*
X329375Y420407D01*
X329107Y420613D01*
X328838Y420665D01*
X328570Y420613D01*
X328225Y420407D01*
X328340Y421750D01*
X329375D01*
G01X331900D02*
X331593Y421647D01*
X331363Y421388D01*
X331210Y421078D01*
X331095Y420665D01*
X331057Y420200D01*
X331095Y419735D01*
X331210Y419322D01*
X331363Y419012D01*
X331593Y418753D01*
X331900Y418650D01*
X332207Y418753D01*
X332437Y419012D01*
X332590Y419322D01*
X332705Y419735D01*
X332743Y420200D01*
X332705Y420665D01*
X332590Y421078D01*
X332437Y421388D01*
X332207Y421647D01*
X331900Y421750D01*
G01X356208Y156193D02*
X356053Y155963D01*
X355950Y155695D01*
Y155388D01*
X356105Y155043D01*
X356363Y154775D01*
X356673Y154583D01*
X357190Y154430D01*
X357655Y154392D01*
X358120Y154468D01*
X358430Y154583D01*
X358740Y154813D01*
X358947Y155082D01*
X359050Y155350D01*
Y155618D01*
X358947Y155887D01*
X358792Y156117D01*
X358585Y156308D01*
G01X359050Y158450D02*
X355950D01*
X356570Y157990D01*
G01X359050D02*
Y158910D01*
G01Y162010D02*
X355950D01*
X358172Y160592D01*
Y162508D01*
G01X359050Y164650D02*
X358998Y164918D01*
X358843Y165225D01*
X358585Y165417D01*
X358223Y165493D01*
X357862Y165417D01*
X357552Y165187D01*
X357397Y164842D01*
Y164458D01*
X357293Y164228D01*
X357035Y164037D01*
X356673Y163960D01*
X356312Y164075D01*
X356053Y164343D01*
X355950Y164650D01*
X356053Y164957D01*
X356312Y165225D01*
X356673Y165340D01*
X357035Y165263D01*
X357293Y165072D01*
X357397Y164842D01*
Y164458D01*
X357552Y164113D01*
X357862Y163883D01*
X358223Y163807D01*
X358585Y163883D01*
X358843Y164075D01*
X358998Y164382D01*
X359050Y164650D01*
G01X350208Y157693D02*
X350053Y157463D01*
X349950Y157195D01*
Y156888D01*
X350105Y156543D01*
X350363Y156275D01*
X350673Y156083D01*
X351190Y155930D01*
X351655Y155892D01*
X352120Y155968D01*
X352430Y156083D01*
X352740Y156313D01*
X352947Y156582D01*
X353050Y156850D01*
Y157118D01*
X352947Y157387D01*
X352792Y157617D01*
X352585Y157808D01*
G01X353050Y159950D02*
X349950D01*
X350570Y159490D01*
G01X353050D02*
Y160410D01*
G01X352585Y162207D02*
X352843Y162437D01*
X352998Y162705D01*
X353050Y163050D01*
X352947Y163395D01*
X352740Y163663D01*
X352378Y163855D01*
X351965Y163893D01*
X351552Y163817D01*
X351293Y163625D01*
X351087Y163357D01*
X351035Y163088D01*
X351087Y162820D01*
X351293Y162475D01*
X349950Y162590D01*
Y163625D01*
G01X352585Y165307D02*
X352843Y165537D01*
X352998Y165805D01*
X353050Y166150D01*
X352947Y166495D01*
X352740Y166763D01*
X352378Y166955D01*
X351965Y166993D01*
X351552Y166917D01*
X351293Y166725D01*
X351087Y166457D01*
X351035Y166188D01*
X351087Y165920D01*
X351293Y165575D01*
X349950Y165690D01*
Y166725D01*
G01X356950Y171232D02*
X353850D01*
Y172191D01*
X354005Y172497D01*
X354212Y172689D01*
X354625Y172766D01*
X355038Y172689D01*
X355297Y172459D01*
X355452Y172191D01*
Y171232D01*
G01Y172191D02*
X356950Y172766D01*
G01X354367Y174371D02*
X354057Y174601D01*
X353902Y174869D01*
X353850Y175176D01*
X353953Y175559D01*
X354212Y175827D01*
X354522Y175904D01*
X354832Y175866D01*
X355090Y175712D01*
X355607Y174946D01*
X355968Y174601D01*
X356485Y174371D01*
X356950Y174294D01*
Y175904D01*
G01X355658Y177471D02*
X355297Y177739D01*
X355090Y177969D01*
X354987Y178276D01*
X355090Y178544D01*
X355297Y178736D01*
X355607Y178889D01*
X355968Y178927D01*
X356278Y178889D01*
X356588Y178736D01*
X356847Y178506D01*
X356950Y178237D01*
X356847Y177931D01*
X356537Y177662D01*
X356072Y177509D01*
X355555Y177471D01*
X354883Y177547D01*
X354522Y177662D01*
X354160Y177854D01*
X353902Y178122D01*
X353850Y178391D01*
X353953Y178659D01*
X354212Y178851D01*
G01X355658Y180571D02*
X355297Y180839D01*
X355090Y181069D01*
X354987Y181376D01*
X355090Y181644D01*
X355297Y181836D01*
X355607Y181989D01*
X355968Y182027D01*
X356278Y181989D01*
X356588Y181836D01*
X356847Y181606D01*
X356950Y181337D01*
X356847Y181031D01*
X356537Y180762D01*
X356072Y180609D01*
X355555Y180571D01*
X354883Y180647D01*
X354522Y180762D01*
X354160Y180954D01*
X353902Y181222D01*
X353850Y181491D01*
X353953Y181759D01*
X354212Y181951D01*
G01X351734Y197149D02*
X352002Y197201D01*
X352309Y197356D01*
X352501Y197614D01*
X352577Y197976D01*
X352501Y198337D01*
X352271Y198647D01*
X351926Y198802D01*
X351542D01*
X351312Y198906D01*
X351121Y199164D01*
X351044Y199526D01*
X351159Y199887D01*
X351427Y200146D01*
X351734Y200249D01*
X352041Y200146D01*
X352309Y199887D01*
X352424Y199526D01*
X352347Y199164D01*
X352156Y198906D01*
X351926Y198802D01*
X351542D01*
X351197Y198647D01*
X350967Y198337D01*
X350891Y197976D01*
X350967Y197614D01*
X351159Y197356D01*
X351466Y197201D01*
X351734Y197149D01*
G01X355570Y197236D02*
X355647Y197908D01*
X355762Y198476D01*
X355915Y198993D01*
X356107Y199561D01*
X356414Y200336D01*
X354880D01*
G01X344950Y187500D02*
Y190600D01*
X344490Y189980D01*
G01Y187500D02*
X345410D01*
G01X347322Y190083D02*
X347552Y190393D01*
X347820Y190548D01*
X348127Y190600D01*
X348510Y190497D01*
X348778Y190238D01*
X348855Y189928D01*
X348817Y189618D01*
X348663Y189360D01*
X347897Y188843D01*
X347552Y188482D01*
X347322Y187965D01*
X347245Y187500D01*
X348855D01*
G01X346848Y193362D02*
X347117Y193103D01*
X347423Y193000D01*
X347730Y193103D01*
X347998Y193413D01*
X348190Y193878D01*
X348267Y194343D01*
Y194912D01*
X348190Y195377D01*
X347998Y195790D01*
X347768Y195997D01*
X347500Y196100D01*
X347193Y195997D01*
X346963Y195790D01*
X346810Y195480D01*
X346733Y195067D01*
X346810Y194705D01*
X347002Y194343D01*
X347232Y194137D01*
X347500Y194085D01*
X347807Y194188D01*
X348037Y194447D01*
X348267Y194912D01*
G01X357272Y186583D02*
X357502Y186893D01*
X357770Y187048D01*
X358077Y187100D01*
X358460Y186997D01*
X358728Y186738D01*
X358805Y186428D01*
X358767Y186118D01*
X358613Y185860D01*
X357847Y185343D01*
X357502Y184982D01*
X357272Y184465D01*
X357195Y184000D01*
X358805D01*
G01X352851Y187606D02*
X355073D01*
X355538Y187759D01*
X355848Y188066D01*
X355951Y188449D01*
X355848Y188832D01*
X355538Y189139D01*
X355073Y189292D01*
X352851D01*
G01X355951Y191549D02*
X352851D01*
X353471Y191089D01*
G01X355951D02*
Y192009D01*
G01Y194649D02*
X352851D01*
X353471Y194189D01*
G01X355951D02*
Y195109D01*
G01X342815Y216946D02*
Y220046D01*
X342355Y219426D01*
G01Y216946D02*
X343275D01*
G01X345263Y217308D02*
X345532Y217049D01*
X345838Y216946D01*
X346145Y217049D01*
X346413Y217359D01*
X346605Y217824D01*
X346682Y218289D01*
Y218858D01*
X346605Y219323D01*
X346413Y219736D01*
X346183Y219943D01*
X345915Y220046D01*
X345608Y219943D01*
X345378Y219736D01*
X345225Y219426D01*
X345148Y219013D01*
X345225Y218651D01*
X345417Y218289D01*
X345647Y218083D01*
X345915Y218031D01*
X346222Y218134D01*
X346452Y218393D01*
X346682Y218858D01*
G01X358550Y234350D02*
X357155D01*
X355450Y233583D01*
G01Y235117D02*
X357155Y234350D01*
G01X358550Y237450D02*
X355450D01*
X356070Y236990D01*
G01X358550D02*
Y237910D01*
G01X348924Y225125D02*
X349154Y225435D01*
X349422Y225590D01*
X349729Y225642D01*
X350112Y225539D01*
X350380Y225280D01*
X350457Y224970D01*
X350419Y224660D01*
X350265Y224402D01*
X349499Y223885D01*
X349154Y223524D01*
X348924Y223007D01*
X348847Y222542D01*
X350457D01*
G01X352752Y225642D02*
X352445Y225539D01*
X352215Y225280D01*
X352062Y224970D01*
X351947Y224557D01*
X351909Y224092D01*
X351947Y223627D01*
X352062Y223214D01*
X352215Y222904D01*
X352445Y222645D01*
X352752Y222542D01*
X353059Y222645D01*
X353289Y222904D01*
X353442Y223214D01*
X353557Y223627D01*
X353595Y224092D01*
X353557Y224557D01*
X353442Y224970D01*
X353289Y225280D01*
X353059Y225539D01*
X352752Y225642D01*
G01X353308Y249593D02*
X353153Y249363D01*
X353050Y249095D01*
Y248788D01*
X353205Y248443D01*
X353463Y248175D01*
X353773Y247983D01*
X354290Y247830D01*
X354755Y247792D01*
X355220Y247868D01*
X355530Y247983D01*
X355840Y248213D01*
X356047Y248482D01*
X356150Y248750D01*
Y249018D01*
X356047Y249287D01*
X355892Y249517D01*
X355685Y249708D01*
G01X353567Y251122D02*
X353257Y251352D01*
X353102Y251620D01*
X353050Y251927D01*
X353153Y252310D01*
X353412Y252578D01*
X353722Y252655D01*
X354032Y252617D01*
X354290Y252463D01*
X354807Y251697D01*
X355168Y251352D01*
X355685Y251122D01*
X356150Y251045D01*
Y252655D01*
G01Y254873D02*
X355478Y254950D01*
X354910Y255065D01*
X354393Y255218D01*
X353825Y255410D01*
X353050Y255717D01*
Y254183D01*
G01X355788Y257398D02*
X356047Y257667D01*
X356150Y257973D01*
X356047Y258280D01*
X355737Y258548D01*
X355272Y258740D01*
X354807Y258817D01*
X354238D01*
X353773Y258740D01*
X353360Y258548D01*
X353153Y258318D01*
X353050Y258050D01*
X353153Y257743D01*
X353360Y257513D01*
X353670Y257360D01*
X354083Y257283D01*
X354445Y257360D01*
X354807Y257552D01*
X355013Y257782D01*
X355065Y258050D01*
X354962Y258357D01*
X354703Y258587D01*
X354238Y258817D01*
G01X342208Y249393D02*
X342053Y249163D01*
X341950Y248895D01*
Y248588D01*
X342105Y248243D01*
X342363Y247975D01*
X342673Y247783D01*
X343190Y247630D01*
X343655Y247592D01*
X344120Y247668D01*
X344430Y247783D01*
X344740Y248013D01*
X344947Y248282D01*
X345050Y248550D01*
Y248818D01*
X344947Y249087D01*
X344792Y249317D01*
X344585Y249508D01*
G01X342467Y250922D02*
X342157Y251152D01*
X342002Y251420D01*
X341950Y251727D01*
X342053Y252110D01*
X342312Y252378D01*
X342622Y252455D01*
X342932Y252417D01*
X343190Y252263D01*
X343707Y251497D01*
X344068Y251152D01*
X344585Y250922D01*
X345050Y250845D01*
Y252455D01*
G01Y254750D02*
X344998Y255018D01*
X344843Y255325D01*
X344585Y255517D01*
X344223Y255593D01*
X343862Y255517D01*
X343552Y255287D01*
X343397Y254942D01*
Y254558D01*
X343293Y254328D01*
X343035Y254137D01*
X342673Y254060D01*
X342312Y254175D01*
X342053Y254443D01*
X341950Y254750D01*
X342053Y255057D01*
X342312Y255325D01*
X342673Y255440D01*
X343035Y255363D01*
X343293Y255172D01*
X343397Y254942D01*
Y254558D01*
X343552Y254213D01*
X343862Y253983D01*
X344223Y253907D01*
X344585Y253983D01*
X344843Y254175D01*
X344998Y254482D01*
X345050Y254750D01*
G01Y257850D02*
X341950D01*
X342570Y257390D01*
G01X345050D02*
Y258310D01*
G01X348764Y239157D02*
X348994Y239467D01*
X349262Y239622D01*
X349569Y239674D01*
X349952Y239571D01*
X350220Y239312D01*
X350297Y239002D01*
X350259Y238692D01*
X350105Y238434D01*
X349339Y237917D01*
X348994Y237556D01*
X348764Y237039D01*
X348687Y236574D01*
X350297D01*
G01X352592D02*
X352860Y236626D01*
X353167Y236781D01*
X353359Y237039D01*
X353435Y237401D01*
X353359Y237762D01*
X353129Y238072D01*
X352784Y238227D01*
X352400D01*
X352170Y238331D01*
X351979Y238589D01*
X351902Y238951D01*
X352017Y239312D01*
X352285Y239571D01*
X352592Y239674D01*
X352899Y239571D01*
X353167Y239312D01*
X353282Y238951D01*
X353205Y238589D01*
X353014Y238331D01*
X352784Y238227D01*
X352400D01*
X352055Y238072D01*
X351825Y237762D01*
X351749Y237401D01*
X351825Y237039D01*
X352017Y236781D01*
X352324Y236626D01*
X352592Y236574D01*
G01X347034Y249733D02*
X350134D01*
Y251267D01*
G01Y253600D02*
X347034D01*
X347654Y253140D01*
G01X350134D02*
Y254060D01*
G01X349772Y256048D02*
X350031Y256317D01*
X350134Y256623D01*
X350031Y256930D01*
X349721Y257198D01*
X349256Y257390D01*
X348791Y257467D01*
X348222D01*
X347757Y257390D01*
X347344Y257198D01*
X347137Y256968D01*
X347034Y256700D01*
X347137Y256393D01*
X347344Y256163D01*
X347654Y256010D01*
X348067Y255933D01*
X348429Y256010D01*
X348791Y256202D01*
X348997Y256432D01*
X349049Y256700D01*
X348946Y257007D01*
X348687Y257237D01*
X348222Y257467D01*
G01X356450Y259850D02*
X359550D01*
G01X356450Y258968D02*
Y260732D01*
G01X359550Y262183D02*
X356450D01*
Y263103D01*
X356605Y263410D01*
X356967Y263640D01*
X357380Y263717D01*
X357793Y263640D01*
X358103Y263448D01*
X358258Y263103D01*
Y262183D01*
G01X359085Y265207D02*
X359343Y265437D01*
X359498Y265705D01*
X359550Y266050D01*
X359447Y266395D01*
X359240Y266663D01*
X358878Y266855D01*
X358465Y266893D01*
X358052Y266817D01*
X357793Y266625D01*
X357587Y266357D01*
X357535Y266088D01*
X357587Y265820D01*
X357793Y265475D01*
X356450Y265590D01*
Y266625D01*
G01X359550Y269150D02*
X359498Y269418D01*
X359343Y269725D01*
X359085Y269917D01*
X358723Y269993D01*
X358362Y269917D01*
X358052Y269687D01*
X357897Y269342D01*
Y268958D01*
X357793Y268728D01*
X357535Y268537D01*
X357173Y268460D01*
X356812Y268575D01*
X356553Y268843D01*
X356450Y269150D01*
X356553Y269457D01*
X356812Y269725D01*
X357173Y269840D01*
X357535Y269763D01*
X357793Y269572D01*
X357897Y269342D01*
Y268958D01*
X358052Y268613D01*
X358362Y268383D01*
X358723Y268307D01*
X359085Y268383D01*
X359343Y268575D01*
X359498Y268882D01*
X359550Y269150D01*
G01X342950Y260850D02*
X346050D01*
G01X342950Y259968D02*
Y261732D01*
G01X346050Y263183D02*
X342950D01*
Y264103D01*
X343105Y264410D01*
X343467Y264640D01*
X343880Y264717D01*
X344293Y264640D01*
X344603Y264448D01*
X344758Y264103D01*
Y263183D01*
G01X346050Y267050D02*
X342950D01*
X343570Y266590D01*
G01X346050D02*
Y267510D01*
G01X345688Y269498D02*
X345947Y269767D01*
X346050Y270073D01*
X345947Y270380D01*
X345637Y270648D01*
X345172Y270840D01*
X344707Y270917D01*
X344138D01*
X343673Y270840D01*
X343260Y270648D01*
X343053Y270418D01*
X342950Y270150D01*
X343053Y269843D01*
X343260Y269613D01*
X343570Y269460D01*
X343983Y269383D01*
X344345Y269460D01*
X344707Y269652D01*
X344913Y269882D01*
X344965Y270150D01*
X344862Y270457D01*
X344603Y270687D01*
X344138Y270917D01*
G01X357158Y286693D02*
X357003Y286463D01*
X356900Y286195D01*
Y285888D01*
X357055Y285543D01*
X357313Y285275D01*
X357623Y285083D01*
X358140Y284930D01*
X358605Y284892D01*
X359070Y284968D01*
X359380Y285083D01*
X359690Y285313D01*
X359897Y285582D01*
X360000Y285850D01*
Y286118D01*
X359897Y286387D01*
X359742Y286617D01*
X359535Y286808D01*
G01X360000Y288950D02*
X356900D01*
X357520Y288490D01*
G01X360000D02*
Y289410D01*
G01X359638Y291398D02*
X359897Y291667D01*
X360000Y291973D01*
X359897Y292280D01*
X359587Y292548D01*
X359122Y292740D01*
X358657Y292817D01*
X358088D01*
X357623Y292740D01*
X357210Y292548D01*
X357003Y292318D01*
X356900Y292050D01*
X357003Y291743D01*
X357210Y291513D01*
X357520Y291360D01*
X357933Y291283D01*
X358295Y291360D01*
X358657Y291552D01*
X358863Y291782D01*
X358915Y292050D01*
X358812Y292357D01*
X358553Y292587D01*
X358088Y292817D01*
G01X359638Y294498D02*
X359897Y294767D01*
X360000Y295073D01*
X359897Y295380D01*
X359587Y295648D01*
X359122Y295840D01*
X358657Y295917D01*
X358088D01*
X357623Y295840D01*
X357210Y295648D01*
X357003Y295418D01*
X356900Y295150D01*
X357003Y294843D01*
X357210Y294613D01*
X357520Y294460D01*
X357933Y294383D01*
X358295Y294460D01*
X358657Y294652D01*
X358863Y294882D01*
X358915Y295150D01*
X358812Y295457D01*
X358553Y295687D01*
X358088Y295917D01*
G01X356908Y274393D02*
X356753Y274163D01*
X356650Y273895D01*
Y273588D01*
X356805Y273243D01*
X357063Y272975D01*
X357373Y272783D01*
X357890Y272630D01*
X358355Y272592D01*
X358820Y272668D01*
X359130Y272783D01*
X359440Y273013D01*
X359647Y273282D01*
X359750Y273550D01*
Y273818D01*
X359647Y274087D01*
X359492Y274317D01*
X359285Y274508D01*
G01X359750Y276650D02*
X356650D01*
X357270Y276190D01*
G01X359750D02*
Y277110D01*
G01X359388Y279098D02*
X359647Y279367D01*
X359750Y279673D01*
X359647Y279980D01*
X359337Y280248D01*
X358872Y280440D01*
X358407Y280517D01*
X357838D01*
X357373Y280440D01*
X356960Y280248D01*
X356753Y280018D01*
X356650Y279750D01*
X356753Y279443D01*
X356960Y279213D01*
X357270Y279060D01*
X357683Y278983D01*
X358045Y279060D01*
X358407Y279252D01*
X358613Y279482D01*
X358665Y279750D01*
X358562Y280057D01*
X358303Y280287D01*
X357838Y280517D01*
G01X359750Y282850D02*
X359698Y283118D01*
X359543Y283425D01*
X359285Y283617D01*
X358923Y283693D01*
X358562Y283617D01*
X358252Y283387D01*
X358097Y283042D01*
Y282658D01*
X357993Y282428D01*
X357735Y282237D01*
X357373Y282160D01*
X357012Y282275D01*
X356753Y282543D01*
X356650Y282850D01*
X356753Y283157D01*
X357012Y283425D01*
X357373Y283540D01*
X357735Y283463D01*
X357993Y283272D01*
X358097Y283042D01*
Y282658D01*
X358252Y282313D01*
X358562Y282083D01*
X358923Y282007D01*
X359285Y282083D01*
X359543Y282275D01*
X359698Y282582D01*
X359750Y282850D01*
G01X345880Y285690D02*
X346110Y285328D01*
X346416Y285122D01*
X346761Y285070D01*
X347068Y285122D01*
X347375Y285380D01*
X347566Y285690D01*
X347605Y286000D01*
X347528Y286362D01*
X347260Y286620D01*
X346991Y286723D01*
X346646D01*
G01X346991D02*
X347221Y286878D01*
X347413Y287137D01*
X347490Y287447D01*
X347413Y287757D01*
X347221Y288015D01*
X346876Y288170D01*
X346531Y288118D01*
X346186Y287912D01*
G01X346723Y274670D02*
Y277770D01*
X346263Y277150D01*
G01Y274670D02*
X347183D01*
G01X348000Y320500D02*
X348268Y320552D01*
X348575Y320707D01*
X348767Y320965D01*
X348843Y321327D01*
X348767Y321688D01*
X348537Y321998D01*
X348192Y322153D01*
X347808D01*
X347578Y322257D01*
X347387Y322515D01*
X347310Y322877D01*
X347425Y323238D01*
X347693Y323497D01*
X348000Y323600D01*
X348307Y323497D01*
X348575Y323238D01*
X348690Y322877D01*
X348613Y322515D01*
X348422Y322257D01*
X348192Y322153D01*
X347808D01*
X347463Y321998D01*
X347233Y321688D01*
X347157Y321327D01*
X347233Y320965D01*
X347425Y320707D01*
X347732Y320552D01*
X348000Y320500D01*
G01X347157Y335965D02*
X347387Y335707D01*
X347655Y335552D01*
X348000Y335500D01*
X348345Y335603D01*
X348613Y335810D01*
X348805Y336172D01*
X348843Y336585D01*
X348767Y336998D01*
X348575Y337257D01*
X348307Y337463D01*
X348038Y337515D01*
X347770Y337463D01*
X347425Y337257D01*
X347540Y338600D01*
X348575D01*
G01X358557Y332550D02*
Y330328D01*
X358710Y329863D01*
X359017Y329553D01*
X359400Y329450D01*
X359783Y329553D01*
X360090Y329863D01*
X360243Y330328D01*
Y332550D01*
G01X361772Y332033D02*
X362002Y332343D01*
X362270Y332498D01*
X362577Y332550D01*
X362960Y332447D01*
X363228Y332188D01*
X363305Y331878D01*
X363267Y331568D01*
X363113Y331310D01*
X362347Y330793D01*
X362002Y330432D01*
X361772Y329915D01*
X361695Y329450D01*
X363305D01*
G01X364757Y330070D02*
X364987Y329708D01*
X365293Y329502D01*
X365638Y329450D01*
X365945Y329502D01*
X366252Y329760D01*
X366443Y330070D01*
X366482Y330380D01*
X366405Y330742D01*
X366137Y331000D01*
X365868Y331103D01*
X365523D01*
G01X365868D02*
X366098Y331258D01*
X366290Y331517D01*
X366367Y331827D01*
X366290Y332137D01*
X366098Y332395D01*
X365753Y332550D01*
X365408Y332498D01*
X365063Y332292D01*
G01X346708Y366243D02*
X346553Y366013D01*
X346450Y365745D01*
Y365438D01*
X346605Y365093D01*
X346863Y364825D01*
X347173Y364633D01*
X347690Y364480D01*
X348155Y364442D01*
X348620Y364518D01*
X348930Y364633D01*
X349240Y364863D01*
X349447Y365132D01*
X349550Y365400D01*
Y365668D01*
X349447Y365937D01*
X349292Y366167D01*
X349085Y366358D01*
G01X346967Y367772D02*
X346657Y368002D01*
X346502Y368270D01*
X346450Y368577D01*
X346553Y368960D01*
X346812Y369228D01*
X347122Y369305D01*
X347432Y369267D01*
X347690Y369113D01*
X348207Y368347D01*
X348568Y368002D01*
X349085Y367772D01*
X349550Y367695D01*
Y369305D01*
G01X346450Y371600D02*
X346553Y371293D01*
X346812Y371063D01*
X347122Y370910D01*
X347535Y370795D01*
X348000Y370757D01*
X348465Y370795D01*
X348878Y370910D01*
X349188Y371063D01*
X349447Y371293D01*
X349550Y371600D01*
X349447Y371907D01*
X349188Y372137D01*
X348878Y372290D01*
X348465Y372405D01*
X348000Y372443D01*
X347535Y372405D01*
X347122Y372290D01*
X346812Y372137D01*
X346553Y371907D01*
X346450Y371600D01*
G01X351543Y390492D02*
X351313Y390647D01*
X351045Y390750D01*
X350738D01*
X350393Y390595D01*
X350125Y390337D01*
X349933Y390027D01*
X349780Y389510D01*
X349742Y389045D01*
X349818Y388580D01*
X349933Y388270D01*
X350163Y387960D01*
X350432Y387753D01*
X350700Y387650D01*
X350968D01*
X351237Y387753D01*
X351467Y387908D01*
X351658Y388115D01*
G01X353800Y387650D02*
Y390750D01*
X353340Y390130D01*
G01Y387650D02*
X354260D01*
G01X356172Y388942D02*
X356440Y389303D01*
X356670Y389510D01*
X356977Y389613D01*
X357245Y389510D01*
X357437Y389303D01*
X357590Y388993D01*
X357628Y388632D01*
X357590Y388322D01*
X357437Y388012D01*
X357207Y387753D01*
X356938Y387650D01*
X356632Y387753D01*
X356363Y388063D01*
X356210Y388528D01*
X356172Y389045D01*
X356248Y389717D01*
X356363Y390078D01*
X356555Y390440D01*
X356823Y390698D01*
X357092Y390750D01*
X357360Y390647D01*
X357552Y390388D01*
G01X350433Y381750D02*
Y384850D01*
X351392D01*
X351698Y384695D01*
X351890Y384488D01*
X351967Y384075D01*
X351890Y383662D01*
X351660Y383403D01*
X351392Y383248D01*
X350433D01*
G01X351392D02*
X351967Y381750D01*
G01X354760D02*
Y384850D01*
X353342Y382628D01*
X355258D01*
G01X357400Y384850D02*
X357093Y384747D01*
X356863Y384488D01*
X356710Y384178D01*
X356595Y383765D01*
X356557Y383300D01*
X356595Y382835D01*
X356710Y382422D01*
X356863Y382112D01*
X357093Y381853D01*
X357400Y381750D01*
X357707Y381853D01*
X357937Y382112D01*
X358090Y382422D01*
X358205Y382835D01*
X358243Y383300D01*
X358205Y383765D01*
X358090Y384178D01*
X357937Y384488D01*
X357707Y384747D01*
X357400Y384850D01*
G01X347633Y376450D02*
Y379550D01*
X348592D01*
X348898Y379395D01*
X349090Y379188D01*
X349167Y378775D01*
X349090Y378362D01*
X348860Y378103D01*
X348592Y377948D01*
X347633D01*
G01X348592D02*
X349167Y376450D01*
G01X350657Y377070D02*
X350887Y376708D01*
X351193Y376502D01*
X351538Y376450D01*
X351845Y376502D01*
X352152Y376760D01*
X352343Y377070D01*
X352382Y377380D01*
X352305Y377742D01*
X352037Y378000D01*
X351768Y378103D01*
X351423D01*
G01X351768D02*
X351998Y378258D01*
X352190Y378517D01*
X352267Y378827D01*
X352190Y379137D01*
X351998Y379395D01*
X351653Y379550D01*
X351308Y379498D01*
X350963Y379292D01*
G01X354600Y376450D02*
X354868Y376502D01*
X355175Y376657D01*
X355367Y376915D01*
X355443Y377277D01*
X355367Y377638D01*
X355137Y377948D01*
X354792Y378103D01*
X354408D01*
X354178Y378207D01*
X353987Y378465D01*
X353910Y378827D01*
X354025Y379188D01*
X354293Y379447D01*
X354600Y379550D01*
X354907Y379447D01*
X355175Y379188D01*
X355290Y378827D01*
X355213Y378465D01*
X355022Y378207D01*
X354792Y378103D01*
X354408D01*
X354063Y377948D01*
X353833Y377638D01*
X353757Y377277D01*
X353833Y376915D01*
X354025Y376657D01*
X354332Y376502D01*
X354600Y376450D01*
G01X345850Y379833D02*
X342750D01*
Y380792D01*
X342905Y381098D01*
X343112Y381290D01*
X343525Y381367D01*
X343938Y381290D01*
X344197Y381060D01*
X344352Y380792D01*
Y379833D01*
G01Y380792D02*
X345850Y381367D01*
G01X345230Y382857D02*
X345592Y383087D01*
X345798Y383393D01*
X345850Y383738D01*
X345798Y384045D01*
X345540Y384352D01*
X345230Y384543D01*
X344920Y384582D01*
X344558Y384505D01*
X344300Y384237D01*
X344197Y383968D01*
Y383623D01*
G01Y383968D02*
X344042Y384198D01*
X343783Y384390D01*
X343473Y384467D01*
X343163Y384390D01*
X342905Y384198D01*
X342750Y383853D01*
X342802Y383508D01*
X343008Y383163D01*
G01X345385Y385957D02*
X345643Y386187D01*
X345798Y386455D01*
X345850Y386800D01*
X345747Y387145D01*
X345540Y387413D01*
X345178Y387605D01*
X344765Y387643D01*
X344352Y387567D01*
X344093Y387375D01*
X343887Y387107D01*
X343835Y386838D01*
X343887Y386570D01*
X344093Y386225D01*
X342750Y386340D01*
Y387375D01*
G01X352043Y404492D02*
X351813Y404647D01*
X351545Y404750D01*
X351238D01*
X350893Y404595D01*
X350625Y404337D01*
X350433Y404027D01*
X350280Y403510D01*
X350242Y403045D01*
X350318Y402580D01*
X350433Y402270D01*
X350663Y401960D01*
X350932Y401753D01*
X351200Y401650D01*
X351468D01*
X351737Y401753D01*
X351967Y401908D01*
X352158Y402115D01*
G01X354760Y401650D02*
Y404750D01*
X353342Y402528D01*
X355258D01*
G01X356672Y402942D02*
X356940Y403303D01*
X357170Y403510D01*
X357477Y403613D01*
X357745Y403510D01*
X357937Y403303D01*
X358090Y402993D01*
X358128Y402632D01*
X358090Y402322D01*
X357937Y402012D01*
X357707Y401753D01*
X357438Y401650D01*
X357132Y401753D01*
X356863Y402063D01*
X356710Y402528D01*
X356672Y403045D01*
X356748Y403717D01*
X356863Y404078D01*
X357055Y404440D01*
X357323Y404698D01*
X357592Y404750D01*
X357860Y404647D01*
X358052Y404388D01*
G01X352043Y399992D02*
X351813Y400147D01*
X351545Y400250D01*
X351238D01*
X350893Y400095D01*
X350625Y399837D01*
X350433Y399527D01*
X350280Y399010D01*
X350242Y398545D01*
X350318Y398080D01*
X350433Y397770D01*
X350663Y397460D01*
X350932Y397253D01*
X351200Y397150D01*
X351468D01*
X351737Y397253D01*
X351967Y397408D01*
X352158Y397615D01*
G01X354760Y397150D02*
Y400250D01*
X353342Y398028D01*
X355258D01*
G01X356748Y397512D02*
X357017Y397253D01*
X357323Y397150D01*
X357630Y397253D01*
X357898Y397563D01*
X358090Y398028D01*
X358167Y398493D01*
Y399062D01*
X358090Y399527D01*
X357898Y399940D01*
X357668Y400147D01*
X357400Y400250D01*
X357093Y400147D01*
X356863Y399940D01*
X356710Y399630D01*
X356633Y399217D01*
X356710Y398855D01*
X356902Y398493D01*
X357132Y398287D01*
X357400Y398235D01*
X357707Y398338D01*
X357937Y398597D01*
X358167Y399062D01*
G01X351543Y395992D02*
X351313Y396147D01*
X351045Y396250D01*
X350738D01*
X350393Y396095D01*
X350125Y395837D01*
X349933Y395527D01*
X349780Y395010D01*
X349742Y394545D01*
X349818Y394080D01*
X349933Y393770D01*
X350163Y393460D01*
X350432Y393253D01*
X350700Y393150D01*
X350968D01*
X351237Y393253D01*
X351467Y393408D01*
X351658Y393615D01*
G01X352957D02*
X353187Y393357D01*
X353455Y393202D01*
X353800Y393150D01*
X354145Y393253D01*
X354413Y393460D01*
X354605Y393822D01*
X354643Y394235D01*
X354567Y394648D01*
X354375Y394907D01*
X354107Y395113D01*
X353838Y395165D01*
X353570Y395113D01*
X353225Y394907D01*
X353340Y396250D01*
X354375D01*
G01X356057Y393615D02*
X356287Y393357D01*
X356555Y393202D01*
X356900Y393150D01*
X357245Y393253D01*
X357513Y393460D01*
X357705Y393822D01*
X357743Y394235D01*
X357667Y394648D01*
X357475Y394907D01*
X357207Y395113D01*
X356938Y395165D01*
X356670Y395113D01*
X356325Y394907D01*
X356440Y396250D01*
X357475D01*
G01X350433Y406150D02*
Y409250D01*
X351392D01*
X351698Y409095D01*
X351890Y408888D01*
X351967Y408475D01*
X351890Y408062D01*
X351660Y407803D01*
X351392Y407648D01*
X350433D01*
G01X351392D02*
X351967Y406150D01*
G01X353457Y406615D02*
X353687Y406357D01*
X353955Y406202D01*
X354300Y406150D01*
X354645Y406253D01*
X354913Y406460D01*
X355105Y406822D01*
X355143Y407235D01*
X355067Y407648D01*
X354875Y407907D01*
X354607Y408113D01*
X354338Y408165D01*
X354070Y408113D01*
X353725Y407907D01*
X353840Y409250D01*
X354875D01*
G01X356672Y408733D02*
X356902Y409043D01*
X357170Y409198D01*
X357477Y409250D01*
X357860Y409147D01*
X358128Y408888D01*
X358205Y408578D01*
X358167Y408268D01*
X358013Y408010D01*
X357247Y407493D01*
X356902Y407132D01*
X356672Y406615D01*
X356595Y406150D01*
X358205D01*
G01X344055Y406121D02*
Y409221D01*
X343595Y408601D01*
G01Y406121D02*
X344515D01*
G01X347155D02*
X347423Y406173D01*
X347730Y406328D01*
X347922Y406586D01*
X347998Y406948D01*
X347922Y407309D01*
X347692Y407619D01*
X347347Y407774D01*
X346963D01*
X346733Y407878D01*
X346542Y408136D01*
X346465Y408498D01*
X346580Y408859D01*
X346848Y409118D01*
X347155Y409221D01*
X347462Y409118D01*
X347730Y408859D01*
X347845Y408498D01*
X347768Y408136D01*
X347577Y407878D01*
X347347Y407774D01*
X346963D01*
X346618Y407619D01*
X346388Y407309D01*
X346312Y406948D01*
X346388Y406586D01*
X346580Y406328D01*
X346887Y406173D01*
X347155Y406121D01*
G01X344055Y394463D02*
Y397563D01*
X343595Y396943D01*
G01Y394463D02*
X344515D01*
G01X346312Y395083D02*
X346542Y394721D01*
X346848Y394515D01*
X347193Y394463D01*
X347500Y394515D01*
X347807Y394773D01*
X347998Y395083D01*
X348037Y395393D01*
X347960Y395755D01*
X347692Y396013D01*
X347423Y396116D01*
X347078D01*
G01X347423D02*
X347653Y396271D01*
X347845Y396530D01*
X347922Y396840D01*
X347845Y397150D01*
X347653Y397408D01*
X347308Y397563D01*
X346963Y397511D01*
X346618Y397305D01*
G01X355043Y420992D02*
X354813Y421147D01*
X354545Y421250D01*
X354238D01*
X353893Y421095D01*
X353625Y420837D01*
X353433Y420527D01*
X353280Y420010D01*
X353242Y419545D01*
X353318Y419080D01*
X353433Y418770D01*
X353663Y418460D01*
X353932Y418253D01*
X354200Y418150D01*
X354468D01*
X354737Y418253D01*
X354967Y418408D01*
X355158Y418615D01*
G01X357223Y418150D02*
X357300Y418822D01*
X357415Y419390D01*
X357568Y419907D01*
X357760Y420475D01*
X358067Y421250D01*
X356533D01*
G01X359672Y419442D02*
X359940Y419803D01*
X360170Y420010D01*
X360477Y420113D01*
X360745Y420010D01*
X360937Y419803D01*
X361090Y419493D01*
X361128Y419132D01*
X361090Y418822D01*
X360937Y418512D01*
X360707Y418253D01*
X360438Y418150D01*
X360132Y418253D01*
X359863Y418563D01*
X359710Y419028D01*
X359672Y419545D01*
X359748Y420217D01*
X359863Y420578D01*
X360055Y420940D01*
X360323Y421198D01*
X360592Y421250D01*
X360860Y421147D01*
X361052Y420888D01*
G01X351443Y413392D02*
X351213Y413547D01*
X350945Y413650D01*
X350638D01*
X350293Y413495D01*
X350025Y413237D01*
X349833Y412927D01*
X349680Y412410D01*
X349642Y411945D01*
X349718Y411480D01*
X349833Y411170D01*
X350063Y410860D01*
X350332Y410653D01*
X350600Y410550D01*
X350868D01*
X351137Y410653D01*
X351367Y410808D01*
X351558Y411015D01*
G01X353623Y410550D02*
X353700Y411222D01*
X353815Y411790D01*
X353968Y412307D01*
X354160Y412875D01*
X354467Y413650D01*
X352933D01*
G01X356723Y410550D02*
X356800Y411222D01*
X356915Y411790D01*
X357068Y412307D01*
X357260Y412875D01*
X357567Y413650D01*
X356033D01*
G01X342814Y422701D02*
Y419601D01*
X344348D01*
G01X346681D02*
X346949Y419653D01*
X347256Y419808D01*
X347448Y420066D01*
X347524Y420428D01*
X347448Y420789D01*
X347218Y421099D01*
X346873Y421254D01*
X346489D01*
X346259Y421358D01*
X346068Y421616D01*
X345991Y421978D01*
X346106Y422339D01*
X346374Y422598D01*
X346681Y422701D01*
X346988Y422598D01*
X347256Y422339D01*
X347371Y421978D01*
X347294Y421616D01*
X347103Y421358D01*
X346873Y421254D01*
X346489D01*
X346144Y421099D01*
X345914Y420789D01*
X345838Y420428D01*
X345914Y420066D01*
X346106Y419808D01*
X346413Y419653D01*
X346681Y419601D01*
G01X372193Y97792D02*
X371963Y97947D01*
X371695Y98050D01*
X371388D01*
X371043Y97895D01*
X370775Y97637D01*
X370583Y97327D01*
X370430Y96810D01*
X370392Y96345D01*
X370468Y95880D01*
X370583Y95570D01*
X370813Y95260D01*
X371082Y95053D01*
X371350Y94950D01*
X371618D01*
X371887Y95053D01*
X372117Y95208D01*
X372308Y95415D01*
G01X373722Y97533D02*
X373952Y97843D01*
X374220Y97998D01*
X374527Y98050D01*
X374910Y97947D01*
X375178Y97688D01*
X375255Y97378D01*
X375217Y97068D01*
X375063Y96810D01*
X374297Y96293D01*
X373952Y95932D01*
X373722Y95415D01*
X373645Y94950D01*
X375255D01*
G01X378010D02*
Y98050D01*
X376592Y95828D01*
X378508D01*
G01X380573Y94950D02*
X380650Y95622D01*
X380765Y96190D01*
X380918Y96707D01*
X381110Y97275D01*
X381417Y98050D01*
X379883D01*
G01X378000Y81583D02*
X374900D01*
Y82542D01*
X375055Y82848D01*
X375262Y83040D01*
X375675Y83117D01*
X376088Y83040D01*
X376347Y82810D01*
X376502Y82542D01*
Y81583D01*
G01Y82542D02*
X378000Y83117D01*
G01X375417Y84722D02*
X375107Y84952D01*
X374952Y85220D01*
X374900Y85527D01*
X375003Y85910D01*
X375262Y86178D01*
X375572Y86255D01*
X375882Y86217D01*
X376140Y86063D01*
X376657Y85297D01*
X377018Y84952D01*
X377535Y84722D01*
X378000Y84645D01*
Y86255D01*
G01X377380Y87707D02*
X377742Y87937D01*
X377948Y88243D01*
X378000Y88588D01*
X377948Y88895D01*
X377690Y89202D01*
X377380Y89393D01*
X377070Y89432D01*
X376708Y89355D01*
X376450Y89087D01*
X376347Y88818D01*
Y88473D01*
G01Y88818D02*
X376192Y89048D01*
X375933Y89240D01*
X375623Y89317D01*
X375313Y89240D01*
X375055Y89048D01*
X374900Y88703D01*
X374952Y88358D01*
X375158Y88013D01*
G01X376708Y90922D02*
X376347Y91190D01*
X376140Y91420D01*
X376037Y91727D01*
X376140Y91995D01*
X376347Y92187D01*
X376657Y92340D01*
X377018Y92378D01*
X377328Y92340D01*
X377638Y92187D01*
X377897Y91957D01*
X378000Y91688D01*
X377897Y91382D01*
X377587Y91113D01*
X377122Y90960D01*
X376605Y90922D01*
X375933Y90998D01*
X375572Y91113D01*
X375210Y91305D01*
X374952Y91573D01*
X374900Y91842D01*
X375003Y92110D01*
X375262Y92302D01*
G01X368950Y79350D02*
X372050D01*
G01X368950Y78468D02*
Y80232D01*
G01X372050Y81683D02*
X368950D01*
Y82603D01*
X369105Y82910D01*
X369467Y83140D01*
X369880Y83217D01*
X370293Y83140D01*
X370603Y82948D01*
X370758Y82603D01*
Y81683D01*
G01X371585Y84707D02*
X371843Y84937D01*
X371998Y85205D01*
X372050Y85550D01*
X371947Y85895D01*
X371740Y86163D01*
X371378Y86355D01*
X370965Y86393D01*
X370552Y86317D01*
X370293Y86125D01*
X370087Y85857D01*
X370035Y85588D01*
X370087Y85320D01*
X370293Y84975D01*
X368950Y85090D01*
Y86125D01*
G01Y88650D02*
X369053Y88343D01*
X369312Y88113D01*
X369622Y87960D01*
X370035Y87845D01*
X370500Y87807D01*
X370965Y87845D01*
X371378Y87960D01*
X371688Y88113D01*
X371947Y88343D01*
X372050Y88650D01*
X371947Y88957D01*
X371688Y89187D01*
X371378Y89340D01*
X370965Y89455D01*
X370500Y89493D01*
X370035Y89455D01*
X369622Y89340D01*
X369312Y89187D01*
X369053Y88957D01*
X368950Y88650D01*
G01X372693Y107292D02*
X372463Y107447D01*
X372195Y107550D01*
X371888D01*
X371543Y107395D01*
X371275Y107137D01*
X371083Y106827D01*
X370930Y106310D01*
X370892Y105845D01*
X370968Y105380D01*
X371083Y105070D01*
X371313Y104760D01*
X371582Y104553D01*
X371850Y104450D01*
X372118D01*
X372387Y104553D01*
X372617Y104708D01*
X372808Y104915D01*
G01X374222Y107033D02*
X374452Y107343D01*
X374720Y107498D01*
X375027Y107550D01*
X375410Y107447D01*
X375678Y107188D01*
X375755Y106878D01*
X375717Y106568D01*
X375563Y106310D01*
X374797Y105793D01*
X374452Y105432D01*
X374222Y104915D01*
X374145Y104450D01*
X375755D01*
G01X377398Y104812D02*
X377667Y104553D01*
X377973Y104450D01*
X378280Y104553D01*
X378548Y104863D01*
X378740Y105328D01*
X378817Y105793D01*
Y106362D01*
X378740Y106827D01*
X378548Y107240D01*
X378318Y107447D01*
X378050Y107550D01*
X377743Y107447D01*
X377513Y107240D01*
X377360Y106930D01*
X377283Y106517D01*
X377360Y106155D01*
X377552Y105793D01*
X377782Y105587D01*
X378050Y105535D01*
X378357Y105638D01*
X378587Y105897D01*
X378817Y106362D01*
G01X381150Y104450D02*
Y107550D01*
X380690Y106930D01*
G01Y104450D02*
X381610D01*
G01X375840Y136762D02*
X375530Y136992D01*
X375375Y137260D01*
X375323Y137567D01*
X375426Y137950D01*
X375685Y138218D01*
X375995Y138295D01*
X376305Y138257D01*
X376563Y138103D01*
X377080Y137337D01*
X377441Y136992D01*
X377958Y136762D01*
X378423Y136685D01*
Y138295D01*
G01Y145450D02*
X375323D01*
X377545Y144032D01*
Y145948D01*
G01X360414Y149501D02*
Y146401D01*
X361948D01*
G01X363438Y147021D02*
X363668Y146659D01*
X363974Y146453D01*
X364319Y146401D01*
X364626Y146453D01*
X364933Y146711D01*
X365124Y147021D01*
X365163Y147331D01*
X365086Y147693D01*
X364818Y147951D01*
X364549Y148054D01*
X364204D01*
G01X364549D02*
X364779Y148209D01*
X364971Y148468D01*
X365048Y148778D01*
X364971Y149088D01*
X364779Y149346D01*
X364434Y149501D01*
X364089Y149449D01*
X363744Y149243D01*
G01X367841Y146401D02*
Y149501D01*
X366423Y147279D01*
X368339D01*
G01X369208Y157693D02*
X369053Y157463D01*
X368950Y157195D01*
Y156888D01*
X369105Y156543D01*
X369363Y156275D01*
X369673Y156083D01*
X370190Y155930D01*
X370655Y155892D01*
X371120Y155968D01*
X371430Y156083D01*
X371740Y156313D01*
X371947Y156582D01*
X372050Y156850D01*
Y157118D01*
X371947Y157387D01*
X371792Y157617D01*
X371585Y157808D01*
G01X372050Y159950D02*
X368950D01*
X369570Y159490D01*
G01X372050D02*
Y160410D01*
G01X371430Y162207D02*
X371792Y162437D01*
X371998Y162743D01*
X372050Y163088D01*
X371998Y163395D01*
X371740Y163702D01*
X371430Y163893D01*
X371120Y163932D01*
X370758Y163855D01*
X370500Y163587D01*
X370397Y163318D01*
Y162973D01*
G01Y163318D02*
X370242Y163548D01*
X369983Y163740D01*
X369673Y163817D01*
X369363Y163740D01*
X369105Y163548D01*
X368950Y163203D01*
X369002Y162858D01*
X369208Y162513D01*
G01X372050Y166073D02*
X371378Y166150D01*
X370810Y166265D01*
X370293Y166418D01*
X369725Y166610D01*
X368950Y166917D01*
Y165383D01*
G01X377131Y152762D02*
X376770Y153030D01*
X376563Y153260D01*
X376460Y153567D01*
X376563Y153835D01*
X376770Y154027D01*
X377080Y154180D01*
X377441Y154218D01*
X377751Y154180D01*
X378061Y154027D01*
X378320Y153797D01*
X378423Y153528D01*
X378320Y153222D01*
X378010Y152953D01*
X377545Y152800D01*
X377028Y152762D01*
X376356Y152838D01*
X375995Y152953D01*
X375633Y153145D01*
X375375Y153413D01*
X375323Y153682D01*
X375426Y153950D01*
X375685Y154142D01*
G01X378423Y160990D02*
X378371Y161258D01*
X378216Y161565D01*
X377958Y161757D01*
X377596Y161833D01*
X377235Y161757D01*
X376925Y161527D01*
X376770Y161182D01*
Y160798D01*
X376666Y160568D01*
X376408Y160377D01*
X376046Y160300D01*
X375685Y160415D01*
X375426Y160683D01*
X375323Y160990D01*
X375426Y161297D01*
X375685Y161565D01*
X376046Y161680D01*
X376408Y161603D01*
X376666Y161412D01*
X376770Y161182D01*
Y160798D01*
X376925Y160453D01*
X377235Y160223D01*
X377596Y160147D01*
X377958Y160223D01*
X378216Y160415D01*
X378371Y160722D01*
X378423Y160990D01*
G01X361950Y171232D02*
X358850D01*
Y172191D01*
X359005Y172497D01*
X359212Y172689D01*
X359625Y172766D01*
X360038Y172689D01*
X360297Y172459D01*
X360452Y172191D01*
Y171232D01*
G01Y172191D02*
X361950Y172766D01*
G01Y175099D02*
X358850D01*
X359470Y174639D01*
G01X361950D02*
Y175559D01*
G01X358850Y178199D02*
X358953Y177892D01*
X359212Y177662D01*
X359522Y177509D01*
X359935Y177394D01*
X360400Y177356D01*
X360865Y177394D01*
X361278Y177509D01*
X361588Y177662D01*
X361847Y177892D01*
X361950Y178199D01*
X361847Y178506D01*
X361588Y178736D01*
X361278Y178889D01*
X360865Y179004D01*
X360400Y179042D01*
X359935Y179004D01*
X359522Y178889D01*
X359212Y178736D01*
X358953Y178506D01*
X358850Y178199D01*
G01X361950Y181759D02*
X358850D01*
X361072Y180341D01*
Y182257D01*
G01X378423Y166440D02*
X375323D01*
X375943Y165980D01*
G01X378423D02*
Y166900D01*
G01X375323Y169540D02*
X375426Y169233D01*
X375685Y169003D01*
X375995Y168850D01*
X376408Y168735D01*
X376873Y168697D01*
X377338Y168735D01*
X377751Y168850D01*
X378061Y169003D01*
X378320Y169233D01*
X378423Y169540D01*
X378320Y169847D01*
X378061Y170077D01*
X377751Y170230D01*
X377338Y170345D01*
X376873Y170383D01*
X376408Y170345D01*
X375995Y170230D01*
X375685Y170077D01*
X375426Y169847D01*
X375323Y169540D01*
G01X378423Y173440D02*
X375323D01*
X375943Y172980D01*
G01X378423D02*
Y173900D01*
G01X375840Y175812D02*
X375530Y176042D01*
X375375Y176310D01*
X375323Y176617D01*
X375426Y177000D01*
X375685Y177268D01*
X375995Y177345D01*
X376305Y177307D01*
X376563Y177153D01*
X377080Y176387D01*
X377441Y176042D01*
X377958Y175812D01*
X378423Y175735D01*
Y177345D01*
G01Y181440D02*
X375323D01*
X375943Y180980D01*
G01X378423D02*
Y181900D01*
G01Y185000D02*
X375323D01*
X377545Y183582D01*
Y185498D01*
G01X371450Y175850D02*
X374550D01*
G01X371450Y174968D02*
Y176732D01*
G01X374550Y178183D02*
X371450D01*
Y179103D01*
X371605Y179410D01*
X371967Y179640D01*
X372380Y179717D01*
X372793Y179640D01*
X373103Y179448D01*
X373258Y179103D01*
Y178183D01*
G01X374550Y182510D02*
X371450D01*
X373672Y181092D01*
Y183008D01*
G01X374550Y185073D02*
X373878Y185150D01*
X373310Y185265D01*
X372793Y185418D01*
X372225Y185610D01*
X371450Y185917D01*
Y184383D01*
G01X359772Y195792D02*
X360040Y196153D01*
X360270Y196360D01*
X360577Y196463D01*
X360845Y196360D01*
X361037Y196153D01*
X361190Y195843D01*
X361228Y195482D01*
X361190Y195172D01*
X361037Y194862D01*
X360807Y194603D01*
X360538Y194500D01*
X360232Y194603D01*
X359963Y194913D01*
X359810Y195378D01*
X359772Y195895D01*
X359848Y196567D01*
X359963Y196928D01*
X360155Y197290D01*
X360423Y197548D01*
X360692Y197600D01*
X360960Y197497D01*
X361152Y197238D01*
G01X359657Y189120D02*
X359887Y188758D01*
X360193Y188552D01*
X360538Y188500D01*
X360845Y188552D01*
X361152Y188810D01*
X361343Y189120D01*
X361382Y189430D01*
X361305Y189792D01*
X361037Y190050D01*
X360768Y190153D01*
X360423D01*
G01X360768D02*
X360998Y190308D01*
X361190Y190567D01*
X361267Y190877D01*
X361190Y191187D01*
X360998Y191445D01*
X360653Y191600D01*
X360308Y191548D01*
X359963Y191342D01*
G01X378423Y196940D02*
X375323D01*
X375943Y196480D01*
G01X378423D02*
Y197400D01*
G01Y200040D02*
X378371Y200308D01*
X378216Y200615D01*
X377958Y200807D01*
X377596Y200883D01*
X377235Y200807D01*
X376925Y200577D01*
X376770Y200232D01*
Y199848D01*
X376666Y199618D01*
X376408Y199427D01*
X376046Y199350D01*
X375685Y199465D01*
X375426Y199733D01*
X375323Y200040D01*
X375426Y200347D01*
X375685Y200615D01*
X376046Y200730D01*
X376408Y200653D01*
X376666Y200462D01*
X376770Y200232D01*
Y199848D01*
X376925Y199503D01*
X377235Y199273D01*
X377596Y199197D01*
X377958Y199273D01*
X378216Y199465D01*
X378371Y199772D01*
X378423Y200040D01*
G01Y189440D02*
X375323D01*
X375943Y188980D01*
G01X378423D02*
Y189900D01*
G01X377131Y191812D02*
X376770Y192080D01*
X376563Y192310D01*
X376460Y192617D01*
X376563Y192885D01*
X376770Y193077D01*
X377080Y193230D01*
X377441Y193268D01*
X377751Y193230D01*
X378061Y193077D01*
X378320Y192847D01*
X378423Y192578D01*
X378320Y192272D01*
X378010Y192003D01*
X377545Y191850D01*
X377028Y191812D01*
X376356Y191888D01*
X375995Y192003D01*
X375633Y192195D01*
X375375Y192463D01*
X375323Y192732D01*
X375426Y193000D01*
X375685Y193192D01*
G01X375840Y204712D02*
X375530Y204942D01*
X375375Y205210D01*
X375323Y205517D01*
X375426Y205900D01*
X375685Y206168D01*
X375995Y206245D01*
X376305Y206207D01*
X376563Y206053D01*
X377080Y205287D01*
X377441Y204942D01*
X377958Y204712D01*
X378423Y204635D01*
Y206245D01*
G01X375323Y208540D02*
X375426Y208233D01*
X375685Y208003D01*
X375995Y207850D01*
X376408Y207735D01*
X376873Y207697D01*
X377338Y207735D01*
X377751Y207850D01*
X378061Y208003D01*
X378320Y208233D01*
X378423Y208540D01*
X378320Y208847D01*
X378061Y209077D01*
X377751Y209230D01*
X377338Y209345D01*
X376873Y209383D01*
X376408Y209345D01*
X375995Y209230D01*
X375685Y209077D01*
X375426Y208847D01*
X375323Y208540D01*
G01X375840Y212712D02*
X375530Y212942D01*
X375375Y213210D01*
X375323Y213517D01*
X375426Y213900D01*
X375685Y214168D01*
X375995Y214245D01*
X376305Y214207D01*
X376563Y214053D01*
X377080Y213287D01*
X377441Y212942D01*
X377958Y212712D01*
X378423Y212635D01*
Y214245D01*
G01X375840Y215812D02*
X375530Y216042D01*
X375375Y216310D01*
X375323Y216617D01*
X375426Y217000D01*
X375685Y217268D01*
X375995Y217345D01*
X376305Y217307D01*
X376563Y217153D01*
X377080Y216387D01*
X377441Y216042D01*
X377958Y215812D01*
X378423Y215735D01*
Y217345D01*
G01X362381Y231343D02*
X362226Y231113D01*
X362123Y230845D01*
Y230538D01*
X362278Y230193D01*
X362536Y229925D01*
X362846Y229733D01*
X363363Y229580D01*
X363828Y229542D01*
X364293Y229618D01*
X364603Y229733D01*
X364913Y229963D01*
X365120Y230232D01*
X365223Y230500D01*
Y230768D01*
X365120Y231037D01*
X364965Y231267D01*
X364758Y231458D01*
G01X365223Y234060D02*
X362123D01*
X364345Y232642D01*
Y234558D01*
G01X365223Y236623D02*
X364551Y236700D01*
X363983Y236815D01*
X363466Y236968D01*
X362898Y237160D01*
X362123Y237467D01*
Y235933D01*
G01X361414Y223001D02*
Y219901D01*
X362948D01*
G01X364438Y220521D02*
X364668Y220159D01*
X364974Y219953D01*
X365319Y219901D01*
X365626Y219953D01*
X365933Y220211D01*
X366124Y220521D01*
X366163Y220831D01*
X366086Y221193D01*
X365818Y221451D01*
X365549Y221554D01*
X365204D01*
G01X365549D02*
X365779Y221709D01*
X365971Y221968D01*
X366048Y222278D01*
X365971Y222588D01*
X365779Y222846D01*
X365434Y223001D01*
X365089Y222949D01*
X364744Y222743D01*
G01X367538Y220521D02*
X367768Y220159D01*
X368074Y219953D01*
X368419Y219901D01*
X368726Y219953D01*
X369033Y220211D01*
X369224Y220521D01*
X369263Y220831D01*
X369186Y221193D01*
X368918Y221451D01*
X368649Y221554D01*
X368304D01*
G01X368649D02*
X368879Y221709D01*
X369071Y221968D01*
X369148Y222278D01*
X369071Y222588D01*
X368879Y222846D01*
X368534Y223001D01*
X368189Y222949D01*
X367844Y222743D01*
G01X375272Y248242D02*
X375540Y248603D01*
X375770Y248810D01*
X376077Y248913D01*
X376345Y248810D01*
X376537Y248603D01*
X376690Y248293D01*
X376728Y247932D01*
X376690Y247622D01*
X376537Y247312D01*
X376307Y247053D01*
X376038Y246950D01*
X375732Y247053D01*
X375463Y247363D01*
X375310Y247828D01*
X375272Y248345D01*
X375348Y249017D01*
X375463Y249378D01*
X375655Y249740D01*
X375923Y249998D01*
X376192Y250050D01*
X376460Y249947D01*
X376652Y249688D01*
G01X362960Y247450D02*
Y250550D01*
X361542Y248328D01*
X363458D01*
G01X368692Y236693D02*
X368537Y236463D01*
X368434Y236195D01*
Y235888D01*
X368589Y235543D01*
X368847Y235275D01*
X369157Y235083D01*
X369674Y234930D01*
X370139Y234892D01*
X370604Y234968D01*
X370914Y235083D01*
X371224Y235313D01*
X371431Y235582D01*
X371534Y235850D01*
Y236118D01*
X371431Y236387D01*
X371276Y236617D01*
X371069Y236808D01*
G01X368951Y238222D02*
X368641Y238452D01*
X368486Y238720D01*
X368434Y239027D01*
X368537Y239410D01*
X368796Y239678D01*
X369106Y239755D01*
X369416Y239717D01*
X369674Y239563D01*
X370191Y238797D01*
X370552Y238452D01*
X371069Y238222D01*
X371534Y238145D01*
Y239755D01*
G01X371069Y241207D02*
X371327Y241437D01*
X371482Y241705D01*
X371534Y242050D01*
X371431Y242395D01*
X371224Y242663D01*
X370862Y242855D01*
X370449Y242893D01*
X370036Y242817D01*
X369777Y242625D01*
X369571Y242357D01*
X369519Y242088D01*
X369571Y241820D01*
X369777Y241475D01*
X368434Y241590D01*
Y242625D01*
G01Y245150D02*
X368537Y244843D01*
X368796Y244613D01*
X369106Y244460D01*
X369519Y244345D01*
X369984Y244307D01*
X370449Y244345D01*
X370862Y244460D01*
X371172Y244613D01*
X371431Y244843D01*
X371534Y245150D01*
X371431Y245457D01*
X371172Y245687D01*
X370862Y245840D01*
X370449Y245955D01*
X369984Y245993D01*
X369519Y245955D01*
X369106Y245840D01*
X368796Y245687D01*
X368537Y245457D01*
X368434Y245150D01*
G01X362158Y240243D02*
X362003Y240013D01*
X361900Y239745D01*
Y239438D01*
X362055Y239093D01*
X362313Y238825D01*
X362623Y238633D01*
X363140Y238480D01*
X363605Y238442D01*
X364070Y238518D01*
X364380Y238633D01*
X364690Y238863D01*
X364897Y239132D01*
X365000Y239400D01*
Y239668D01*
X364897Y239937D01*
X364742Y240167D01*
X364535Y240358D01*
G01Y241657D02*
X364793Y241887D01*
X364948Y242155D01*
X365000Y242500D01*
X364897Y242845D01*
X364690Y243113D01*
X364328Y243305D01*
X363915Y243343D01*
X363502Y243267D01*
X363243Y243075D01*
X363037Y242807D01*
X362985Y242538D01*
X363037Y242270D01*
X363243Y241925D01*
X361900Y242040D01*
Y243075D01*
G01X365000Y245600D02*
X361900D01*
X362520Y245140D01*
G01X365000D02*
Y246060D01*
G01X377034Y235083D02*
X373934D01*
Y236042D01*
X374089Y236348D01*
X374296Y236540D01*
X374709Y236617D01*
X375122Y236540D01*
X375381Y236310D01*
X375536Y236042D01*
Y235083D01*
G01Y236042D02*
X377034Y236617D01*
G01Y238950D02*
X373934D01*
X374554Y238490D01*
G01X377034D02*
Y239410D01*
G01X375742Y241322D02*
X375381Y241590D01*
X375174Y241820D01*
X375071Y242127D01*
X375174Y242395D01*
X375381Y242587D01*
X375691Y242740D01*
X376052Y242778D01*
X376362Y242740D01*
X376672Y242587D01*
X376931Y242357D01*
X377034Y242088D01*
X376931Y241782D01*
X376621Y241513D01*
X376156Y241360D01*
X375639Y241322D01*
X374967Y241398D01*
X374606Y241513D01*
X374244Y241705D01*
X373986Y241973D01*
X373934Y242242D01*
X374037Y242510D01*
X374296Y242702D01*
G01X377034Y245610D02*
X373934D01*
X376156Y244192D01*
Y246108D01*
G01X364057Y258050D02*
Y255828D01*
X364210Y255363D01*
X364517Y255053D01*
X364900Y254950D01*
X365283Y255053D01*
X365590Y255363D01*
X365743Y255828D01*
Y258050D01*
G01X367157Y255570D02*
X367387Y255208D01*
X367693Y255002D01*
X368038Y254950D01*
X368345Y255002D01*
X368652Y255260D01*
X368843Y255570D01*
X368882Y255880D01*
X368805Y256242D01*
X368537Y256500D01*
X368268Y256603D01*
X367923D01*
G01X368268D02*
X368498Y256758D01*
X368690Y257017D01*
X368767Y257327D01*
X368690Y257637D01*
X368498Y257895D01*
X368153Y258050D01*
X367808Y257998D01*
X367463Y257792D01*
G01X371560Y254950D02*
Y258050D01*
X370142Y255828D01*
X372058D01*
G01X362657Y265570D02*
X362887Y265208D01*
X363193Y265002D01*
X363538Y264950D01*
X363845Y265002D01*
X364152Y265260D01*
X364343Y265570D01*
X364382Y265880D01*
X364305Y266242D01*
X364037Y266500D01*
X363768Y266603D01*
X363423D01*
G01X363768D02*
X363998Y266758D01*
X364190Y267017D01*
X364267Y267327D01*
X364190Y267637D01*
X363998Y267895D01*
X363653Y268050D01*
X363308Y267998D01*
X362963Y267792D01*
G01X371608Y279893D02*
X371453Y279663D01*
X371350Y279395D01*
Y279088D01*
X371505Y278743D01*
X371763Y278475D01*
X372073Y278283D01*
X372590Y278130D01*
X373055Y278092D01*
X373520Y278168D01*
X373830Y278283D01*
X374140Y278513D01*
X374347Y278782D01*
X374450Y279050D01*
Y279318D01*
X374347Y279587D01*
X374192Y279817D01*
X373985Y280008D01*
G01X374450Y282150D02*
X371350D01*
X371970Y281690D01*
G01X374450D02*
Y282610D01*
G01X374088Y284598D02*
X374347Y284867D01*
X374450Y285173D01*
X374347Y285480D01*
X374037Y285748D01*
X373572Y285940D01*
X373107Y286017D01*
X372538D01*
X372073Y285940D01*
X371660Y285748D01*
X371453Y285518D01*
X371350Y285250D01*
X371453Y284943D01*
X371660Y284713D01*
X371970Y284560D01*
X372383Y284483D01*
X372745Y284560D01*
X373107Y284752D01*
X373313Y284982D01*
X373365Y285250D01*
X373262Y285557D01*
X373003Y285787D01*
X372538Y286017D01*
G01X374450Y288810D02*
X371350D01*
X373572Y287392D01*
Y289308D01*
G01X365583Y269966D02*
Y273066D01*
X366542D01*
X366848Y272911D01*
X367040Y272704D01*
X367117Y272291D01*
X367040Y271878D01*
X366810Y271619D01*
X366542Y271464D01*
X365583D01*
G01X366542D02*
X367117Y269966D01*
G01X369450D02*
Y273066D01*
X368990Y272446D01*
G01Y269966D02*
X369910D01*
G01X371822Y271258D02*
X372090Y271619D01*
X372320Y271826D01*
X372627Y271929D01*
X372895Y271826D01*
X373087Y271619D01*
X373240Y271309D01*
X373278Y270948D01*
X373240Y270638D01*
X373087Y270328D01*
X372857Y270069D01*
X372588Y269966D01*
X372282Y270069D01*
X372013Y270379D01*
X371860Y270844D01*
X371822Y271361D01*
X371898Y272033D01*
X372013Y272394D01*
X372205Y272756D01*
X372473Y273014D01*
X372742Y273066D01*
X373010Y272963D01*
X373202Y272704D01*
G01X375573Y269966D02*
X375650Y270638D01*
X375765Y271206D01*
X375918Y271723D01*
X376110Y272291D01*
X376417Y273066D01*
X374883D01*
G01X363950Y274850D02*
X367050D01*
G01X363950Y273968D02*
Y275732D01*
G01X367050Y277183D02*
X363950D01*
Y278103D01*
X364105Y278410D01*
X364467Y278640D01*
X364880Y278717D01*
X365293Y278640D01*
X365603Y278448D01*
X365758Y278103D01*
Y277183D01*
G01X366585Y280207D02*
X366843Y280437D01*
X366998Y280705D01*
X367050Y281050D01*
X366947Y281395D01*
X366740Y281663D01*
X366378Y281855D01*
X365965Y281893D01*
X365552Y281817D01*
X365293Y281625D01*
X365087Y281357D01*
X365035Y281088D01*
X365087Y280820D01*
X365293Y280475D01*
X363950Y280590D01*
Y281625D01*
G01X366585Y283307D02*
X366843Y283537D01*
X366998Y283805D01*
X367050Y284150D01*
X366947Y284495D01*
X366740Y284763D01*
X366378Y284955D01*
X365965Y284993D01*
X365552Y284917D01*
X365293Y284725D01*
X365087Y284457D01*
X365035Y284188D01*
X365087Y283920D01*
X365293Y283575D01*
X363950Y283690D01*
Y284725D01*
G01X364908Y295893D02*
X364753Y295663D01*
X364650Y295395D01*
Y295088D01*
X364805Y294743D01*
X365063Y294475D01*
X365373Y294283D01*
X365890Y294130D01*
X366355Y294092D01*
X366820Y294168D01*
X367130Y294283D01*
X367440Y294513D01*
X367647Y294782D01*
X367750Y295050D01*
Y295318D01*
X367647Y295587D01*
X367492Y295817D01*
X367285Y296008D01*
G01X367750Y298150D02*
X364650D01*
X365270Y297690D01*
G01X367750D02*
Y298610D01*
G01Y301250D02*
X367698Y301518D01*
X367543Y301825D01*
X367285Y302017D01*
X366923Y302093D01*
X366562Y302017D01*
X366252Y301787D01*
X366097Y301442D01*
Y301058D01*
X365993Y300828D01*
X365735Y300637D01*
X365373Y300560D01*
X365012Y300675D01*
X364753Y300943D01*
X364650Y301250D01*
X364753Y301557D01*
X365012Y301825D01*
X365373Y301940D01*
X365735Y301863D01*
X365993Y301672D01*
X366097Y301442D01*
Y301058D01*
X366252Y300713D01*
X366562Y300483D01*
X366923Y300407D01*
X367285Y300483D01*
X367543Y300675D01*
X367698Y300982D01*
X367750Y301250D01*
G01X365167Y303622D02*
X364857Y303852D01*
X364702Y304120D01*
X364650Y304427D01*
X364753Y304810D01*
X365012Y305078D01*
X365322Y305155D01*
X365632Y305117D01*
X365890Y304963D01*
X366407Y304197D01*
X366768Y303852D01*
X367285Y303622D01*
X367750Y303545D01*
Y305155D01*
G01X371908Y294693D02*
X371753Y294463D01*
X371650Y294195D01*
Y293888D01*
X371805Y293543D01*
X372063Y293275D01*
X372373Y293083D01*
X372890Y292930D01*
X373355Y292892D01*
X373820Y292968D01*
X374130Y293083D01*
X374440Y293313D01*
X374647Y293582D01*
X374750Y293850D01*
Y294118D01*
X374647Y294387D01*
X374492Y294617D01*
X374285Y294808D01*
G01X374750Y296950D02*
X371650D01*
X372270Y296490D01*
G01X374750D02*
Y297410D01*
G01Y300050D02*
X374698Y300318D01*
X374543Y300625D01*
X374285Y300817D01*
X373923Y300893D01*
X373562Y300817D01*
X373252Y300587D01*
X373097Y300242D01*
Y299858D01*
X372993Y299628D01*
X372735Y299437D01*
X372373Y299360D01*
X372012Y299475D01*
X371753Y299743D01*
X371650Y300050D01*
X371753Y300357D01*
X372012Y300625D01*
X372373Y300740D01*
X372735Y300663D01*
X372993Y300472D01*
X373097Y300242D01*
Y299858D01*
X373252Y299513D01*
X373562Y299283D01*
X373923Y299207D01*
X374285Y299283D01*
X374543Y299475D01*
X374698Y299782D01*
X374750Y300050D01*
G01X374285Y302307D02*
X374543Y302537D01*
X374698Y302805D01*
X374750Y303150D01*
X374647Y303495D01*
X374440Y303763D01*
X374078Y303955D01*
X373665Y303993D01*
X373252Y303917D01*
X372993Y303725D01*
X372787Y303457D01*
X372735Y303188D01*
X372787Y302920D01*
X372993Y302575D01*
X371650Y302690D01*
Y303725D01*
G01X372583Y308000D02*
Y311100D01*
X373542D01*
X373848Y310945D01*
X374040Y310738D01*
X374117Y310325D01*
X374040Y309912D01*
X373810Y309653D01*
X373542Y309498D01*
X372583D01*
G01X373542D02*
X374117Y308000D01*
G01X376450D02*
Y311100D01*
X375990Y310480D01*
G01Y308000D02*
X376910D01*
G01X380010D02*
Y311100D01*
X378592Y308878D01*
X380508D01*
G01X382650Y311100D02*
X382343Y310997D01*
X382113Y310738D01*
X381960Y310428D01*
X381845Y310015D01*
X381807Y309550D01*
X381845Y309085D01*
X381960Y308672D01*
X382113Y308362D01*
X382343Y308103D01*
X382650Y308000D01*
X382957Y308103D01*
X383187Y308362D01*
X383340Y308672D01*
X383455Y309085D01*
X383493Y309550D01*
X383455Y310015D01*
X383340Y310428D01*
X383187Y310738D01*
X382957Y310997D01*
X382650Y311100D01*
G01X364233Y311450D02*
Y308350D01*
X365767D01*
G01X368100D02*
Y311450D01*
X367640Y310830D01*
G01Y308350D02*
X368560D01*
G01X371200D02*
Y311450D01*
X370740Y310830D01*
G01Y308350D02*
X371660D01*
G01X376560Y338700D02*
Y341800D01*
X375142Y339578D01*
X377058D01*
G01X363850Y381833D02*
X360750D01*
Y382792D01*
X360905Y383098D01*
X361112Y383290D01*
X361525Y383367D01*
X361938Y383290D01*
X362197Y383060D01*
X362352Y382792D01*
Y381833D01*
G01Y382792D02*
X363850Y383367D01*
G01Y385700D02*
X360750D01*
X361370Y385240D01*
G01X363850D02*
Y386160D01*
G01Y388723D02*
X363178Y388800D01*
X362610Y388915D01*
X362093Y389068D01*
X361525Y389260D01*
X360750Y389567D01*
Y388033D01*
G01X364350Y415050D02*
Y411950D01*
G01X363468Y415050D02*
X365232D01*
G01X366683Y411950D02*
Y415050D01*
X367603D01*
X367910Y414895D01*
X368140Y414533D01*
X368217Y414120D01*
X368140Y413707D01*
X367948Y413397D01*
X367603Y413242D01*
X366683D01*
G01X369707Y412415D02*
X369937Y412157D01*
X370205Y412002D01*
X370550Y411950D01*
X370895Y412053D01*
X371163Y412260D01*
X371355Y412622D01*
X371393Y413035D01*
X371317Y413448D01*
X371125Y413707D01*
X370857Y413913D01*
X370588Y413965D01*
X370320Y413913D01*
X369975Y413707D01*
X370090Y415050D01*
X371125D01*
G01X372998Y412312D02*
X373267Y412053D01*
X373573Y411950D01*
X373880Y412053D01*
X374148Y412363D01*
X374340Y412828D01*
X374417Y413293D01*
Y413862D01*
X374340Y414327D01*
X374148Y414740D01*
X373918Y414947D01*
X373650Y415050D01*
X373343Y414947D01*
X373113Y414740D01*
X372960Y414430D01*
X372883Y414017D01*
X372960Y413655D01*
X373152Y413293D01*
X373382Y413087D01*
X373650Y413035D01*
X373957Y413138D01*
X374187Y413397D01*
X374417Y413862D01*
G01X370433Y420091D02*
Y416991D01*
G01X369551Y420091D02*
X371315D01*
G01X372766Y416991D02*
Y420091D01*
X373686D01*
X373993Y419936D01*
X374223Y419574D01*
X374300Y419161D01*
X374223Y418748D01*
X374031Y418438D01*
X373686Y418283D01*
X372766D01*
G01X375790Y417611D02*
X376020Y417249D01*
X376326Y417043D01*
X376671Y416991D01*
X376978Y417043D01*
X377285Y417301D01*
X377476Y417611D01*
X377515Y417921D01*
X377438Y418283D01*
X377170Y418541D01*
X376901Y418644D01*
X376556D01*
G01X376901D02*
X377131Y418799D01*
X377323Y419058D01*
X377400Y419368D01*
X377323Y419678D01*
X377131Y419936D01*
X376786Y420091D01*
X376441Y420039D01*
X376096Y419833D01*
G01X379733Y416991D02*
X380001Y417043D01*
X380308Y417198D01*
X380500Y417456D01*
X380576Y417818D01*
X380500Y418179D01*
X380270Y418489D01*
X379925Y418644D01*
X379541D01*
X379311Y418748D01*
X379120Y419006D01*
X379043Y419368D01*
X379158Y419729D01*
X379426Y419988D01*
X379733Y420091D01*
X380040Y419988D01*
X380308Y419729D01*
X380423Y419368D01*
X380346Y419006D01*
X380155Y418748D01*
X379925Y418644D01*
X379541D01*
X379196Y418489D01*
X378966Y418179D01*
X378890Y417818D01*
X378966Y417456D01*
X379158Y417198D01*
X379465Y417043D01*
X379733Y416991D01*
G01X387717Y68297D02*
Y71397D01*
X387257Y70777D01*
G01Y68297D02*
X388177D01*
G01X384193Y97292D02*
X383963Y97447D01*
X383695Y97550D01*
X383388D01*
X383043Y97395D01*
X382775Y97137D01*
X382583Y96827D01*
X382430Y96310D01*
X382392Y95845D01*
X382468Y95380D01*
X382583Y95070D01*
X382813Y94760D01*
X383082Y94553D01*
X383350Y94450D01*
X383618D01*
X383887Y94553D01*
X384117Y94708D01*
X384308Y94915D01*
G01X385722Y97033D02*
X385952Y97343D01*
X386220Y97498D01*
X386527Y97550D01*
X386910Y97447D01*
X387178Y97188D01*
X387255Y96878D01*
X387217Y96568D01*
X387063Y96310D01*
X386297Y95793D01*
X385952Y95432D01*
X385722Y94915D01*
X385645Y94450D01*
X387255D01*
G01X390010D02*
Y97550D01*
X388592Y95328D01*
X390508D01*
G01X391998Y94812D02*
X392267Y94553D01*
X392573Y94450D01*
X392880Y94553D01*
X393148Y94863D01*
X393340Y95328D01*
X393417Y95793D01*
Y96362D01*
X393340Y96827D01*
X393148Y97240D01*
X392918Y97447D01*
X392650Y97550D01*
X392343Y97447D01*
X392113Y97240D01*
X391960Y96930D01*
X391883Y96517D01*
X391960Y96155D01*
X392152Y95793D01*
X392382Y95587D01*
X392650Y95535D01*
X392957Y95638D01*
X393187Y95897D01*
X393417Y96362D01*
G01X381272Y90792D02*
X381540Y91153D01*
X381770Y91360D01*
X382077Y91463D01*
X382345Y91360D01*
X382537Y91153D01*
X382690Y90843D01*
X382728Y90482D01*
X382690Y90172D01*
X382537Y89862D01*
X382307Y89603D01*
X382038Y89500D01*
X381732Y89603D01*
X381463Y89913D01*
X381310Y90378D01*
X381272Y90895D01*
X381348Y91567D01*
X381463Y91928D01*
X381655Y92290D01*
X381923Y92548D01*
X382192Y92600D01*
X382460Y92497D01*
X382652Y92238D01*
G01X391033Y124792D02*
X387933Y125750D01*
X391033Y126708D01*
G01X389948Y126363D02*
Y125137D01*
G01X393380Y123057D02*
X393225Y123210D01*
X392966Y123325D01*
X392605Y123402D01*
X392295Y123325D01*
X392088Y123172D01*
X391933Y122903D01*
Y121868D01*
X395033D01*
Y123133D01*
X394826Y123402D01*
X394516Y123555D01*
X394155Y123632D01*
X393793Y123555D01*
X393483Y123325D01*
X393380Y123057D01*
Y121868D01*
G01X382923Y133990D02*
X379823D01*
X380443Y133530D01*
G01X382923D02*
Y134450D01*
G01X382303Y141147D02*
X382665Y141377D01*
X382871Y141683D01*
X382923Y142028D01*
X382871Y142335D01*
X382613Y142642D01*
X382303Y142833D01*
X381993Y142872D01*
X381631Y142795D01*
X381373Y142527D01*
X381270Y142258D01*
Y141913D01*
G01Y142258D02*
X381115Y142488D01*
X380856Y142680D01*
X380546Y142757D01*
X380236Y142680D01*
X379978Y142488D01*
X379823Y142143D01*
X379875Y141798D01*
X380081Y141453D01*
G01X382458Y149147D02*
X382716Y149377D01*
X382871Y149645D01*
X382923Y149990D01*
X382820Y150335D01*
X382613Y150603D01*
X382251Y150795D01*
X381838Y150833D01*
X381425Y150757D01*
X381166Y150565D01*
X380960Y150297D01*
X380908Y150028D01*
X380960Y149760D01*
X381166Y149415D01*
X379823Y149530D01*
Y150565D01*
G01X382923Y157913D02*
X382251Y157990D01*
X381683Y158105D01*
X381166Y158258D01*
X380598Y158450D01*
X379823Y158757D01*
Y157223D01*
G01X382561Y164838D02*
X382820Y165107D01*
X382923Y165413D01*
X382820Y165720D01*
X382510Y165988D01*
X382045Y166180D01*
X381580Y166257D01*
X381011D01*
X380546Y166180D01*
X380133Y165988D01*
X379926Y165758D01*
X379823Y165490D01*
X379926Y165183D01*
X380133Y164953D01*
X380443Y164800D01*
X380856Y164723D01*
X381218Y164800D01*
X381580Y164992D01*
X381786Y165222D01*
X381838Y165490D01*
X381735Y165797D01*
X381476Y166027D01*
X381011Y166257D01*
G01X382923Y177940D02*
X379823D01*
X380443Y177480D01*
G01X382923D02*
Y178400D01*
G01X382303Y180197D02*
X382665Y180427D01*
X382871Y180733D01*
X382923Y181078D01*
X382871Y181385D01*
X382613Y181692D01*
X382303Y181883D01*
X381993Y181922D01*
X381631Y181845D01*
X381373Y181577D01*
X381270Y181308D01*
Y180963D01*
G01Y181308D02*
X381115Y181538D01*
X380856Y181730D01*
X380546Y181807D01*
X380236Y181730D01*
X379978Y181538D01*
X379823Y181193D01*
X379875Y180848D01*
X380081Y180503D01*
G01X382923Y169940D02*
X379823D01*
X380443Y169480D01*
G01X382923D02*
Y170400D01*
G01Y173040D02*
X379823D01*
X380443Y172580D01*
G01X382923D02*
Y173500D01*
G01Y185940D02*
X379823D01*
X380443Y185480D01*
G01X382923D02*
Y186400D01*
G01X382458Y188197D02*
X382716Y188427D01*
X382871Y188695D01*
X382923Y189040D01*
X382820Y189385D01*
X382613Y189653D01*
X382251Y189845D01*
X381838Y189883D01*
X381425Y189807D01*
X381166Y189615D01*
X380960Y189347D01*
X380908Y189078D01*
X380960Y188810D01*
X381166Y188465D01*
X379823Y188580D01*
Y189615D01*
G01X382923Y193940D02*
X379823D01*
X380443Y193480D01*
G01X382923D02*
Y194400D01*
G01Y196963D02*
X382251Y197040D01*
X381683Y197155D01*
X381166Y197308D01*
X380598Y197500D01*
X379823Y197807D01*
Y196273D01*
G01X382923Y201440D02*
X379823D01*
X380443Y200980D01*
G01X382923D02*
Y201900D01*
G01X382561Y203888D02*
X382820Y204157D01*
X382923Y204463D01*
X382820Y204770D01*
X382510Y205038D01*
X382045Y205230D01*
X381580Y205307D01*
X381011D01*
X380546Y205230D01*
X380133Y205038D01*
X379926Y204808D01*
X379823Y204540D01*
X379926Y204233D01*
X380133Y204003D01*
X380443Y203850D01*
X380856Y203773D01*
X381218Y203850D01*
X381580Y204042D01*
X381786Y204272D01*
X381838Y204540D01*
X381735Y204847D01*
X381476Y205077D01*
X381011Y205307D01*
G01X380340Y209212D02*
X380030Y209442D01*
X379875Y209710D01*
X379823Y210017D01*
X379926Y210400D01*
X380185Y210668D01*
X380495Y210745D01*
X380805Y210707D01*
X381063Y210553D01*
X381580Y209787D01*
X381941Y209442D01*
X382458Y209212D01*
X382923Y209135D01*
Y210745D01*
G01Y213040D02*
X379823D01*
X380443Y212580D01*
G01X382923D02*
Y213500D01*
G01X393450Y247683D02*
X390350D01*
Y248642D01*
X390505Y248948D01*
X390712Y249140D01*
X391125Y249217D01*
X391538Y249140D01*
X391797Y248910D01*
X391952Y248642D01*
Y247683D01*
G01Y248642D02*
X393450Y249217D01*
G01Y251550D02*
X390350D01*
X390970Y251090D01*
G01X393450D02*
Y252010D01*
G01Y254573D02*
X392778Y254650D01*
X392210Y254765D01*
X391693Y254918D01*
X391125Y255110D01*
X390350Y255417D01*
Y253883D01*
G01X390867Y257022D02*
X390557Y257252D01*
X390402Y257520D01*
X390350Y257827D01*
X390453Y258210D01*
X390712Y258478D01*
X391022Y258555D01*
X391332Y258517D01*
X391590Y258363D01*
X392107Y257597D01*
X392468Y257252D01*
X392985Y257022D01*
X393450Y256945D01*
Y258555D01*
G01X387034Y247683D02*
X383934D01*
Y248642D01*
X384089Y248948D01*
X384296Y249140D01*
X384709Y249217D01*
X385122Y249140D01*
X385381Y248910D01*
X385536Y248642D01*
Y247683D01*
G01Y248642D02*
X387034Y249217D01*
G01X384451Y250822D02*
X384141Y251052D01*
X383986Y251320D01*
X383934Y251627D01*
X384037Y252010D01*
X384296Y252278D01*
X384606Y252355D01*
X384916Y252317D01*
X385174Y252163D01*
X385691Y251397D01*
X386052Y251052D01*
X386569Y250822D01*
X387034Y250745D01*
Y252355D01*
G01Y254650D02*
X386982Y254918D01*
X386827Y255225D01*
X386569Y255417D01*
X386207Y255493D01*
X385846Y255417D01*
X385536Y255187D01*
X385381Y254842D01*
Y254458D01*
X385277Y254228D01*
X385019Y254037D01*
X384657Y253960D01*
X384296Y254075D01*
X384037Y254343D01*
X383934Y254650D01*
X384037Y254957D01*
X384296Y255225D01*
X384657Y255340D01*
X385019Y255263D01*
X385277Y255072D01*
X385381Y254842D01*
Y254458D01*
X385536Y254113D01*
X385846Y253883D01*
X386207Y253807D01*
X386569Y253883D01*
X386827Y254075D01*
X386982Y254382D01*
X387034Y254650D01*
G01X386414Y256907D02*
X386776Y257137D01*
X386982Y257443D01*
X387034Y257788D01*
X386982Y258095D01*
X386724Y258402D01*
X386414Y258593D01*
X386104Y258632D01*
X385742Y258555D01*
X385484Y258287D01*
X385381Y258018D01*
Y257673D01*
G01Y258018D02*
X385226Y258248D01*
X384967Y258440D01*
X384657Y258517D01*
X384347Y258440D01*
X384089Y258248D01*
X383934Y257903D01*
X383986Y257558D01*
X384192Y257213D01*
G01X381134Y247683D02*
X378034D01*
Y248642D01*
X378189Y248948D01*
X378396Y249140D01*
X378809Y249217D01*
X379222Y249140D01*
X379481Y248910D01*
X379636Y248642D01*
Y247683D01*
G01Y248642D02*
X381134Y249217D01*
G01X378551Y250822D02*
X378241Y251052D01*
X378086Y251320D01*
X378034Y251627D01*
X378137Y252010D01*
X378396Y252278D01*
X378706Y252355D01*
X379016Y252317D01*
X379274Y252163D01*
X379791Y251397D01*
X380152Y251052D01*
X380669Y250822D01*
X381134Y250745D01*
Y252355D01*
G01Y254650D02*
X381082Y254918D01*
X380927Y255225D01*
X380669Y255417D01*
X380307Y255493D01*
X379946Y255417D01*
X379636Y255187D01*
X379481Y254842D01*
Y254458D01*
X379377Y254228D01*
X379119Y254037D01*
X378757Y253960D01*
X378396Y254075D01*
X378137Y254343D01*
X378034Y254650D01*
X378137Y254957D01*
X378396Y255225D01*
X378757Y255340D01*
X379119Y255263D01*
X379377Y255072D01*
X379481Y254842D01*
Y254458D01*
X379636Y254113D01*
X379946Y253883D01*
X380307Y253807D01*
X380669Y253883D01*
X380927Y254075D01*
X381082Y254382D01*
X381134Y254650D01*
G01X380669Y256907D02*
X380927Y257137D01*
X381082Y257405D01*
X381134Y257750D01*
X381031Y258095D01*
X380824Y258363D01*
X380462Y258555D01*
X380049Y258593D01*
X379636Y258517D01*
X379377Y258325D01*
X379171Y258057D01*
X379119Y257788D01*
X379171Y257520D01*
X379377Y257175D01*
X378034Y257290D01*
Y258325D01*
G01X391783Y266950D02*
Y270050D01*
X392742D01*
X393048Y269895D01*
X393240Y269688D01*
X393317Y269275D01*
X393240Y268862D01*
X393010Y268603D01*
X392742Y268448D01*
X391783D01*
G01X392742D02*
X393317Y266950D01*
G01X395650D02*
Y270050D01*
X395190Y269430D01*
G01Y266950D02*
X396110D01*
G01X398673D02*
X398750Y267622D01*
X398865Y268190D01*
X399018Y268707D01*
X399210Y269275D01*
X399517Y270050D01*
X397983D01*
G01X401850Y266950D02*
X402118Y267002D01*
X402425Y267157D01*
X402617Y267415D01*
X402693Y267777D01*
X402617Y268138D01*
X402387Y268448D01*
X402042Y268603D01*
X401658D01*
X401428Y268707D01*
X401237Y268965D01*
X401160Y269327D01*
X401275Y269688D01*
X401543Y269947D01*
X401850Y270050D01*
X402157Y269947D01*
X402425Y269688D01*
X402540Y269327D01*
X402463Y268965D01*
X402272Y268707D01*
X402042Y268603D01*
X401658D01*
X401313Y268448D01*
X401083Y268138D01*
X401007Y267777D01*
X401083Y267415D01*
X401275Y267157D01*
X401582Y267002D01*
X401850Y266950D01*
G01X378283Y266966D02*
Y270066D01*
X379242D01*
X379548Y269911D01*
X379740Y269704D01*
X379817Y269291D01*
X379740Y268878D01*
X379510Y268619D01*
X379242Y268464D01*
X378283D01*
G01X379242D02*
X379817Y266966D01*
G01X382150D02*
Y270066D01*
X381690Y269446D01*
G01Y266966D02*
X382610D01*
G01X385250D02*
X385518Y267018D01*
X385825Y267173D01*
X386017Y267431D01*
X386093Y267793D01*
X386017Y268154D01*
X385787Y268464D01*
X385442Y268619D01*
X385058D01*
X384828Y268723D01*
X384637Y268981D01*
X384560Y269343D01*
X384675Y269704D01*
X384943Y269963D01*
X385250Y270066D01*
X385557Y269963D01*
X385825Y269704D01*
X385940Y269343D01*
X385863Y268981D01*
X385672Y268723D01*
X385442Y268619D01*
X385058D01*
X384713Y268464D01*
X384483Y268154D01*
X384407Y267793D01*
X384483Y267431D01*
X384675Y267173D01*
X384982Y267018D01*
X385250Y266966D01*
G01X387622Y268258D02*
X387890Y268619D01*
X388120Y268826D01*
X388427Y268929D01*
X388695Y268826D01*
X388887Y268619D01*
X389040Y268309D01*
X389078Y267948D01*
X389040Y267638D01*
X388887Y267328D01*
X388657Y267069D01*
X388388Y266966D01*
X388082Y267069D01*
X387813Y267379D01*
X387660Y267844D01*
X387622Y268361D01*
X387698Y269033D01*
X387813Y269394D01*
X388005Y269756D01*
X388273Y270014D01*
X388542Y270066D01*
X388810Y269963D01*
X389002Y269704D01*
G01X378408Y283193D02*
X378253Y282963D01*
X378150Y282695D01*
Y282388D01*
X378305Y282043D01*
X378563Y281775D01*
X378873Y281583D01*
X379390Y281430D01*
X379855Y281392D01*
X380320Y281468D01*
X380630Y281583D01*
X380940Y281813D01*
X381147Y282082D01*
X381250Y282350D01*
Y282618D01*
X381147Y282887D01*
X380992Y283117D01*
X380785Y283308D01*
G01X381250Y285450D02*
X378150D01*
X378770Y284990D01*
G01X381250D02*
Y285910D01*
G01X380888Y287898D02*
X381147Y288167D01*
X381250Y288473D01*
X381147Y288780D01*
X380837Y289048D01*
X380372Y289240D01*
X379907Y289317D01*
X379338D01*
X378873Y289240D01*
X378460Y289048D01*
X378253Y288818D01*
X378150Y288550D01*
X378253Y288243D01*
X378460Y288013D01*
X378770Y287860D01*
X379183Y287783D01*
X379545Y287860D01*
X379907Y288052D01*
X380113Y288282D01*
X380165Y288550D01*
X380062Y288857D01*
X379803Y289087D01*
X379338Y289317D01*
G01X379958Y290922D02*
X379597Y291190D01*
X379390Y291420D01*
X379287Y291727D01*
X379390Y291995D01*
X379597Y292187D01*
X379907Y292340D01*
X380268Y292378D01*
X380578Y292340D01*
X380888Y292187D01*
X381147Y291957D01*
X381250Y291688D01*
X381147Y291382D01*
X380837Y291113D01*
X380372Y290960D01*
X379855Y290922D01*
X379183Y290998D01*
X378822Y291113D01*
X378460Y291305D01*
X378202Y291573D01*
X378150Y291842D01*
X378253Y292110D01*
X378512Y292302D01*
G01X393893Y279192D02*
X393663Y279347D01*
X393395Y279450D01*
X393088D01*
X392743Y279295D01*
X392475Y279037D01*
X392283Y278727D01*
X392130Y278210D01*
X392092Y277745D01*
X392168Y277280D01*
X392283Y276970D01*
X392513Y276660D01*
X392782Y276453D01*
X393050Y276350D01*
X393318D01*
X393587Y276453D01*
X393817Y276608D01*
X394008Y276815D01*
G01X396150Y276350D02*
Y279450D01*
X395690Y278830D01*
G01Y276350D02*
X396610D01*
G01X398598Y276712D02*
X398867Y276453D01*
X399173Y276350D01*
X399480Y276453D01*
X399748Y276763D01*
X399940Y277228D01*
X400017Y277693D01*
Y278262D01*
X399940Y278727D01*
X399748Y279140D01*
X399518Y279347D01*
X399250Y279450D01*
X398943Y279347D01*
X398713Y279140D01*
X398560Y278830D01*
X398483Y278417D01*
X398560Y278055D01*
X398752Y277693D01*
X398982Y277487D01*
X399250Y277435D01*
X399557Y277538D01*
X399787Y277797D01*
X400017Y278262D01*
G01X401622Y278933D02*
X401852Y279243D01*
X402120Y279398D01*
X402427Y279450D01*
X402810Y279347D01*
X403078Y279088D01*
X403155Y278778D01*
X403117Y278468D01*
X402963Y278210D01*
X402197Y277693D01*
X401852Y277332D01*
X401622Y276815D01*
X401545Y276350D01*
X403155D01*
G01X378283Y275950D02*
Y279050D01*
X379242D01*
X379548Y278895D01*
X379740Y278688D01*
X379817Y278275D01*
X379740Y277862D01*
X379510Y277603D01*
X379242Y277448D01*
X378283D01*
G01X379242D02*
X379817Y275950D01*
G01X382150D02*
Y279050D01*
X381690Y278430D01*
G01Y275950D02*
X382610D01*
G01X385250D02*
X385518Y276002D01*
X385825Y276157D01*
X386017Y276415D01*
X386093Y276777D01*
X386017Y277138D01*
X385787Y277448D01*
X385442Y277603D01*
X385058D01*
X384828Y277707D01*
X384637Y277965D01*
X384560Y278327D01*
X384675Y278688D01*
X384943Y278947D01*
X385250Y279050D01*
X385557Y278947D01*
X385825Y278688D01*
X385940Y278327D01*
X385863Y277965D01*
X385672Y277707D01*
X385442Y277603D01*
X385058D01*
X384713Y277448D01*
X384483Y277138D01*
X384407Y276777D01*
X384483Y276415D01*
X384675Y276157D01*
X384982Y276002D01*
X385250Y275950D01*
G01X387507Y276415D02*
X387737Y276157D01*
X388005Y276002D01*
X388350Y275950D01*
X388695Y276053D01*
X388963Y276260D01*
X389155Y276622D01*
X389193Y277035D01*
X389117Y277448D01*
X388925Y277707D01*
X388657Y277913D01*
X388388Y277965D01*
X388120Y277913D01*
X387775Y277707D01*
X387890Y279050D01*
X388925D01*
G01X391783Y271450D02*
Y274550D01*
X392742D01*
X393048Y274395D01*
X393240Y274188D01*
X393317Y273775D01*
X393240Y273362D01*
X393010Y273103D01*
X392742Y272948D01*
X391783D01*
G01X392742D02*
X393317Y271450D01*
G01X395650D02*
Y274550D01*
X395190Y273930D01*
G01Y271450D02*
X396110D01*
G01X398750D02*
X399018Y271502D01*
X399325Y271657D01*
X399517Y271915D01*
X399593Y272277D01*
X399517Y272638D01*
X399287Y272948D01*
X398942Y273103D01*
X398558D01*
X398328Y273207D01*
X398137Y273465D01*
X398060Y273827D01*
X398175Y274188D01*
X398443Y274447D01*
X398750Y274550D01*
X399057Y274447D01*
X399325Y274188D01*
X399440Y273827D01*
X399363Y273465D01*
X399172Y273207D01*
X398942Y273103D01*
X398558D01*
X398213Y272948D01*
X397983Y272638D01*
X397907Y272277D01*
X397983Y271915D01*
X398175Y271657D01*
X398482Y271502D01*
X398750Y271450D01*
G01X401850D02*
Y274550D01*
X401390Y273930D01*
G01Y271450D02*
X402310D01*
G01X378283Y270950D02*
Y274050D01*
X379242D01*
X379548Y273895D01*
X379740Y273688D01*
X379817Y273275D01*
X379740Y272862D01*
X379510Y272603D01*
X379242Y272448D01*
X378283D01*
G01X379242D02*
X379817Y270950D01*
G01X382150D02*
Y274050D01*
X381690Y273430D01*
G01Y270950D02*
X382610D01*
G01X385250D02*
X385518Y271002D01*
X385825Y271157D01*
X386017Y271415D01*
X386093Y271777D01*
X386017Y272138D01*
X385787Y272448D01*
X385442Y272603D01*
X385058D01*
X384828Y272707D01*
X384637Y272965D01*
X384560Y273327D01*
X384675Y273688D01*
X384943Y273947D01*
X385250Y274050D01*
X385557Y273947D01*
X385825Y273688D01*
X385940Y273327D01*
X385863Y272965D01*
X385672Y272707D01*
X385442Y272603D01*
X385058D01*
X384713Y272448D01*
X384483Y272138D01*
X384407Y271777D01*
X384483Y271415D01*
X384675Y271157D01*
X384982Y271002D01*
X385250Y270950D01*
G01X387698Y271312D02*
X387967Y271053D01*
X388273Y270950D01*
X388580Y271053D01*
X388848Y271363D01*
X389040Y271828D01*
X389117Y272293D01*
Y272862D01*
X389040Y273327D01*
X388848Y273740D01*
X388618Y273947D01*
X388350Y274050D01*
X388043Y273947D01*
X387813Y273740D01*
X387660Y273430D01*
X387583Y273017D01*
X387660Y272655D01*
X387852Y272293D01*
X388082Y272087D01*
X388350Y272035D01*
X388657Y272138D01*
X388887Y272397D01*
X389117Y272862D01*
G01X378408Y295193D02*
X378253Y294963D01*
X378150Y294695D01*
Y294388D01*
X378305Y294043D01*
X378563Y293775D01*
X378873Y293583D01*
X379390Y293430D01*
X379855Y293392D01*
X380320Y293468D01*
X380630Y293583D01*
X380940Y293813D01*
X381147Y294082D01*
X381250Y294350D01*
Y294618D01*
X381147Y294887D01*
X380992Y295117D01*
X380785Y295308D01*
G01X381250Y297450D02*
X378150D01*
X378770Y296990D01*
G01X381250D02*
Y297910D01*
G01Y300550D02*
X381198Y300818D01*
X381043Y301125D01*
X380785Y301317D01*
X380423Y301393D01*
X380062Y301317D01*
X379752Y301087D01*
X379597Y300742D01*
Y300358D01*
X379493Y300128D01*
X379235Y299937D01*
X378873Y299860D01*
X378512Y299975D01*
X378253Y300243D01*
X378150Y300550D01*
X378253Y300857D01*
X378512Y301125D01*
X378873Y301240D01*
X379235Y301163D01*
X379493Y300972D01*
X379597Y300742D01*
Y300358D01*
X379752Y300013D01*
X380062Y299783D01*
X380423Y299707D01*
X380785Y299783D01*
X381043Y299975D01*
X381198Y300282D01*
X381250Y300550D01*
G01Y303650D02*
X381198Y303918D01*
X381043Y304225D01*
X380785Y304417D01*
X380423Y304493D01*
X380062Y304417D01*
X379752Y304187D01*
X379597Y303842D01*
Y303458D01*
X379493Y303228D01*
X379235Y303037D01*
X378873Y302960D01*
X378512Y303075D01*
X378253Y303343D01*
X378150Y303650D01*
X378253Y303957D01*
X378512Y304225D01*
X378873Y304340D01*
X379235Y304263D01*
X379493Y304072D01*
X379597Y303842D01*
Y303458D01*
X379752Y303113D01*
X380062Y302883D01*
X380423Y302807D01*
X380785Y302883D01*
X381043Y303075D01*
X381198Y303382D01*
X381250Y303650D01*
G01X393772Y303792D02*
X394040Y304153D01*
X394270Y304360D01*
X394577Y304463D01*
X394845Y304360D01*
X395037Y304153D01*
X395190Y303843D01*
X395228Y303482D01*
X395190Y303172D01*
X395037Y302862D01*
X394807Y302603D01*
X394538Y302500D01*
X394232Y302603D01*
X393963Y302913D01*
X393810Y303378D01*
X393772Y303895D01*
X393848Y304567D01*
X393963Y304928D01*
X394155Y305290D01*
X394423Y305548D01*
X394692Y305600D01*
X394960Y305497D01*
X395152Y305238D01*
G01X384450Y302500D02*
Y305600D01*
X383990Y304980D01*
G01Y302500D02*
X384910D01*
G01X387550Y305600D02*
X387243Y305497D01*
X387013Y305238D01*
X386860Y304928D01*
X386745Y304515D01*
X386707Y304050D01*
X386745Y303585D01*
X386860Y303172D01*
X387013Y302862D01*
X387243Y302603D01*
X387550Y302500D01*
X387857Y302603D01*
X388087Y302862D01*
X388240Y303172D01*
X388355Y303585D01*
X388393Y304050D01*
X388355Y304515D01*
X388240Y304928D01*
X388087Y305238D01*
X387857Y305497D01*
X387550Y305600D01*
G01X389650Y290557D02*
X391872D01*
X392337Y290710D01*
X392647Y291017D01*
X392750Y291400D01*
X392647Y291783D01*
X392337Y292090D01*
X391872Y292243D01*
X389650D01*
G01X390167Y293772D02*
X389857Y294002D01*
X389702Y294270D01*
X389650Y294577D01*
X389753Y294960D01*
X390012Y295228D01*
X390322Y295305D01*
X390632Y295267D01*
X390890Y295113D01*
X391407Y294347D01*
X391768Y294002D01*
X392285Y293772D01*
X392750Y293695D01*
Y295305D01*
G01X389650Y297600D02*
X389753Y297293D01*
X390012Y297063D01*
X390322Y296910D01*
X390735Y296795D01*
X391200Y296757D01*
X391665Y296795D01*
X392078Y296910D01*
X392388Y297063D01*
X392647Y297293D01*
X392750Y297600D01*
X392647Y297907D01*
X392388Y298137D01*
X392078Y298290D01*
X391665Y298405D01*
X391200Y298443D01*
X390735Y298405D01*
X390322Y298290D01*
X390012Y298137D01*
X389753Y297907D01*
X389650Y297600D01*
G01X386693Y310842D02*
X386463Y310997D01*
X386195Y311100D01*
X385888D01*
X385543Y310945D01*
X385275Y310687D01*
X385083Y310377D01*
X384930Y309860D01*
X384892Y309395D01*
X384968Y308930D01*
X385083Y308620D01*
X385313Y308310D01*
X385582Y308103D01*
X385850Y308000D01*
X386118D01*
X386387Y308103D01*
X386617Y308258D01*
X386808Y308465D01*
G01X388950Y308000D02*
Y311100D01*
X388490Y310480D01*
G01Y308000D02*
X389410D01*
G01X392050D02*
X392318Y308052D01*
X392625Y308207D01*
X392817Y308465D01*
X392893Y308827D01*
X392817Y309188D01*
X392587Y309498D01*
X392242Y309653D01*
X391858D01*
X391628Y309757D01*
X391437Y310015D01*
X391360Y310377D01*
X391475Y310738D01*
X391743Y310997D01*
X392050Y311100D01*
X392357Y310997D01*
X392625Y310738D01*
X392740Y310377D01*
X392663Y310015D01*
X392472Y309757D01*
X392242Y309653D01*
X391858D01*
X391513Y309498D01*
X391283Y309188D01*
X391207Y308827D01*
X391283Y308465D01*
X391475Y308207D01*
X391782Y308052D01*
X392050Y308000D01*
G01X395610D02*
Y311100D01*
X394192Y308878D01*
X396108D01*
G01X393983Y328066D02*
Y331166D01*
X394942D01*
X395248Y331011D01*
X395440Y330804D01*
X395517Y330391D01*
X395440Y329978D01*
X395210Y329719D01*
X394942Y329564D01*
X393983D01*
G01X394942D02*
X395517Y328066D01*
G01X398310D02*
Y331166D01*
X396892Y328944D01*
X398808D01*
G01X400222Y329358D02*
X400490Y329719D01*
X400720Y329926D01*
X401027Y330029D01*
X401295Y329926D01*
X401487Y329719D01*
X401640Y329409D01*
X401678Y329048D01*
X401640Y328738D01*
X401487Y328428D01*
X401257Y328169D01*
X400988Y328066D01*
X400682Y328169D01*
X400413Y328479D01*
X400260Y328944D01*
X400222Y329461D01*
X400298Y330133D01*
X400413Y330494D01*
X400605Y330856D01*
X400873Y331114D01*
X401142Y331166D01*
X401410Y331063D01*
X401602Y330804D01*
G01X404050Y328066D02*
Y331166D01*
X403590Y330546D01*
G01Y328066D02*
X404510D01*
G01X393983Y322866D02*
Y325966D01*
X394942D01*
X395248Y325811D01*
X395440Y325604D01*
X395517Y325191D01*
X395440Y324778D01*
X395210Y324519D01*
X394942Y324364D01*
X393983D01*
G01X394942D02*
X395517Y322866D01*
G01X398310D02*
Y325966D01*
X396892Y323744D01*
X398808D01*
G01X400222Y324158D02*
X400490Y324519D01*
X400720Y324726D01*
X401027Y324829D01*
X401295Y324726D01*
X401487Y324519D01*
X401640Y324209D01*
X401678Y323848D01*
X401640Y323538D01*
X401487Y323228D01*
X401257Y322969D01*
X400988Y322866D01*
X400682Y322969D01*
X400413Y323279D01*
X400260Y323744D01*
X400222Y324261D01*
X400298Y324933D01*
X400413Y325294D01*
X400605Y325656D01*
X400873Y325914D01*
X401142Y325966D01*
X401410Y325863D01*
X401602Y325604D01*
G01X403322Y325449D02*
X403552Y325759D01*
X403820Y325914D01*
X404127Y325966D01*
X404510Y325863D01*
X404778Y325604D01*
X404855Y325294D01*
X404817Y324984D01*
X404663Y324726D01*
X403897Y324209D01*
X403552Y323848D01*
X403322Y323331D01*
X403245Y322866D01*
X404855D01*
G01X395756Y336748D02*
X392656D01*
X394878Y335330D01*
Y337246D01*
G01X388034Y339083D02*
X384934D01*
Y340042D01*
X385089Y340348D01*
X385296Y340540D01*
X385709Y340617D01*
X386122Y340540D01*
X386381Y340310D01*
X386536Y340042D01*
Y339083D01*
G01Y340042D02*
X388034Y340617D01*
G01Y343410D02*
X384934D01*
X387156Y341992D01*
Y343908D01*
G01X386742Y345322D02*
X386381Y345590D01*
X386174Y345820D01*
X386071Y346127D01*
X386174Y346395D01*
X386381Y346587D01*
X386691Y346740D01*
X387052Y346778D01*
X387362Y346740D01*
X387672Y346587D01*
X387931Y346357D01*
X388034Y346088D01*
X387931Y345782D01*
X387621Y345513D01*
X387156Y345360D01*
X386639Y345322D01*
X385967Y345398D01*
X385606Y345513D01*
X385244Y345705D01*
X384986Y345973D01*
X384934Y346242D01*
X385037Y346510D01*
X385296Y346702D01*
G01X388034Y349610D02*
X384934D01*
X387156Y348192D01*
Y350108D01*
G01X395180Y351314D02*
X395542Y351544D01*
X395748Y351850D01*
X395800Y352195D01*
X395748Y352502D01*
X395490Y352809D01*
X395180Y353000D01*
X394870Y353039D01*
X394508Y352962D01*
X394250Y352694D01*
X394147Y352425D01*
Y352080D01*
G01Y352425D02*
X393992Y352655D01*
X393733Y352847D01*
X393423Y352924D01*
X393113Y352847D01*
X392855Y352655D01*
X392700Y352310D01*
X392752Y351965D01*
X392958Y351620D01*
G01X379083Y379950D02*
Y383050D01*
X380042D01*
X380348Y382895D01*
X380540Y382688D01*
X380617Y382275D01*
X380540Y381862D01*
X380310Y381603D01*
X380042Y381448D01*
X379083D01*
G01X380042D02*
X380617Y379950D01*
G01X383410D02*
Y383050D01*
X381992Y380828D01*
X383908D01*
G01X386510Y379950D02*
Y383050D01*
X385092Y380828D01*
X387008D01*
G01X389150Y379950D02*
X389418Y380002D01*
X389725Y380157D01*
X389917Y380415D01*
X389993Y380777D01*
X389917Y381138D01*
X389687Y381448D01*
X389342Y381603D01*
X388958D01*
X388728Y381707D01*
X388537Y381965D01*
X388460Y382327D01*
X388575Y382688D01*
X388843Y382947D01*
X389150Y383050D01*
X389457Y382947D01*
X389725Y382688D01*
X389840Y382327D01*
X389763Y381965D01*
X389572Y381707D01*
X389342Y381603D01*
X388958D01*
X388613Y381448D01*
X388383Y381138D01*
X388307Y380777D01*
X388383Y380415D01*
X388575Y380157D01*
X388882Y380002D01*
X389150Y379950D01*
G01X379083Y374450D02*
Y377550D01*
X380042D01*
X380348Y377395D01*
X380540Y377188D01*
X380617Y376775D01*
X380540Y376362D01*
X380310Y376103D01*
X380042Y375948D01*
X379083D01*
G01X380042D02*
X380617Y374450D01*
G01X383410D02*
Y377550D01*
X381992Y375328D01*
X383908D01*
G01X386510Y374450D02*
Y377550D01*
X385092Y375328D01*
X387008D01*
G01X388498Y374812D02*
X388767Y374553D01*
X389073Y374450D01*
X389380Y374553D01*
X389648Y374863D01*
X389840Y375328D01*
X389917Y375793D01*
Y376362D01*
X389840Y376827D01*
X389648Y377240D01*
X389418Y377447D01*
X389150Y377550D01*
X388843Y377447D01*
X388613Y377240D01*
X388460Y376930D01*
X388383Y376517D01*
X388460Y376155D01*
X388652Y375793D01*
X388882Y375587D01*
X389150Y375535D01*
X389457Y375638D01*
X389687Y375897D01*
X389917Y376362D01*
G01X392850Y383550D02*
Y380450D01*
G01X391968Y383550D02*
X393732D01*
G01X395183Y380450D02*
Y383550D01*
X396103D01*
X396410Y383395D01*
X396640Y383033D01*
X396717Y382620D01*
X396640Y382207D01*
X396448Y381897D01*
X396103Y381742D01*
X395183D01*
G01X399050Y380450D02*
Y383550D01*
X398590Y382930D01*
G01Y380450D02*
X399510D01*
G01X402610D02*
Y383550D01*
X401192Y381328D01*
X403108D01*
G01X407207Y68509D02*
X407437Y68147D01*
X407743Y67941D01*
X408088Y67889D01*
X408395Y67941D01*
X408702Y68199D01*
X408893Y68509D01*
X408932Y68819D01*
X408855Y69181D01*
X408587Y69439D01*
X408318Y69542D01*
X407973D01*
G01X408318D02*
X408548Y69697D01*
X408740Y69956D01*
X408817Y70266D01*
X408740Y70576D01*
X408548Y70834D01*
X408203Y70989D01*
X407858Y70937D01*
X407513Y70731D01*
G01X406083Y94500D02*
Y97600D01*
X407042D01*
X407348Y97445D01*
X407540Y97238D01*
X407617Y96825D01*
X407540Y96412D01*
X407310Y96153D01*
X407042Y95998D01*
X406083D01*
G01X407042D02*
X407617Y94500D01*
G01X409222Y97083D02*
X409452Y97393D01*
X409720Y97548D01*
X410027Y97600D01*
X410410Y97497D01*
X410678Y97238D01*
X410755Y96928D01*
X410717Y96618D01*
X410563Y96360D01*
X409797Y95843D01*
X409452Y95482D01*
X409222Y94965D01*
X409145Y94500D01*
X410755D01*
G01X413510D02*
Y97600D01*
X412092Y95378D01*
X414008D01*
G01X415422Y97083D02*
X415652Y97393D01*
X415920Y97548D01*
X416227Y97600D01*
X416610Y97497D01*
X416878Y97238D01*
X416955Y96928D01*
X416917Y96618D01*
X416763Y96360D01*
X415997Y95843D01*
X415652Y95482D01*
X415422Y94965D01*
X415345Y94500D01*
X416955D01*
G01X394083D02*
Y97600D01*
X395042D01*
X395348Y97445D01*
X395540Y97238D01*
X395617Y96825D01*
X395540Y96412D01*
X395310Y96153D01*
X395042Y95998D01*
X394083D01*
G01X395042D02*
X395617Y94500D01*
G01X397222Y97083D02*
X397452Y97393D01*
X397720Y97548D01*
X398027Y97600D01*
X398410Y97497D01*
X398678Y97238D01*
X398755Y96928D01*
X398717Y96618D01*
X398563Y96360D01*
X397797Y95843D01*
X397452Y95482D01*
X397222Y94965D01*
X397145Y94500D01*
X398755D01*
G01X401510D02*
Y97600D01*
X400092Y95378D01*
X402008D01*
G01X404150Y97600D02*
X403843Y97497D01*
X403613Y97238D01*
X403460Y96928D01*
X403345Y96515D01*
X403307Y96050D01*
X403345Y95585D01*
X403460Y95172D01*
X403613Y94862D01*
X403843Y94603D01*
X404150Y94500D01*
X404457Y94603D01*
X404687Y94862D01*
X404840Y95172D01*
X404955Y95585D01*
X404993Y96050D01*
X404955Y96515D01*
X404840Y96928D01*
X404687Y97238D01*
X404457Y97497D01*
X404150Y97600D01*
G01X399550Y80950D02*
X398155D01*
X396450Y80183D01*
G01Y81717D02*
X398155Y80950D01*
G01X399550Y84510D02*
X396450D01*
X398672Y83092D01*
Y85008D01*
G01X399708Y100693D02*
X399553Y100463D01*
X399450Y100195D01*
Y99888D01*
X399605Y99543D01*
X399863Y99275D01*
X400173Y99083D01*
X400690Y98930D01*
X401155Y98892D01*
X401620Y98968D01*
X401930Y99083D01*
X402240Y99313D01*
X402447Y99582D01*
X402550Y99850D01*
Y100118D01*
X402447Y100387D01*
X402292Y100617D01*
X402085Y100808D01*
G01X399967Y102222D02*
X399657Y102452D01*
X399502Y102720D01*
X399450Y103027D01*
X399553Y103410D01*
X399812Y103678D01*
X400122Y103755D01*
X400432Y103717D01*
X400690Y103563D01*
X401207Y102797D01*
X401568Y102452D01*
X402085Y102222D01*
X402550Y102145D01*
Y103755D01*
G01X402085Y105207D02*
X402343Y105437D01*
X402498Y105705D01*
X402550Y106050D01*
X402447Y106395D01*
X402240Y106663D01*
X401878Y106855D01*
X401465Y106893D01*
X401052Y106817D01*
X400793Y106625D01*
X400587Y106357D01*
X400535Y106088D01*
X400587Y105820D01*
X400793Y105475D01*
X399450Y105590D01*
Y106625D01*
G01X402550Y109610D02*
X399450D01*
X401672Y108192D01*
Y110108D01*
G01X404208Y100693D02*
X404053Y100463D01*
X403950Y100195D01*
Y99888D01*
X404105Y99543D01*
X404363Y99275D01*
X404673Y99083D01*
X405190Y98930D01*
X405655Y98892D01*
X406120Y98968D01*
X406430Y99083D01*
X406740Y99313D01*
X406947Y99582D01*
X407050Y99850D01*
Y100118D01*
X406947Y100387D01*
X406792Y100617D01*
X406585Y100808D01*
G01X404467Y102222D02*
X404157Y102452D01*
X404002Y102720D01*
X403950Y103027D01*
X404053Y103410D01*
X404312Y103678D01*
X404622Y103755D01*
X404932Y103717D01*
X405190Y103563D01*
X405707Y102797D01*
X406068Y102452D01*
X406585Y102222D01*
X407050Y102145D01*
Y103755D01*
G01X406585Y105207D02*
X406843Y105437D01*
X406998Y105705D01*
X407050Y106050D01*
X406947Y106395D01*
X406740Y106663D01*
X406378Y106855D01*
X405965Y106893D01*
X405552Y106817D01*
X405293Y106625D01*
X405087Y106357D01*
X405035Y106088D01*
X405087Y105820D01*
X405293Y105475D01*
X403950Y105590D01*
Y106625D01*
G01X406430Y108307D02*
X406792Y108537D01*
X406998Y108843D01*
X407050Y109188D01*
X406998Y109495D01*
X406740Y109802D01*
X406430Y109993D01*
X406120Y110032D01*
X405758Y109955D01*
X405500Y109687D01*
X405397Y109418D01*
Y109073D01*
G01Y109418D02*
X405242Y109648D01*
X404983Y109840D01*
X404673Y109917D01*
X404363Y109840D01*
X404105Y109648D01*
X403950Y109303D01*
X404002Y108958D01*
X404208Y108613D01*
G01X397191Y126593D02*
X397036Y126363D01*
X396933Y126095D01*
Y125788D01*
X397088Y125443D01*
X397346Y125175D01*
X397656Y124983D01*
X398173Y124830D01*
X398638Y124792D01*
X399103Y124868D01*
X399413Y124983D01*
X399723Y125213D01*
X399930Y125482D01*
X400033Y125750D01*
Y126018D01*
X399930Y126287D01*
X399775Y126517D01*
X399568Y126708D01*
G01X405033Y121907D02*
X401933D01*
Y122673D01*
X402088Y122980D01*
X402295Y123210D01*
X402605Y123402D01*
X402966Y123555D01*
X403483Y123593D01*
X404000Y123555D01*
X404361Y123402D01*
X404671Y123210D01*
X404878Y122980D01*
X405033Y122673D01*
Y121907D01*
G01X409533Y126517D02*
Y124983D01*
X406433D01*
Y126517D01*
G01X407931Y125903D02*
Y124983D01*
G01X413533Y122022D02*
X410433D01*
Y123478D01*
G01X411931Y122942D02*
Y122022D01*
G01X404218Y247683D02*
X401118D01*
Y248642D01*
X401273Y248948D01*
X401480Y249140D01*
X401893Y249217D01*
X402306Y249140D01*
X402565Y248910D01*
X402720Y248642D01*
Y247683D01*
G01Y248642D02*
X404218Y249217D01*
G01X401635Y250822D02*
X401325Y251052D01*
X401170Y251320D01*
X401118Y251627D01*
X401221Y252010D01*
X401480Y252278D01*
X401790Y252355D01*
X402100Y252317D01*
X402358Y252163D01*
X402875Y251397D01*
X403236Y251052D01*
X403753Y250822D01*
X404218Y250745D01*
Y252355D01*
G01X403856Y253998D02*
X404115Y254267D01*
X404218Y254573D01*
X404115Y254880D01*
X403805Y255148D01*
X403340Y255340D01*
X402875Y255417D01*
X402306D01*
X401841Y255340D01*
X401428Y255148D01*
X401221Y254918D01*
X401118Y254650D01*
X401221Y254343D01*
X401428Y254113D01*
X401738Y253960D01*
X402151Y253883D01*
X402513Y253960D01*
X402875Y254152D01*
X403081Y254382D01*
X403133Y254650D01*
X403030Y254957D01*
X402771Y255187D01*
X402306Y255417D01*
G01X401635Y257022D02*
X401325Y257252D01*
X401170Y257520D01*
X401118Y257827D01*
X401221Y258210D01*
X401480Y258478D01*
X401790Y258555D01*
X402100Y258517D01*
X402358Y258363D01*
X402875Y257597D01*
X403236Y257252D01*
X403753Y257022D01*
X404218Y256945D01*
Y258555D01*
G01X398318Y247683D02*
X395218D01*
Y248642D01*
X395373Y248948D01*
X395580Y249140D01*
X395993Y249217D01*
X396406Y249140D01*
X396665Y248910D01*
X396820Y248642D01*
Y247683D01*
G01Y248642D02*
X398318Y249217D01*
G01Y251550D02*
X395218D01*
X395838Y251090D01*
G01X398318D02*
Y252010D01*
G01Y254573D02*
X397646Y254650D01*
X397078Y254765D01*
X396561Y254918D01*
X395993Y255110D01*
X395218Y255417D01*
Y253883D01*
G01Y257750D02*
X395321Y257443D01*
X395580Y257213D01*
X395890Y257060D01*
X396303Y256945D01*
X396768Y256907D01*
X397233Y256945D01*
X397646Y257060D01*
X397956Y257213D01*
X398215Y257443D01*
X398318Y257750D01*
X398215Y258057D01*
X397956Y258287D01*
X397646Y258440D01*
X397233Y258555D01*
X396768Y258593D01*
X396303Y258555D01*
X395890Y258440D01*
X395580Y258287D01*
X395321Y258057D01*
X395218Y257750D01*
G01X410334Y247683D02*
X407234D01*
Y248642D01*
X407389Y248948D01*
X407596Y249140D01*
X408009Y249217D01*
X408422Y249140D01*
X408681Y248910D01*
X408836Y248642D01*
Y247683D01*
G01Y248642D02*
X410334Y249217D01*
G01X409714Y250707D02*
X410076Y250937D01*
X410282Y251243D01*
X410334Y251588D01*
X410282Y251895D01*
X410024Y252202D01*
X409714Y252393D01*
X409404Y252432D01*
X409042Y252355D01*
X408784Y252087D01*
X408681Y251818D01*
Y251473D01*
G01Y251818D02*
X408526Y252048D01*
X408267Y252240D01*
X407957Y252317D01*
X407647Y252240D01*
X407389Y252048D01*
X407234Y251703D01*
X407286Y251358D01*
X407492Y251013D01*
G01X407234Y254650D02*
X407337Y254343D01*
X407596Y254113D01*
X407906Y253960D01*
X408319Y253845D01*
X408784Y253807D01*
X409249Y253845D01*
X409662Y253960D01*
X409972Y254113D01*
X410231Y254343D01*
X410334Y254650D01*
X410231Y254957D01*
X409972Y255187D01*
X409662Y255340D01*
X409249Y255455D01*
X408784Y255493D01*
X408319Y255455D01*
X407906Y255340D01*
X407596Y255187D01*
X407337Y254957D01*
X407234Y254650D01*
G01X410334Y257750D02*
X410282Y258018D01*
X410127Y258325D01*
X409869Y258517D01*
X409507Y258593D01*
X409146Y258517D01*
X408836Y258287D01*
X408681Y257942D01*
Y257558D01*
X408577Y257328D01*
X408319Y257137D01*
X407957Y257060D01*
X407596Y257175D01*
X407337Y257443D01*
X407234Y257750D01*
X407337Y258057D01*
X407596Y258325D01*
X407957Y258440D01*
X408319Y258363D01*
X408577Y258172D01*
X408681Y257942D01*
Y257558D01*
X408836Y257213D01*
X409146Y256983D01*
X409507Y256907D01*
X409869Y256983D01*
X410127Y257175D01*
X410282Y257482D01*
X410334Y257750D01*
G01X412793Y280492D02*
X412563Y280647D01*
X412295Y280750D01*
X411988D01*
X411643Y280595D01*
X411375Y280337D01*
X411183Y280027D01*
X411030Y279510D01*
X410992Y279045D01*
X411068Y278580D01*
X411183Y278270D01*
X411413Y277960D01*
X411682Y277753D01*
X411950Y277650D01*
X412218D01*
X412487Y277753D01*
X412717Y277908D01*
X412908Y278115D01*
G01X414322Y280233D02*
X414552Y280543D01*
X414820Y280698D01*
X415127Y280750D01*
X415510Y280647D01*
X415778Y280388D01*
X415855Y280078D01*
X415817Y279768D01*
X415663Y279510D01*
X414897Y278993D01*
X414552Y278632D01*
X414322Y278115D01*
X414245Y277650D01*
X415855D01*
G01X417307Y278270D02*
X417537Y277908D01*
X417843Y277702D01*
X418188Y277650D01*
X418495Y277702D01*
X418802Y277960D01*
X418993Y278270D01*
X419032Y278580D01*
X418955Y278942D01*
X418687Y279200D01*
X418418Y279303D01*
X418073D01*
G01X418418D02*
X418648Y279458D01*
X418840Y279717D01*
X418917Y280027D01*
X418840Y280337D01*
X418648Y280595D01*
X418303Y280750D01*
X417958Y280698D01*
X417613Y280492D01*
G01X421173Y277650D02*
X421250Y278322D01*
X421365Y278890D01*
X421518Y279407D01*
X421710Y279975D01*
X422017Y280750D01*
X420483D01*
G01X412893Y286792D02*
X412663Y286947D01*
X412395Y287050D01*
X412088D01*
X411743Y286895D01*
X411475Y286637D01*
X411283Y286327D01*
X411130Y285810D01*
X411092Y285345D01*
X411168Y284880D01*
X411283Y284570D01*
X411513Y284260D01*
X411782Y284053D01*
X412050Y283950D01*
X412318D01*
X412587Y284053D01*
X412817Y284208D01*
X413008Y284415D01*
G01X414422Y286533D02*
X414652Y286843D01*
X414920Y286998D01*
X415227Y287050D01*
X415610Y286947D01*
X415878Y286688D01*
X415955Y286378D01*
X415917Y286068D01*
X415763Y285810D01*
X414997Y285293D01*
X414652Y284932D01*
X414422Y284415D01*
X414345Y283950D01*
X415955D01*
G01X418710D02*
Y287050D01*
X417292Y284828D01*
X419208D01*
G01X421350Y287050D02*
X421043Y286947D01*
X420813Y286688D01*
X420660Y286378D01*
X420545Y285965D01*
X420507Y285500D01*
X420545Y285035D01*
X420660Y284622D01*
X420813Y284312D01*
X421043Y284053D01*
X421350Y283950D01*
X421657Y284053D01*
X421887Y284312D01*
X422040Y284622D01*
X422155Y285035D01*
X422193Y285500D01*
X422155Y285965D01*
X422040Y286378D01*
X421887Y286688D01*
X421657Y286947D01*
X421350Y287050D01*
G01X398157Y286965D02*
X398387Y286707D01*
X398655Y286552D01*
X399000Y286500D01*
X399345Y286603D01*
X399613Y286810D01*
X399805Y287172D01*
X399843Y287585D01*
X399767Y287998D01*
X399575Y288257D01*
X399307Y288463D01*
X399038Y288515D01*
X398770Y288463D01*
X398425Y288257D01*
X398540Y289600D01*
X399575D01*
G01X412893Y294892D02*
X412663Y295047D01*
X412395Y295150D01*
X412088D01*
X411743Y294995D01*
X411475Y294737D01*
X411283Y294427D01*
X411130Y293910D01*
X411092Y293445D01*
X411168Y292980D01*
X411283Y292670D01*
X411513Y292360D01*
X411782Y292153D01*
X412050Y292050D01*
X412318D01*
X412587Y292153D01*
X412817Y292308D01*
X413008Y292515D01*
G01X414422Y294633D02*
X414652Y294943D01*
X414920Y295098D01*
X415227Y295150D01*
X415610Y295047D01*
X415878Y294788D01*
X415955Y294478D01*
X415917Y294168D01*
X415763Y293910D01*
X414997Y293393D01*
X414652Y293032D01*
X414422Y292515D01*
X414345Y292050D01*
X415955D01*
G01X417407Y292670D02*
X417637Y292308D01*
X417943Y292102D01*
X418288Y292050D01*
X418595Y292102D01*
X418902Y292360D01*
X419093Y292670D01*
X419132Y292980D01*
X419055Y293342D01*
X418787Y293600D01*
X418518Y293703D01*
X418173D01*
G01X418518D02*
X418748Y293858D01*
X418940Y294117D01*
X419017Y294427D01*
X418940Y294737D01*
X418748Y294995D01*
X418403Y295150D01*
X418058Y295098D01*
X417713Y294892D01*
G01X421350Y292050D02*
X421618Y292102D01*
X421925Y292257D01*
X422117Y292515D01*
X422193Y292877D01*
X422117Y293238D01*
X421887Y293548D01*
X421542Y293703D01*
X421158D01*
X420928Y293807D01*
X420737Y294065D01*
X420660Y294427D01*
X420775Y294788D01*
X421043Y295047D01*
X421350Y295150D01*
X421657Y295047D01*
X421925Y294788D01*
X422040Y294427D01*
X421963Y294065D01*
X421772Y293807D01*
X421542Y293703D01*
X421158D01*
X420813Y293548D01*
X420583Y293238D01*
X420507Y292877D01*
X420583Y292515D01*
X420775Y292257D01*
X421082Y292102D01*
X421350Y292050D01*
G01X396908Y305193D02*
X396753Y304963D01*
X396650Y304695D01*
Y304388D01*
X396805Y304043D01*
X397063Y303775D01*
X397373Y303583D01*
X397890Y303430D01*
X398355Y303392D01*
X398820Y303468D01*
X399130Y303583D01*
X399440Y303813D01*
X399647Y304082D01*
X399750Y304350D01*
Y304618D01*
X399647Y304887D01*
X399492Y305117D01*
X399285Y305308D01*
G01X399750Y307450D02*
X396650D01*
X397270Y306990D01*
G01X399750D02*
Y307910D01*
G01X399388Y309898D02*
X399647Y310167D01*
X399750Y310473D01*
X399647Y310780D01*
X399337Y311048D01*
X398872Y311240D01*
X398407Y311317D01*
X397838D01*
X397373Y311240D01*
X396960Y311048D01*
X396753Y310818D01*
X396650Y310550D01*
X396753Y310243D01*
X396960Y310013D01*
X397270Y309860D01*
X397683Y309783D01*
X398045Y309860D01*
X398407Y310052D01*
X398613Y310282D01*
X398665Y310550D01*
X398562Y310857D01*
X398303Y311087D01*
X397838Y311317D01*
G01X396650Y313650D02*
X396753Y313343D01*
X397012Y313113D01*
X397322Y312960D01*
X397735Y312845D01*
X398200Y312807D01*
X398665Y312845D01*
X399078Y312960D01*
X399388Y313113D01*
X399647Y313343D01*
X399750Y313650D01*
X399647Y313957D01*
X399388Y314187D01*
X399078Y314340D01*
X398665Y314455D01*
X398200Y314493D01*
X397735Y314455D01*
X397322Y314340D01*
X397012Y314187D01*
X396753Y313957D01*
X396650Y313650D01*
G01X410900Y305600D02*
X411168Y305652D01*
X411475Y305807D01*
X411667Y306065D01*
X411743Y306427D01*
X411667Y306788D01*
X411437Y307098D01*
X411092Y307253D01*
X410708D01*
X410478Y307357D01*
X410287Y307615D01*
X410210Y307977D01*
X410325Y308338D01*
X410593Y308597D01*
X410900Y308700D01*
X411207Y308597D01*
X411475Y308338D01*
X411590Y307977D01*
X411513Y307615D01*
X411322Y307357D01*
X411092Y307253D01*
X410708D01*
X410363Y307098D01*
X410133Y306788D01*
X410057Y306427D01*
X410133Y306065D01*
X410325Y305807D01*
X410632Y305652D01*
X410900Y305600D01*
G01X406950Y322350D02*
X410050D01*
G01X406950Y321468D02*
Y323232D01*
G01X410050Y324683D02*
X406950D01*
Y325603D01*
X407105Y325910D01*
X407467Y326140D01*
X407880Y326217D01*
X408293Y326140D01*
X408603Y325948D01*
X408758Y325603D01*
Y324683D01*
G01X410050Y328550D02*
X406950D01*
X407570Y328090D01*
G01X410050D02*
Y329010D01*
G01X409430Y330807D02*
X409792Y331037D01*
X409998Y331343D01*
X410050Y331688D01*
X409998Y331995D01*
X409740Y332302D01*
X409430Y332493D01*
X409120Y332532D01*
X408758Y332455D01*
X408500Y332187D01*
X408397Y331918D01*
Y331573D01*
G01Y331918D02*
X408242Y332148D01*
X407983Y332340D01*
X407673Y332417D01*
X407363Y332340D01*
X407105Y332148D01*
X406950Y331803D01*
X407002Y331458D01*
X407208Y331113D01*
G01X400984Y335812D02*
X400623Y336080D01*
X400416Y336310D01*
X400313Y336617D01*
X400416Y336885D01*
X400623Y337077D01*
X400933Y337230D01*
X401294Y337268D01*
X401604Y337230D01*
X401914Y337077D01*
X402173Y336847D01*
X402276Y336578D01*
X402173Y336272D01*
X401863Y336003D01*
X401398Y335850D01*
X400881Y335812D01*
X400209Y335888D01*
X399848Y336003D01*
X399486Y336195D01*
X399228Y336463D01*
X399176Y336732D01*
X399279Y337000D01*
X399538Y337192D01*
G01X409034Y339583D02*
X405934D01*
Y340542D01*
X406089Y340848D01*
X406296Y341040D01*
X406709Y341117D01*
X407122Y341040D01*
X407381Y340810D01*
X407536Y340542D01*
Y339583D01*
G01Y340542D02*
X409034Y341117D01*
G01Y343910D02*
X405934D01*
X408156Y342492D01*
Y344408D01*
G01X407742Y345822D02*
X407381Y346090D01*
X407174Y346320D01*
X407071Y346627D01*
X407174Y346895D01*
X407381Y347087D01*
X407691Y347240D01*
X408052Y347278D01*
X408362Y347240D01*
X408672Y347087D01*
X408931Y346857D01*
X409034Y346588D01*
X408931Y346282D01*
X408621Y346013D01*
X408156Y345860D01*
X407639Y345822D01*
X406967Y345898D01*
X406606Y346013D01*
X406244Y346205D01*
X405986Y346473D01*
X405934Y346742D01*
X406037Y347010D01*
X406296Y347202D01*
G01X408569Y348807D02*
X408827Y349037D01*
X408982Y349305D01*
X409034Y349650D01*
X408931Y349995D01*
X408724Y350263D01*
X408362Y350455D01*
X407949Y350493D01*
X407536Y350417D01*
X407277Y350225D01*
X407071Y349957D01*
X407019Y349688D01*
X407071Y349420D01*
X407277Y349075D01*
X405934Y349190D01*
Y350225D01*
G01X396968Y340357D02*
X399190D01*
X399655Y340510D01*
X399965Y340817D01*
X400068Y341200D01*
X399965Y341583D01*
X399655Y341890D01*
X399190Y342043D01*
X396968D01*
G01X399448Y343457D02*
X399810Y343687D01*
X400016Y343993D01*
X400068Y344338D01*
X400016Y344645D01*
X399758Y344952D01*
X399448Y345143D01*
X399138Y345182D01*
X398776Y345105D01*
X398518Y344837D01*
X398415Y344568D01*
Y344223D01*
G01Y344568D02*
X398260Y344798D01*
X398001Y344990D01*
X397691Y345067D01*
X397381Y344990D01*
X397123Y344798D01*
X396968Y344453D01*
X397020Y344108D01*
X397226Y343763D01*
G01X399706Y346748D02*
X399965Y347017D01*
X400068Y347323D01*
X399965Y347630D01*
X399655Y347898D01*
X399190Y348090D01*
X398725Y348167D01*
X398156D01*
X397691Y348090D01*
X397278Y347898D01*
X397071Y347668D01*
X396968Y347400D01*
X397071Y347093D01*
X397278Y346863D01*
X397588Y346710D01*
X398001Y346633D01*
X398363Y346710D01*
X398725Y346902D01*
X398931Y347132D01*
X398983Y347400D01*
X398880Y347707D01*
X398621Y347937D01*
X398156Y348167D01*
G01X397500Y357500D02*
X397768Y357552D01*
X398075Y357707D01*
X398267Y357965D01*
X398343Y358327D01*
X398267Y358688D01*
X398037Y358998D01*
X397692Y359153D01*
X397308D01*
X397078Y359257D01*
X396887Y359515D01*
X396810Y359877D01*
X396925Y360238D01*
X397193Y360497D01*
X397500Y360600D01*
X397807Y360497D01*
X398075Y360238D01*
X398190Y359877D01*
X398113Y359515D01*
X397922Y359257D01*
X397692Y359153D01*
X397308D01*
X396963Y358998D01*
X396733Y358688D01*
X396657Y358327D01*
X396733Y357965D01*
X396925Y357707D01*
X397232Y357552D01*
X397500Y357500D01*
G01X406216Y385455D02*
X406446Y385765D01*
X406714Y385920D01*
X407021Y385972D01*
X407404Y385869D01*
X407672Y385610D01*
X407749Y385300D01*
X407711Y384990D01*
X407557Y384732D01*
X406791Y384215D01*
X406446Y383854D01*
X406216Y383337D01*
X406139Y382872D01*
X407749D01*
G01X409316Y385455D02*
X409546Y385765D01*
X409814Y385920D01*
X410121Y385972D01*
X410504Y385869D01*
X410772Y385610D01*
X410849Y385300D01*
X410811Y384990D01*
X410657Y384732D01*
X409891Y384215D01*
X409546Y383854D01*
X409316Y383337D01*
X409239Y382872D01*
X410849D01*
G01X396290Y404538D02*
Y407638D01*
X395830Y407018D01*
G01Y404538D02*
X396750D01*
G01X398547Y405003D02*
X398777Y404745D01*
X399045Y404590D01*
X399390Y404538D01*
X399735Y404641D01*
X400003Y404848D01*
X400195Y405210D01*
X400233Y405623D01*
X400157Y406036D01*
X399965Y406295D01*
X399697Y406501D01*
X399428Y406553D01*
X399160Y406501D01*
X398815Y406295D01*
X398930Y407638D01*
X399965D01*
G01X395562Y395309D02*
X395792Y395619D01*
X396060Y395774D01*
X396367Y395826D01*
X396750Y395723D01*
X397018Y395464D01*
X397095Y395154D01*
X397057Y394844D01*
X396903Y394586D01*
X396137Y394069D01*
X395792Y393708D01*
X395562Y393191D01*
X395485Y392726D01*
X397095D01*
G01X399390D02*
Y395826D01*
X398930Y395206D01*
G01Y392726D02*
X399850D01*
G01X409007Y401782D02*
Y399560D01*
X409160Y399095D01*
X409467Y398785D01*
X409850Y398682D01*
X410233Y398785D01*
X410540Y399095D01*
X410693Y399560D01*
Y401782D01*
G01X412107Y399302D02*
X412337Y398940D01*
X412643Y398734D01*
X412988Y398682D01*
X413295Y398734D01*
X413602Y398992D01*
X413793Y399302D01*
X413832Y399612D01*
X413755Y399974D01*
X413487Y400232D01*
X413218Y400335D01*
X412873D01*
G01X413218D02*
X413448Y400490D01*
X413640Y400749D01*
X413717Y401059D01*
X413640Y401369D01*
X413448Y401627D01*
X413103Y401782D01*
X412758Y401730D01*
X412413Y401524D01*
G01X415207Y399302D02*
X415437Y398940D01*
X415743Y398734D01*
X416088Y398682D01*
X416395Y398734D01*
X416702Y398992D01*
X416893Y399302D01*
X416932Y399612D01*
X416855Y399974D01*
X416587Y400232D01*
X416318Y400335D01*
X415973D01*
G01X416318D02*
X416548Y400490D01*
X416740Y400749D01*
X416817Y401059D01*
X416740Y401369D01*
X416548Y401627D01*
X416203Y401782D01*
X415858Y401730D01*
X415513Y401524D01*
G01X406944Y414494D02*
Y417594D01*
X406484Y416974D01*
G01Y414494D02*
X407404D01*
G01X410504D02*
Y417594D01*
X409086Y415372D01*
X411002D01*
G01X427500Y75000D02*
Y78100D01*
X427040Y77480D01*
G01Y75000D02*
X427960D01*
G01X418950Y72850D02*
X422050D01*
G01X418950Y71968D02*
Y73732D01*
G01X422050Y75183D02*
X418950D01*
Y76103D01*
X419105Y76410D01*
X419467Y76640D01*
X419880Y76717D01*
X420293Y76640D01*
X420603Y76448D01*
X420758Y76103D01*
Y75183D01*
G01X422050Y79510D02*
X418950D01*
X421172Y78092D01*
Y80008D01*
G01X421688Y81498D02*
X421947Y81767D01*
X422050Y82073D01*
X421947Y82380D01*
X421637Y82648D01*
X421172Y82840D01*
X420707Y82917D01*
X420138D01*
X419673Y82840D01*
X419260Y82648D01*
X419053Y82418D01*
X418950Y82150D01*
X419053Y81843D01*
X419260Y81613D01*
X419570Y81460D01*
X419983Y81383D01*
X420345Y81460D01*
X420707Y81652D01*
X420913Y81882D01*
X420965Y82150D01*
X420862Y82457D01*
X420603Y82687D01*
X420138Y82917D01*
G01X422050Y84583D02*
X418950D01*
Y85542D01*
X419105Y85848D01*
X419312Y86040D01*
X419725Y86117D01*
X420138Y86040D01*
X420397Y85810D01*
X420552Y85542D01*
Y84583D01*
G01Y85542D02*
X422050Y86117D01*
G01X419467Y87722D02*
X419157Y87952D01*
X419002Y88220D01*
X418950Y88527D01*
X419053Y88910D01*
X419312Y89178D01*
X419622Y89255D01*
X419932Y89217D01*
X420190Y89063D01*
X420707Y88297D01*
X421068Y87952D01*
X421585Y87722D01*
X422050Y87645D01*
Y89255D01*
G01X421430Y90707D02*
X421792Y90937D01*
X421998Y91243D01*
X422050Y91588D01*
X421998Y91895D01*
X421740Y92202D01*
X421430Y92393D01*
X421120Y92432D01*
X420758Y92355D01*
X420500Y92087D01*
X420397Y91818D01*
Y91473D01*
G01Y91818D02*
X420242Y92048D01*
X419983Y92240D01*
X419673Y92317D01*
X419363Y92240D01*
X419105Y92048D01*
X418950Y91703D01*
X419002Y91358D01*
X419208Y91013D01*
G01X421585Y93807D02*
X421843Y94037D01*
X421998Y94305D01*
X422050Y94650D01*
X421947Y94995D01*
X421740Y95263D01*
X421378Y95455D01*
X420965Y95493D01*
X420552Y95417D01*
X420293Y95225D01*
X420087Y94957D01*
X420035Y94688D01*
X420087Y94420D01*
X420293Y94075D01*
X418950Y94190D01*
Y95225D01*
G01X427583Y95000D02*
Y98100D01*
X428542D01*
X428848Y97945D01*
X429040Y97738D01*
X429117Y97325D01*
X429040Y96912D01*
X428810Y96653D01*
X428542Y96498D01*
X427583D01*
G01X428542D02*
X429117Y95000D01*
G01X430722Y97583D02*
X430952Y97893D01*
X431220Y98048D01*
X431527Y98100D01*
X431910Y97997D01*
X432178Y97738D01*
X432255Y97428D01*
X432217Y97118D01*
X432063Y96860D01*
X431297Y96343D01*
X430952Y95982D01*
X430722Y95465D01*
X430645Y95000D01*
X432255D01*
G01X433707Y95620D02*
X433937Y95258D01*
X434243Y95052D01*
X434588Y95000D01*
X434895Y95052D01*
X435202Y95310D01*
X435393Y95620D01*
X435432Y95930D01*
X435355Y96292D01*
X435087Y96550D01*
X434818Y96653D01*
X434473D01*
G01X434818D02*
X435048Y96808D01*
X435240Y97067D01*
X435317Y97377D01*
X435240Y97687D01*
X435048Y97945D01*
X434703Y98100D01*
X434358Y98048D01*
X434013Y97842D01*
G01X436998Y95362D02*
X437267Y95103D01*
X437573Y95000D01*
X437880Y95103D01*
X438148Y95413D01*
X438340Y95878D01*
X438417Y96343D01*
Y96912D01*
X438340Y97377D01*
X438148Y97790D01*
X437918Y97997D01*
X437650Y98100D01*
X437343Y97997D01*
X437113Y97790D01*
X436960Y97480D01*
X436883Y97067D01*
X436960Y96705D01*
X437152Y96343D01*
X437382Y96137D01*
X437650Y96085D01*
X437957Y96188D01*
X438187Y96447D01*
X438417Y96912D01*
G01X425272Y94742D02*
X425540Y95103D01*
X425770Y95310D01*
X426077Y95413D01*
X426345Y95310D01*
X426537Y95103D01*
X426690Y94793D01*
X426728Y94432D01*
X426690Y94122D01*
X426537Y93812D01*
X426307Y93553D01*
X426038Y93450D01*
X425732Y93553D01*
X425463Y93863D01*
X425310Y94328D01*
X425272Y94845D01*
X425348Y95517D01*
X425463Y95878D01*
X425655Y96240D01*
X425923Y96498D01*
X426192Y96550D01*
X426460Y96447D01*
X426652Y96188D01*
G01X413960Y88500D02*
Y91600D01*
X412542Y89378D01*
X414458D01*
G01X425583Y110950D02*
Y114050D01*
X426542D01*
X426848Y113895D01*
X427040Y113688D01*
X427117Y113275D01*
X427040Y112862D01*
X426810Y112603D01*
X426542Y112448D01*
X425583D01*
G01X426542D02*
X427117Y110950D01*
G01X428607Y111570D02*
X428837Y111208D01*
X429143Y111002D01*
X429488Y110950D01*
X429795Y111002D01*
X430102Y111260D01*
X430293Y111570D01*
X430332Y111880D01*
X430255Y112242D01*
X429987Y112500D01*
X429718Y112603D01*
X429373D01*
G01X429718D02*
X429948Y112758D01*
X430140Y113017D01*
X430217Y113327D01*
X430140Y113637D01*
X429948Y113895D01*
X429603Y114050D01*
X429258Y113998D01*
X428913Y113792D01*
G01X431822Y112242D02*
X432090Y112603D01*
X432320Y112810D01*
X432627Y112913D01*
X432895Y112810D01*
X433087Y112603D01*
X433240Y112293D01*
X433278Y111932D01*
X433240Y111622D01*
X433087Y111312D01*
X432857Y111053D01*
X432588Y110950D01*
X432282Y111053D01*
X432013Y111363D01*
X431860Y111828D01*
X431822Y112345D01*
X431898Y113017D01*
X432013Y113378D01*
X432205Y113740D01*
X432473Y113998D01*
X432742Y114050D01*
X433010Y113947D01*
X433202Y113688D01*
G01X435650Y114050D02*
X435343Y113947D01*
X435113Y113688D01*
X434960Y113378D01*
X434845Y112965D01*
X434807Y112500D01*
X434845Y112035D01*
X434960Y111622D01*
X435113Y111312D01*
X435343Y111053D01*
X435650Y110950D01*
X435957Y111053D01*
X436187Y111312D01*
X436340Y111622D01*
X436455Y112035D01*
X436493Y112500D01*
X436455Y112965D01*
X436340Y113378D01*
X436187Y113688D01*
X435957Y113947D01*
X435650Y114050D01*
G01X415983Y125980D02*
Y126747D01*
X416913D01*
X417223Y126517D01*
X417430Y126248D01*
X417533Y125865D01*
X417430Y125482D01*
X417223Y125213D01*
X416913Y124983D01*
X416551Y124830D01*
X416138Y124753D01*
X415776D01*
X415466Y124830D01*
X415105Y124983D01*
X414795Y125213D01*
X414588Y125443D01*
X414433Y125750D01*
Y126018D01*
X414536Y126325D01*
X414743Y126555D01*
G01X421533Y121945D02*
X418433D01*
G01Y123555D02*
X421533D01*
G01X419983D02*
Y121945D01*
G01X424413Y124983D02*
X424723Y125175D01*
X424930Y125405D01*
X425033Y125673D01*
X424930Y125980D01*
X424723Y126210D01*
X424413Y126440D01*
X424000Y126517D01*
X421933D01*
G01X428033Y121907D02*
X424933D01*
G01Y123363D02*
X426845Y121907D01*
G01X428033Y123593D02*
X425966Y122558D01*
G01X428433Y124983D02*
X431533D01*
Y126517D01*
G01X426557Y172600D02*
Y170378D01*
X426710Y169913D01*
X427017Y169603D01*
X427400Y169500D01*
X427783Y169603D01*
X428090Y169913D01*
X428243Y170378D01*
Y172600D01*
G01X429772Y172083D02*
X430002Y172393D01*
X430270Y172548D01*
X430577Y172600D01*
X430960Y172497D01*
X431228Y172238D01*
X431305Y171928D01*
X431267Y171618D01*
X431113Y171360D01*
X430347Y170843D01*
X430002Y170482D01*
X429772Y169965D01*
X429695Y169500D01*
X431305D01*
G01X434060D02*
Y172600D01*
X432642Y170378D01*
X434558D01*
G01X421934Y247683D02*
X418834D01*
Y248642D01*
X418989Y248948D01*
X419196Y249140D01*
X419609Y249217D01*
X420022Y249140D01*
X420281Y248910D01*
X420436Y248642D01*
Y247683D01*
G01Y248642D02*
X421934Y249217D01*
G01X421314Y250707D02*
X421676Y250937D01*
X421882Y251243D01*
X421934Y251588D01*
X421882Y251895D01*
X421624Y252202D01*
X421314Y252393D01*
X421004Y252432D01*
X420642Y252355D01*
X420384Y252087D01*
X420281Y251818D01*
Y251473D01*
G01Y251818D02*
X420126Y252048D01*
X419867Y252240D01*
X419557Y252317D01*
X419247Y252240D01*
X418989Y252048D01*
X418834Y251703D01*
X418886Y251358D01*
X419092Y251013D01*
G01X419351Y253922D02*
X419041Y254152D01*
X418886Y254420D01*
X418834Y254727D01*
X418937Y255110D01*
X419196Y255378D01*
X419506Y255455D01*
X419816Y255417D01*
X420074Y255263D01*
X420591Y254497D01*
X420952Y254152D01*
X421469Y253922D01*
X421934Y253845D01*
Y255455D01*
G01X421469Y256907D02*
X421727Y257137D01*
X421882Y257405D01*
X421934Y257750D01*
X421831Y258095D01*
X421624Y258363D01*
X421262Y258555D01*
X420849Y258593D01*
X420436Y258517D01*
X420177Y258325D01*
X419971Y258057D01*
X419919Y257788D01*
X419971Y257520D01*
X420177Y257175D01*
X418834Y257290D01*
Y258325D01*
G01X416034Y247683D02*
X412934D01*
Y248642D01*
X413089Y248948D01*
X413296Y249140D01*
X413709Y249217D01*
X414122Y249140D01*
X414381Y248910D01*
X414536Y248642D01*
Y247683D01*
G01Y248642D02*
X416034Y249217D01*
G01X415414Y250707D02*
X415776Y250937D01*
X415982Y251243D01*
X416034Y251588D01*
X415982Y251895D01*
X415724Y252202D01*
X415414Y252393D01*
X415104Y252432D01*
X414742Y252355D01*
X414484Y252087D01*
X414381Y251818D01*
Y251473D01*
G01Y251818D02*
X414226Y252048D01*
X413967Y252240D01*
X413657Y252317D01*
X413347Y252240D01*
X413089Y252048D01*
X412934Y251703D01*
X412986Y251358D01*
X413192Y251013D01*
G01X413451Y253922D02*
X413141Y254152D01*
X412986Y254420D01*
X412934Y254727D01*
X413037Y255110D01*
X413296Y255378D01*
X413606Y255455D01*
X413916Y255417D01*
X414174Y255263D01*
X414691Y254497D01*
X415052Y254152D01*
X415569Y253922D01*
X416034Y253845D01*
Y255455D01*
G01Y257673D02*
X415362Y257750D01*
X414794Y257865D01*
X414277Y258018D01*
X413709Y258210D01*
X412934Y258517D01*
Y256983D01*
G01X423450Y278450D02*
Y281550D01*
X422990Y280930D01*
G01Y278450D02*
X423910D01*
G01X425822Y281033D02*
X426052Y281343D01*
X426320Y281498D01*
X426627Y281550D01*
X427010Y281447D01*
X427278Y281188D01*
X427355Y280878D01*
X427317Y280568D01*
X427163Y280310D01*
X426397Y279793D01*
X426052Y279432D01*
X425822Y278915D01*
X425745Y278450D01*
X427355D01*
G01X424350Y275550D02*
Y272450D01*
G01X423468Y275550D02*
X425232D01*
G01X426683Y272450D02*
Y275550D01*
X427603D01*
X427910Y275395D01*
X428140Y275033D01*
X428217Y274620D01*
X428140Y274207D01*
X427948Y273897D01*
X427603Y273742D01*
X426683D01*
G01X429707Y272915D02*
X429937Y272657D01*
X430205Y272502D01*
X430550Y272450D01*
X430895Y272553D01*
X431163Y272760D01*
X431355Y273122D01*
X431393Y273535D01*
X431317Y273948D01*
X431125Y274207D01*
X430857Y274413D01*
X430588Y274465D01*
X430320Y274413D01*
X429975Y274207D01*
X430090Y275550D01*
X431125D01*
G01X432807Y273070D02*
X433037Y272708D01*
X433343Y272502D01*
X433688Y272450D01*
X433995Y272502D01*
X434302Y272760D01*
X434493Y273070D01*
X434532Y273380D01*
X434455Y273742D01*
X434187Y274000D01*
X433918Y274103D01*
X433573D01*
G01X433918D02*
X434148Y274258D01*
X434340Y274517D01*
X434417Y274827D01*
X434340Y275137D01*
X434148Y275395D01*
X433803Y275550D01*
X433458Y275498D01*
X433113Y275292D01*
G01X425423Y292450D02*
X425500Y293122D01*
X425615Y293690D01*
X425768Y294207D01*
X425960Y294775D01*
X426267Y295550D01*
X424733D01*
G01X424957Y317666D02*
Y315444D01*
X425110Y314979D01*
X425417Y314669D01*
X425800Y314566D01*
X426183Y314669D01*
X426490Y314979D01*
X426643Y315444D01*
Y317666D01*
G01X428057Y315186D02*
X428287Y314824D01*
X428593Y314618D01*
X428938Y314566D01*
X429245Y314618D01*
X429552Y314876D01*
X429743Y315186D01*
X429782Y315496D01*
X429705Y315858D01*
X429437Y316116D01*
X429168Y316219D01*
X428823D01*
G01X429168D02*
X429398Y316374D01*
X429590Y316633D01*
X429667Y316943D01*
X429590Y317253D01*
X429398Y317511D01*
X429053Y317666D01*
X428708Y317614D01*
X428363Y317408D01*
G01X432000Y314566D02*
X432268Y314618D01*
X432575Y314773D01*
X432767Y315031D01*
X432843Y315393D01*
X432767Y315754D01*
X432537Y316064D01*
X432192Y316219D01*
X431808D01*
X431578Y316323D01*
X431387Y316581D01*
X431310Y316943D01*
X431425Y317304D01*
X431693Y317563D01*
X432000Y317666D01*
X432307Y317563D01*
X432575Y317304D01*
X432690Y316943D01*
X432613Y316581D01*
X432422Y316323D01*
X432192Y316219D01*
X431808D01*
X431463Y316064D01*
X431233Y315754D01*
X431157Y315393D01*
X431233Y315031D01*
X431425Y314773D01*
X431732Y314618D01*
X432000Y314566D01*
G01X420484Y336012D02*
X420123Y336280D01*
X419916Y336510D01*
X419813Y336817D01*
X419916Y337085D01*
X420123Y337277D01*
X420433Y337430D01*
X420794Y337468D01*
X421104Y337430D01*
X421414Y337277D01*
X421673Y337047D01*
X421776Y336778D01*
X421673Y336472D01*
X421363Y336203D01*
X420898Y336050D01*
X420381Y336012D01*
X419709Y336088D01*
X419348Y336203D01*
X418986Y336395D01*
X418728Y336663D01*
X418676Y336932D01*
X418779Y337200D01*
X419038Y337392D01*
G01X415256Y336948D02*
X412156D01*
X414378Y335530D01*
Y337446D01*
G01X416468Y340557D02*
X418690D01*
X419155Y340710D01*
X419465Y341017D01*
X419568Y341400D01*
X419465Y341783D01*
X419155Y342090D01*
X418690Y342243D01*
X416468D01*
G01X419568Y344960D02*
X416468D01*
X418690Y343542D01*
Y345458D01*
G01X416468Y347600D02*
X416571Y347293D01*
X416830Y347063D01*
X417140Y346910D01*
X417553Y346795D01*
X418018Y346757D01*
X418483Y346795D01*
X418896Y346910D01*
X419206Y347063D01*
X419465Y347293D01*
X419568Y347600D01*
X419465Y347907D01*
X419206Y348137D01*
X418896Y348290D01*
X418483Y348405D01*
X418018Y348443D01*
X417553Y348405D01*
X417140Y348290D01*
X416830Y348137D01*
X416571Y347907D01*
X416468Y347600D01*
G01X414680Y351514D02*
X415042Y351744D01*
X415248Y352050D01*
X415300Y352395D01*
X415248Y352702D01*
X414990Y353009D01*
X414680Y353200D01*
X414370Y353239D01*
X414008Y353162D01*
X413750Y352894D01*
X413647Y352625D01*
Y352280D01*
G01Y352625D02*
X413492Y352855D01*
X413233Y353047D01*
X412923Y353124D01*
X412613Y353047D01*
X412355Y352855D01*
X412200Y352510D01*
X412252Y352165D01*
X412458Y351820D01*
G01X411557Y369566D02*
Y367344D01*
X411710Y366879D01*
X412017Y366569D01*
X412400Y366466D01*
X412783Y366569D01*
X413090Y366879D01*
X413243Y367344D01*
Y369566D01*
G01X414657Y367086D02*
X414887Y366724D01*
X415193Y366518D01*
X415538Y366466D01*
X415845Y366518D01*
X416152Y366776D01*
X416343Y367086D01*
X416382Y367396D01*
X416305Y367758D01*
X416037Y368016D01*
X415768Y368119D01*
X415423D01*
G01X415768D02*
X415998Y368274D01*
X416190Y368533D01*
X416267Y368843D01*
X416190Y369153D01*
X415998Y369411D01*
X415653Y369566D01*
X415308Y369514D01*
X414963Y369308D01*
G01X418600Y369566D02*
X418293Y369463D01*
X418063Y369204D01*
X417910Y368894D01*
X417795Y368481D01*
X417757Y368016D01*
X417795Y367551D01*
X417910Y367138D01*
X418063Y366828D01*
X418293Y366569D01*
X418600Y366466D01*
X418907Y366569D01*
X419137Y366828D01*
X419290Y367138D01*
X419405Y367551D01*
X419443Y368016D01*
X419405Y368481D01*
X419290Y368894D01*
X419137Y369204D01*
X418907Y369463D01*
X418600Y369566D01*
G01X418028Y385455D02*
X418258Y385765D01*
X418526Y385920D01*
X418833Y385972D01*
X419216Y385869D01*
X419484Y385610D01*
X419561Y385300D01*
X419523Y384990D01*
X419369Y384732D01*
X418603Y384215D01*
X418258Y383854D01*
X418028Y383337D01*
X417951Y382872D01*
X419561D01*
G01X421856D02*
X422124Y382924D01*
X422431Y383079D01*
X422623Y383337D01*
X422699Y383699D01*
X422623Y384060D01*
X422393Y384370D01*
X422048Y384525D01*
X421664D01*
X421434Y384629D01*
X421243Y384887D01*
X421166Y385249D01*
X421281Y385610D01*
X421549Y385869D01*
X421856Y385972D01*
X422163Y385869D01*
X422431Y385610D01*
X422546Y385249D01*
X422469Y384887D01*
X422278Y384629D01*
X422048Y384525D01*
X421664D01*
X421319Y384370D01*
X421089Y384060D01*
X421013Y383699D01*
X421089Y383337D01*
X421281Y383079D01*
X421588Y382924D01*
X421856Y382872D01*
G01X427450Y380350D02*
X430550D01*
G01X427450Y379468D02*
Y381232D01*
G01X430550Y382683D02*
X427450D01*
Y383603D01*
X427605Y383910D01*
X427967Y384140D01*
X428380Y384217D01*
X428793Y384140D01*
X429103Y383948D01*
X429258Y383603D01*
Y382683D01*
G01X427967Y385822D02*
X427657Y386052D01*
X427502Y386320D01*
X427450Y386627D01*
X427553Y387010D01*
X427812Y387278D01*
X428122Y387355D01*
X428432Y387317D01*
X428690Y387163D01*
X429207Y386397D01*
X429568Y386052D01*
X430085Y385822D01*
X430550Y385745D01*
Y387355D01*
G01X430085Y388807D02*
X430343Y389037D01*
X430498Y389305D01*
X430550Y389650D01*
X430447Y389995D01*
X430240Y390263D01*
X429878Y390455D01*
X429465Y390493D01*
X429052Y390417D01*
X428793Y390225D01*
X428587Y389957D01*
X428535Y389688D01*
X428587Y389420D01*
X428793Y389075D01*
X427450Y389190D01*
Y390225D01*
G01X420306Y414494D02*
X420574Y414546D01*
X420881Y414701D01*
X421073Y414959D01*
X421149Y415321D01*
X421073Y415682D01*
X420843Y415992D01*
X420498Y416147D01*
X420114D01*
X419884Y416251D01*
X419693Y416509D01*
X419616Y416871D01*
X419731Y417232D01*
X419999Y417491D01*
X420306Y417594D01*
X420613Y417491D01*
X420881Y417232D01*
X420996Y416871D01*
X420919Y416509D01*
X420728Y416251D01*
X420498Y416147D01*
X420114D01*
X419769Y415992D01*
X419539Y415682D01*
X419463Y415321D01*
X419539Y414959D01*
X419731Y414701D01*
X420038Y414546D01*
X420306Y414494D01*
G01X444157Y75620D02*
X444387Y75258D01*
X444693Y75052D01*
X445038Y75000D01*
X445345Y75052D01*
X445652Y75310D01*
X445843Y75620D01*
X445882Y75930D01*
X445805Y76292D01*
X445537Y76550D01*
X445268Y76653D01*
X444923D01*
G01X445268D02*
X445498Y76808D01*
X445690Y77067D01*
X445767Y77377D01*
X445690Y77687D01*
X445498Y77945D01*
X445153Y78100D01*
X444808Y78048D01*
X444463Y77842D01*
G01X441083Y95000D02*
Y98100D01*
X442042D01*
X442348Y97945D01*
X442540Y97738D01*
X442617Y97325D01*
X442540Y96912D01*
X442310Y96653D01*
X442042Y96498D01*
X441083D01*
G01X442042D02*
X442617Y95000D01*
G01X444222Y97583D02*
X444452Y97893D01*
X444720Y98048D01*
X445027Y98100D01*
X445410Y97997D01*
X445678Y97738D01*
X445755Y97428D01*
X445717Y97118D01*
X445563Y96860D01*
X444797Y96343D01*
X444452Y95982D01*
X444222Y95465D01*
X444145Y95000D01*
X445755D01*
G01X448510D02*
Y98100D01*
X447092Y95878D01*
X449008D01*
G01X451150Y95000D02*
Y98100D01*
X450690Y97480D01*
G01Y95000D02*
X451610D01*
G01X433450Y85950D02*
Y87345D01*
X432683Y89050D01*
G01X434217D02*
X433450Y87345D01*
G01X435707Y86570D02*
X435937Y86208D01*
X436243Y86002D01*
X436588Y85950D01*
X436895Y86002D01*
X437202Y86260D01*
X437393Y86570D01*
X437432Y86880D01*
X437355Y87242D01*
X437087Y87500D01*
X436818Y87603D01*
X436473D01*
G01X436818D02*
X437048Y87758D01*
X437240Y88017D01*
X437317Y88327D01*
X437240Y88637D01*
X437048Y88895D01*
X436703Y89050D01*
X436358Y88998D01*
X436013Y88792D01*
G01X435608Y100893D02*
X435453Y100663D01*
X435350Y100395D01*
Y100088D01*
X435505Y99743D01*
X435763Y99475D01*
X436073Y99283D01*
X436590Y99130D01*
X437055Y99092D01*
X437520Y99168D01*
X437830Y99283D01*
X438140Y99513D01*
X438347Y99782D01*
X438450Y100050D01*
Y100318D01*
X438347Y100587D01*
X438192Y100817D01*
X437985Y101008D01*
G01X435867Y102422D02*
X435557Y102652D01*
X435402Y102920D01*
X435350Y103227D01*
X435453Y103610D01*
X435712Y103878D01*
X436022Y103955D01*
X436332Y103917D01*
X436590Y103763D01*
X437107Y102997D01*
X437468Y102652D01*
X437985Y102422D01*
X438450Y102345D01*
Y103955D01*
G01X437985Y105407D02*
X438243Y105637D01*
X438398Y105905D01*
X438450Y106250D01*
X438347Y106595D01*
X438140Y106863D01*
X437778Y107055D01*
X437365Y107093D01*
X436952Y107017D01*
X436693Y106825D01*
X436487Y106557D01*
X436435Y106288D01*
X436487Y106020D01*
X436693Y105675D01*
X435350Y105790D01*
Y106825D01*
G01X435867Y108622D02*
X435557Y108852D01*
X435402Y109120D01*
X435350Y109427D01*
X435453Y109810D01*
X435712Y110078D01*
X436022Y110155D01*
X436332Y110117D01*
X436590Y109963D01*
X437107Y109197D01*
X437468Y108852D01*
X437985Y108622D01*
X438450Y108545D01*
Y110155D01*
G01X440108Y100893D02*
X439953Y100663D01*
X439850Y100395D01*
Y100088D01*
X440005Y99743D01*
X440263Y99475D01*
X440573Y99283D01*
X441090Y99130D01*
X441555Y99092D01*
X442020Y99168D01*
X442330Y99283D01*
X442640Y99513D01*
X442847Y99782D01*
X442950Y100050D01*
Y100318D01*
X442847Y100587D01*
X442692Y100817D01*
X442485Y101008D01*
G01X440367Y102422D02*
X440057Y102652D01*
X439902Y102920D01*
X439850Y103227D01*
X439953Y103610D01*
X440212Y103878D01*
X440522Y103955D01*
X440832Y103917D01*
X441090Y103763D01*
X441607Y102997D01*
X441968Y102652D01*
X442485Y102422D01*
X442950Y102345D01*
Y103955D01*
G01X442485Y105407D02*
X442743Y105637D01*
X442898Y105905D01*
X442950Y106250D01*
X442847Y106595D01*
X442640Y106863D01*
X442278Y107055D01*
X441865Y107093D01*
X441452Y107017D01*
X441193Y106825D01*
X440987Y106557D01*
X440935Y106288D01*
X440987Y106020D01*
X441193Y105675D01*
X439850Y105790D01*
Y106825D01*
G01X442950Y109350D02*
X439850D01*
X440470Y108890D01*
G01X442950D02*
Y109810D01*
G01X439083Y110950D02*
Y114050D01*
X440042D01*
X440348Y113895D01*
X440540Y113688D01*
X440617Y113275D01*
X440540Y112862D01*
X440310Y112603D01*
X440042Y112448D01*
X439083D01*
G01X440042D02*
X440617Y110950D01*
G01X442107Y111570D02*
X442337Y111208D01*
X442643Y111002D01*
X442988Y110950D01*
X443295Y111002D01*
X443602Y111260D01*
X443793Y111570D01*
X443832Y111880D01*
X443755Y112242D01*
X443487Y112500D01*
X443218Y112603D01*
X442873D01*
G01X443218D02*
X443448Y112758D01*
X443640Y113017D01*
X443717Y113327D01*
X443640Y113637D01*
X443448Y113895D01*
X443103Y114050D01*
X442758Y113998D01*
X442413Y113792D01*
G01X445207Y111415D02*
X445437Y111157D01*
X445705Y111002D01*
X446050Y110950D01*
X446395Y111053D01*
X446663Y111260D01*
X446855Y111622D01*
X446893Y112035D01*
X446817Y112448D01*
X446625Y112707D01*
X446357Y112913D01*
X446088Y112965D01*
X445820Y112913D01*
X445475Y112707D01*
X445590Y114050D01*
X446625D01*
G01X448498Y111312D02*
X448767Y111053D01*
X449073Y110950D01*
X449380Y111053D01*
X449648Y111363D01*
X449840Y111828D01*
X449917Y112293D01*
Y112862D01*
X449840Y113327D01*
X449648Y113740D01*
X449418Y113947D01*
X449150Y114050D01*
X448843Y113947D01*
X448613Y113740D01*
X448460Y113430D01*
X448383Y113017D01*
X448460Y112655D01*
X448652Y112293D01*
X448882Y112087D01*
X449150Y112035D01*
X449457Y112138D01*
X449687Y112397D01*
X449917Y112862D01*
G01X434533Y121753D02*
X431433D01*
X434016Y122750D01*
X431433Y123747D01*
X434533D01*
G01X439033Y124868D02*
X435933D01*
X439033Y126632D01*
X435933D01*
G01X441533Y121983D02*
X438433D01*
Y122903D01*
X438588Y123210D01*
X438950Y123440D01*
X439363Y123517D01*
X439776Y123440D01*
X440086Y123248D01*
X440241Y122903D01*
Y121983D01*
G01X446033Y124983D02*
X442933D01*
Y125942D01*
X443088Y126248D01*
X443295Y126440D01*
X443708Y126517D01*
X444121Y126440D01*
X444380Y126210D01*
X444535Y125942D01*
Y124983D01*
G01Y125942D02*
X446033Y126517D01*
G01X445933Y122750D02*
X449033D01*
G01X445933Y121868D02*
Y123632D01*
G01X441050Y238583D02*
X437950D01*
Y239542D01*
X438105Y239848D01*
X438312Y240040D01*
X438725Y240117D01*
X439138Y240040D01*
X439397Y239810D01*
X439552Y239542D01*
Y238583D01*
G01Y239542D02*
X441050Y240117D01*
G01X438467Y241722D02*
X438157Y241952D01*
X438002Y242220D01*
X437950Y242527D01*
X438053Y242910D01*
X438312Y243178D01*
X438622Y243255D01*
X438932Y243217D01*
X439190Y243063D01*
X439707Y242297D01*
X440068Y241952D01*
X440585Y241722D01*
X441050Y241645D01*
Y243255D01*
G01Y245550D02*
X437950D01*
X438570Y245090D01*
G01X441050D02*
Y246010D01*
G01X440430Y247807D02*
X440792Y248037D01*
X440998Y248343D01*
X441050Y248688D01*
X440998Y248995D01*
X440740Y249302D01*
X440430Y249493D01*
X440120Y249532D01*
X439758Y249455D01*
X439500Y249187D01*
X439397Y248918D01*
Y248573D01*
G01Y248918D02*
X439242Y249148D01*
X438983Y249340D01*
X438673Y249417D01*
X438363Y249340D01*
X438105Y249148D01*
X437950Y248803D01*
X438002Y248458D01*
X438208Y248113D01*
G01X445550Y238583D02*
X442450D01*
Y239542D01*
X442605Y239848D01*
X442812Y240040D01*
X443225Y240117D01*
X443638Y240040D01*
X443897Y239810D01*
X444052Y239542D01*
Y238583D01*
G01Y239542D02*
X445550Y240117D01*
G01X442967Y241722D02*
X442657Y241952D01*
X442502Y242220D01*
X442450Y242527D01*
X442553Y242910D01*
X442812Y243178D01*
X443122Y243255D01*
X443432Y243217D01*
X443690Y243063D01*
X444207Y242297D01*
X444568Y241952D01*
X445085Y241722D01*
X445550Y241645D01*
Y243255D01*
G01Y245550D02*
X442450D01*
X443070Y245090D01*
G01X445550D02*
Y246010D01*
G01Y249110D02*
X442450D01*
X444672Y247692D01*
Y249608D01*
G01X437708Y268193D02*
X437553Y267963D01*
X437450Y267695D01*
Y267388D01*
X437605Y267043D01*
X437863Y266775D01*
X438173Y266583D01*
X438690Y266430D01*
X439155Y266392D01*
X439620Y266468D01*
X439930Y266583D01*
X440240Y266813D01*
X440447Y267082D01*
X440550Y267350D01*
Y267618D01*
X440447Y267887D01*
X440292Y268117D01*
X440085Y268308D01*
G01X437967Y269722D02*
X437657Y269952D01*
X437502Y270220D01*
X437450Y270527D01*
X437553Y270910D01*
X437812Y271178D01*
X438122Y271255D01*
X438432Y271217D01*
X438690Y271063D01*
X439207Y270297D01*
X439568Y269952D01*
X440085Y269722D01*
X440550Y269645D01*
Y271255D01*
G01X439930Y272707D02*
X440292Y272937D01*
X440498Y273243D01*
X440550Y273588D01*
X440498Y273895D01*
X440240Y274202D01*
X439930Y274393D01*
X439620Y274432D01*
X439258Y274355D01*
X439000Y274087D01*
X438897Y273818D01*
Y273473D01*
G01Y273818D02*
X438742Y274048D01*
X438483Y274240D01*
X438173Y274317D01*
X437863Y274240D01*
X437605Y274048D01*
X437450Y273703D01*
X437502Y273358D01*
X437708Y273013D01*
G01X439930Y275807D02*
X440292Y276037D01*
X440498Y276343D01*
X440550Y276688D01*
X440498Y276995D01*
X440240Y277302D01*
X439930Y277493D01*
X439620Y277532D01*
X439258Y277455D01*
X439000Y277187D01*
X438897Y276918D01*
Y276573D01*
G01Y276918D02*
X438742Y277148D01*
X438483Y277340D01*
X438173Y277417D01*
X437863Y277340D01*
X437605Y277148D01*
X437450Y276803D01*
X437502Y276458D01*
X437708Y276113D01*
G01X444208Y266693D02*
X444053Y266463D01*
X443950Y266195D01*
Y265888D01*
X444105Y265543D01*
X444363Y265275D01*
X444673Y265083D01*
X445190Y264930D01*
X445655Y264892D01*
X446120Y264968D01*
X446430Y265083D01*
X446740Y265313D01*
X446947Y265582D01*
X447050Y265850D01*
Y266118D01*
X446947Y266387D01*
X446792Y266617D01*
X446585Y266808D01*
G01X444467Y268222D02*
X444157Y268452D01*
X444002Y268720D01*
X443950Y269027D01*
X444053Y269410D01*
X444312Y269678D01*
X444622Y269755D01*
X444932Y269717D01*
X445190Y269563D01*
X445707Y268797D01*
X446068Y268452D01*
X446585Y268222D01*
X447050Y268145D01*
Y269755D01*
G01X446430Y271207D02*
X446792Y271437D01*
X446998Y271743D01*
X447050Y272088D01*
X446998Y272395D01*
X446740Y272702D01*
X446430Y272893D01*
X446120Y272932D01*
X445758Y272855D01*
X445500Y272587D01*
X445397Y272318D01*
Y271973D01*
G01Y272318D02*
X445242Y272548D01*
X444983Y272740D01*
X444673Y272817D01*
X444363Y272740D01*
X444105Y272548D01*
X443950Y272203D01*
X444002Y271858D01*
X444208Y271513D01*
G01X444467Y274422D02*
X444157Y274652D01*
X444002Y274920D01*
X443950Y275227D01*
X444053Y275610D01*
X444312Y275878D01*
X444622Y275955D01*
X444932Y275917D01*
X445190Y275763D01*
X445707Y274997D01*
X446068Y274652D01*
X446585Y274422D01*
X447050Y274345D01*
Y275955D01*
G01X430207Y290182D02*
Y287960D01*
X430360Y287495D01*
X430667Y287185D01*
X431050Y287082D01*
X431433Y287185D01*
X431740Y287495D01*
X431893Y287960D01*
Y290182D01*
G01X433422Y289665D02*
X433652Y289975D01*
X433920Y290130D01*
X434227Y290182D01*
X434610Y290079D01*
X434878Y289820D01*
X434955Y289510D01*
X434917Y289200D01*
X434763Y288942D01*
X433997Y288425D01*
X433652Y288064D01*
X433422Y287547D01*
X433345Y287082D01*
X434955D01*
G01X436522Y289665D02*
X436752Y289975D01*
X437020Y290130D01*
X437327Y290182D01*
X437710Y290079D01*
X437978Y289820D01*
X438055Y289510D01*
X438017Y289200D01*
X437863Y288942D01*
X437097Y288425D01*
X436752Y288064D01*
X436522Y287547D01*
X436445Y287082D01*
X438055D01*
G01X445734Y293081D02*
X446002Y293442D01*
X446232Y293649D01*
X446539Y293752D01*
X446807Y293649D01*
X446999Y293442D01*
X447152Y293132D01*
X447190Y292771D01*
X447152Y292461D01*
X446999Y292151D01*
X446769Y291892D01*
X446500Y291789D01*
X446194Y291892D01*
X445925Y292202D01*
X445772Y292667D01*
X445734Y293184D01*
X445810Y293856D01*
X445925Y294217D01*
X446117Y294579D01*
X446385Y294837D01*
X446654Y294889D01*
X446922Y294786D01*
X447114Y294527D01*
G01X446148Y305462D02*
X446417Y305203D01*
X446723Y305100D01*
X447030Y305203D01*
X447298Y305513D01*
X447490Y305978D01*
X447567Y306443D01*
Y307012D01*
X447490Y307477D01*
X447298Y307890D01*
X447068Y308097D01*
X446800Y308200D01*
X446493Y308097D01*
X446263Y307890D01*
X446110Y307580D01*
X446033Y307167D01*
X446110Y306805D01*
X446302Y306443D01*
X446532Y306237D01*
X446800Y306185D01*
X447107Y306288D01*
X447337Y306547D01*
X447567Y307012D01*
G01X442950Y326950D02*
Y330050D01*
X442490Y329430D01*
G01Y326950D02*
X443410D01*
G01X445322Y328242D02*
X445590Y328603D01*
X445820Y328810D01*
X446127Y328913D01*
X446395Y328810D01*
X446587Y328603D01*
X446740Y328293D01*
X446778Y327932D01*
X446740Y327622D01*
X446587Y327312D01*
X446357Y327053D01*
X446088Y326950D01*
X445782Y327053D01*
X445513Y327363D01*
X445360Y327828D01*
X445322Y328345D01*
X445398Y329017D01*
X445513Y329378D01*
X445705Y329740D01*
X445973Y329998D01*
X446242Y330050D01*
X446510Y329947D01*
X446702Y329688D01*
G01X435034Y342083D02*
X431934D01*
Y343042D01*
X432089Y343348D01*
X432296Y343540D01*
X432709Y343617D01*
X433122Y343540D01*
X433381Y343310D01*
X433536Y343042D01*
Y342083D01*
G01Y343042D02*
X435034Y343617D01*
G01Y346410D02*
X431934D01*
X434156Y344992D01*
Y346908D01*
G01X435034Y349510D02*
X431934D01*
X434156Y348092D01*
Y350008D01*
G01X434414Y351307D02*
X434776Y351537D01*
X434982Y351843D01*
X435034Y352188D01*
X434982Y352495D01*
X434724Y352802D01*
X434414Y352993D01*
X434104Y353032D01*
X433742Y352955D01*
X433484Y352687D01*
X433381Y352418D01*
Y352073D01*
G01Y352418D02*
X433226Y352648D01*
X432967Y352840D01*
X432657Y352917D01*
X432347Y352840D01*
X432089Y352648D01*
X431934Y352303D01*
X431986Y351958D01*
X432192Y351613D01*
G01X441950Y356467D02*
X441643Y356519D01*
X441375Y356725D01*
X441145Y357035D01*
X440992Y357397D01*
X440915Y357810D01*
Y358224D01*
X440992Y358637D01*
X441145Y358999D01*
X441375Y359309D01*
X441643Y359515D01*
X441950Y359567D01*
X442257Y359515D01*
X442525Y359309D01*
X442755Y358999D01*
X442908Y358637D01*
X442985Y358224D01*
Y357810D01*
X442908Y357397D01*
X442755Y357035D01*
X442525Y356725D01*
X442257Y356519D01*
X441950Y356467D01*
G01X442257Y357294D02*
X442717Y356467D01*
G01X445050D02*
Y359567D01*
X444590Y358947D01*
G01Y356467D02*
X445510D01*
G01X436083Y372966D02*
Y376066D01*
X437042D01*
X437348Y375911D01*
X437540Y375704D01*
X437617Y375291D01*
X437540Y374878D01*
X437310Y374619D01*
X437042Y374464D01*
X436083D01*
G01X437042D02*
X437617Y372966D01*
G01X440410D02*
Y376066D01*
X438992Y373844D01*
X440908D01*
G01X442207Y373431D02*
X442437Y373173D01*
X442705Y373018D01*
X443050Y372966D01*
X443395Y373069D01*
X443663Y373276D01*
X443855Y373638D01*
X443893Y374051D01*
X443817Y374464D01*
X443625Y374723D01*
X443357Y374929D01*
X443088Y374981D01*
X442820Y374929D01*
X442475Y374723D01*
X442590Y376066D01*
X443625D01*
G01X445307Y373586D02*
X445537Y373224D01*
X445843Y373018D01*
X446188Y372966D01*
X446495Y373018D01*
X446802Y373276D01*
X446993Y373586D01*
X447032Y373896D01*
X446955Y374258D01*
X446687Y374516D01*
X446418Y374619D01*
X446073D01*
G01X446418D02*
X446648Y374774D01*
X446840Y375033D01*
X446917Y375343D01*
X446840Y375653D01*
X446648Y375911D01*
X446303Y376066D01*
X445958Y376014D01*
X445613Y375808D01*
G01X436083Y368466D02*
Y371566D01*
X437042D01*
X437348Y371411D01*
X437540Y371204D01*
X437617Y370791D01*
X437540Y370378D01*
X437310Y370119D01*
X437042Y369964D01*
X436083D01*
G01X437042D02*
X437617Y368466D01*
G01X440410D02*
Y371566D01*
X438992Y369344D01*
X440908D01*
G01X442207Y368931D02*
X442437Y368673D01*
X442705Y368518D01*
X443050Y368466D01*
X443395Y368569D01*
X443663Y368776D01*
X443855Y369138D01*
X443893Y369551D01*
X443817Y369964D01*
X443625Y370223D01*
X443357Y370429D01*
X443088Y370481D01*
X442820Y370429D01*
X442475Y370223D01*
X442590Y371566D01*
X443625D01*
G01X445422Y371049D02*
X445652Y371359D01*
X445920Y371514D01*
X446227Y371566D01*
X446610Y371463D01*
X446878Y371204D01*
X446955Y370894D01*
X446917Y370584D01*
X446763Y370326D01*
X445997Y369809D01*
X445652Y369448D01*
X445422Y368931D01*
X445345Y368466D01*
X446955D01*
G01X432748Y357362D02*
X433017Y357103D01*
X433323Y357000D01*
X433630Y357103D01*
X433898Y357413D01*
X434090Y357878D01*
X434167Y358343D01*
Y358912D01*
X434090Y359377D01*
X433898Y359790D01*
X433668Y359997D01*
X433400Y360100D01*
X433093Y359997D01*
X432863Y359790D01*
X432710Y359480D01*
X432633Y359067D01*
X432710Y358705D01*
X432902Y358343D01*
X433132Y358137D01*
X433400Y358085D01*
X433707Y358188D01*
X433937Y358447D01*
X434167Y358912D01*
G01X439243Y380792D02*
X439013Y380947D01*
X438745Y381050D01*
X438438D01*
X438093Y380895D01*
X437825Y380637D01*
X437633Y380327D01*
X437480Y379810D01*
X437442Y379345D01*
X437518Y378880D01*
X437633Y378570D01*
X437863Y378260D01*
X438132Y378053D01*
X438400Y377950D01*
X438668D01*
X438937Y378053D01*
X439167Y378208D01*
X439358Y378415D01*
G01X441500Y377950D02*
X441768Y378002D01*
X442075Y378157D01*
X442267Y378415D01*
X442343Y378777D01*
X442267Y379138D01*
X442037Y379448D01*
X441692Y379603D01*
X441308D01*
X441078Y379707D01*
X440887Y379965D01*
X440810Y380327D01*
X440925Y380688D01*
X441193Y380947D01*
X441500Y381050D01*
X441807Y380947D01*
X442075Y380688D01*
X442190Y380327D01*
X442113Y379965D01*
X441922Y379707D01*
X441692Y379603D01*
X441308D01*
X440963Y379448D01*
X440733Y379138D01*
X440657Y378777D01*
X440733Y378415D01*
X440925Y378157D01*
X441232Y378002D01*
X441500Y377950D01*
G01X443948Y378312D02*
X444217Y378053D01*
X444523Y377950D01*
X444830Y378053D01*
X445098Y378363D01*
X445290Y378828D01*
X445367Y379293D01*
Y379862D01*
X445290Y380327D01*
X445098Y380740D01*
X444868Y380947D01*
X444600Y381050D01*
X444293Y380947D01*
X444063Y380740D01*
X443910Y380430D01*
X443833Y380017D01*
X443910Y379655D01*
X444102Y379293D01*
X444332Y379087D01*
X444600Y379035D01*
X444907Y379138D01*
X445137Y379397D01*
X445367Y379862D01*
G01X432083Y389950D02*
Y393050D01*
X433042D01*
X433348Y392895D01*
X433540Y392688D01*
X433617Y392275D01*
X433540Y391862D01*
X433310Y391603D01*
X433042Y391448D01*
X432083D01*
G01X433042D02*
X433617Y389950D01*
G01X435107Y390570D02*
X435337Y390208D01*
X435643Y390002D01*
X435988Y389950D01*
X436295Y390002D01*
X436602Y390260D01*
X436793Y390570D01*
X436832Y390880D01*
X436755Y391242D01*
X436487Y391500D01*
X436218Y391603D01*
X435873D01*
G01X436218D02*
X436448Y391758D01*
X436640Y392017D01*
X436717Y392327D01*
X436640Y392637D01*
X436448Y392895D01*
X436103Y393050D01*
X435758Y392998D01*
X435413Y392792D01*
G01X438322Y392533D02*
X438552Y392843D01*
X438820Y392998D01*
X439127Y393050D01*
X439510Y392947D01*
X439778Y392688D01*
X439855Y392378D01*
X439817Y392068D01*
X439663Y391810D01*
X438897Y391293D01*
X438552Y390932D01*
X438322Y390415D01*
X438245Y389950D01*
X439855D01*
G01X442610D02*
Y393050D01*
X441192Y390828D01*
X443108D01*
G01X432083Y384950D02*
Y388050D01*
X433042D01*
X433348Y387895D01*
X433540Y387688D01*
X433617Y387275D01*
X433540Y386862D01*
X433310Y386603D01*
X433042Y386448D01*
X432083D01*
G01X433042D02*
X433617Y384950D01*
G01X435107Y385570D02*
X435337Y385208D01*
X435643Y385002D01*
X435988Y384950D01*
X436295Y385002D01*
X436602Y385260D01*
X436793Y385570D01*
X436832Y385880D01*
X436755Y386242D01*
X436487Y386500D01*
X436218Y386603D01*
X435873D01*
G01X436218D02*
X436448Y386758D01*
X436640Y387017D01*
X436717Y387327D01*
X436640Y387637D01*
X436448Y387895D01*
X436103Y388050D01*
X435758Y387998D01*
X435413Y387792D01*
G01X438322Y387533D02*
X438552Y387843D01*
X438820Y387998D01*
X439127Y388050D01*
X439510Y387947D01*
X439778Y387688D01*
X439855Y387378D01*
X439817Y387068D01*
X439663Y386810D01*
X438897Y386293D01*
X438552Y385932D01*
X438322Y385415D01*
X438245Y384950D01*
X439855D01*
G01X442150Y388050D02*
X441843Y387947D01*
X441613Y387688D01*
X441460Y387378D01*
X441345Y386965D01*
X441307Y386500D01*
X441345Y386035D01*
X441460Y385622D01*
X441613Y385312D01*
X441843Y385053D01*
X442150Y384950D01*
X442457Y385053D01*
X442687Y385312D01*
X442840Y385622D01*
X442955Y386035D01*
X442993Y386500D01*
X442955Y386965D01*
X442840Y387378D01*
X442687Y387688D01*
X442457Y387947D01*
X442150Y388050D01*
G01X431950Y377950D02*
Y381050D01*
X431490Y380430D01*
G01Y377950D02*
X432410D01*
G01X434322Y379242D02*
X434590Y379603D01*
X434820Y379810D01*
X435127Y379913D01*
X435395Y379810D01*
X435587Y379603D01*
X435740Y379293D01*
X435778Y378932D01*
X435740Y378622D01*
X435587Y378312D01*
X435357Y378053D01*
X435088Y377950D01*
X434782Y378053D01*
X434513Y378363D01*
X434360Y378828D01*
X434322Y379345D01*
X434398Y380017D01*
X434513Y380378D01*
X434705Y380740D01*
X434973Y380998D01*
X435242Y381050D01*
X435510Y380947D01*
X435702Y380688D01*
G01X433693Y397792D02*
X433463Y397947D01*
X433195Y398050D01*
X432888D01*
X432543Y397895D01*
X432275Y397637D01*
X432083Y397327D01*
X431930Y396810D01*
X431892Y396345D01*
X431968Y395880D01*
X432083Y395570D01*
X432313Y395260D01*
X432582Y395053D01*
X432850Y394950D01*
X433118D01*
X433387Y395053D01*
X433617Y395208D01*
X433808Y395415D01*
G01X435107Y395570D02*
X435337Y395208D01*
X435643Y395002D01*
X435988Y394950D01*
X436295Y395002D01*
X436602Y395260D01*
X436793Y395570D01*
X436832Y395880D01*
X436755Y396242D01*
X436487Y396500D01*
X436218Y396603D01*
X435873D01*
G01X436218D02*
X436448Y396758D01*
X436640Y397017D01*
X436717Y397327D01*
X436640Y397637D01*
X436448Y397895D01*
X436103Y398050D01*
X435758Y397998D01*
X435413Y397792D01*
G01X439050Y394950D02*
Y398050D01*
X438590Y397430D01*
G01Y394950D02*
X439510D01*
G01X442610D02*
Y398050D01*
X441192Y395828D01*
X443108D01*
G01X432083Y399950D02*
Y403050D01*
X433042D01*
X433348Y402895D01*
X433540Y402688D01*
X433617Y402275D01*
X433540Y401862D01*
X433310Y401603D01*
X433042Y401448D01*
X432083D01*
G01X433042D02*
X433617Y399950D01*
G01X435107Y400570D02*
X435337Y400208D01*
X435643Y400002D01*
X435988Y399950D01*
X436295Y400002D01*
X436602Y400260D01*
X436793Y400570D01*
X436832Y400880D01*
X436755Y401242D01*
X436487Y401500D01*
X436218Y401603D01*
X435873D01*
G01X436218D02*
X436448Y401758D01*
X436640Y402017D01*
X436717Y402327D01*
X436640Y402637D01*
X436448Y402895D01*
X436103Y403050D01*
X435758Y402998D01*
X435413Y402792D01*
G01X438322Y402533D02*
X438552Y402843D01*
X438820Y402998D01*
X439127Y403050D01*
X439510Y402947D01*
X439778Y402688D01*
X439855Y402378D01*
X439817Y402068D01*
X439663Y401810D01*
X438897Y401293D01*
X438552Y400932D01*
X438322Y400415D01*
X438245Y399950D01*
X439855D01*
G01X441307Y400570D02*
X441537Y400208D01*
X441843Y400002D01*
X442188Y399950D01*
X442495Y400002D01*
X442802Y400260D01*
X442993Y400570D01*
X443032Y400880D01*
X442955Y401242D01*
X442687Y401500D01*
X442418Y401603D01*
X442073D01*
G01X442418D02*
X442648Y401758D01*
X442840Y402017D01*
X442917Y402327D01*
X442840Y402637D01*
X442648Y402895D01*
X442303Y403050D01*
X441958Y402998D01*
X441613Y402792D01*
G01X432083Y405466D02*
Y408566D01*
X433042D01*
X433348Y408411D01*
X433540Y408204D01*
X433617Y407791D01*
X433540Y407378D01*
X433310Y407119D01*
X433042Y406964D01*
X432083D01*
G01X433042D02*
X433617Y405466D01*
G01X435107Y406086D02*
X435337Y405724D01*
X435643Y405518D01*
X435988Y405466D01*
X436295Y405518D01*
X436602Y405776D01*
X436793Y406086D01*
X436832Y406396D01*
X436755Y406758D01*
X436487Y407016D01*
X436218Y407119D01*
X435873D01*
G01X436218D02*
X436448Y407274D01*
X436640Y407533D01*
X436717Y407843D01*
X436640Y408153D01*
X436448Y408411D01*
X436103Y408566D01*
X435758Y408514D01*
X435413Y408308D01*
G01X438322Y406758D02*
X438590Y407119D01*
X438820Y407326D01*
X439127Y407429D01*
X439395Y407326D01*
X439587Y407119D01*
X439740Y406809D01*
X439778Y406448D01*
X439740Y406138D01*
X439587Y405828D01*
X439357Y405569D01*
X439088Y405466D01*
X438782Y405569D01*
X438513Y405879D01*
X438360Y406344D01*
X438322Y406861D01*
X438398Y407533D01*
X438513Y407894D01*
X438705Y408256D01*
X438973Y408514D01*
X439242Y408566D01*
X439510Y408463D01*
X439702Y408204D01*
G01X442610Y405466D02*
Y408566D01*
X441192Y406344D01*
X443108D01*
G01X430883Y404538D02*
X430960Y405210D01*
X431075Y405778D01*
X431228Y406295D01*
X431420Y406863D01*
X431727Y407638D01*
X430193D01*
G01X432083Y410466D02*
Y413566D01*
X433042D01*
X433348Y413411D01*
X433540Y413204D01*
X433617Y412791D01*
X433540Y412378D01*
X433310Y412119D01*
X433042Y411964D01*
X432083D01*
G01X433042D02*
X433617Y410466D01*
G01X435107Y411086D02*
X435337Y410724D01*
X435643Y410518D01*
X435988Y410466D01*
X436295Y410518D01*
X436602Y410776D01*
X436793Y411086D01*
X436832Y411396D01*
X436755Y411758D01*
X436487Y412016D01*
X436218Y412119D01*
X435873D01*
G01X436218D02*
X436448Y412274D01*
X436640Y412533D01*
X436717Y412843D01*
X436640Y413153D01*
X436448Y413411D01*
X436103Y413566D01*
X435758Y413514D01*
X435413Y413308D01*
G01X438322Y411758D02*
X438590Y412119D01*
X438820Y412326D01*
X439127Y412429D01*
X439395Y412326D01*
X439587Y412119D01*
X439740Y411809D01*
X439778Y411448D01*
X439740Y411138D01*
X439587Y410828D01*
X439357Y410569D01*
X439088Y410466D01*
X438782Y410569D01*
X438513Y410879D01*
X438360Y411344D01*
X438322Y411861D01*
X438398Y412533D01*
X438513Y412894D01*
X438705Y413256D01*
X438973Y413514D01*
X439242Y413566D01*
X439510Y413463D01*
X439702Y413204D01*
G01X441422Y411758D02*
X441690Y412119D01*
X441920Y412326D01*
X442227Y412429D01*
X442495Y412326D01*
X442687Y412119D01*
X442840Y411809D01*
X442878Y411448D01*
X442840Y411138D01*
X442687Y410828D01*
X442457Y410569D01*
X442188Y410466D01*
X441882Y410569D01*
X441613Y410879D01*
X441460Y411344D01*
X441422Y411861D01*
X441498Y412533D01*
X441613Y412894D01*
X441805Y413256D01*
X442073Y413514D01*
X442342Y413566D01*
X442610Y413463D01*
X442802Y413204D01*
G01X448460Y91000D02*
Y94100D01*
X447042Y91878D01*
X448958D01*
G01X459534Y110583D02*
X456434D01*
Y111542D01*
X456589Y111848D01*
X456796Y112040D01*
X457209Y112117D01*
X457622Y112040D01*
X457881Y111810D01*
X458036Y111542D01*
Y110583D01*
G01Y111542D02*
X459534Y112117D01*
G01Y114910D02*
X456434D01*
X458656Y113492D01*
Y115408D01*
G01X458914Y116707D02*
X459276Y116937D01*
X459482Y117243D01*
X459534Y117588D01*
X459482Y117895D01*
X459224Y118202D01*
X458914Y118393D01*
X458604Y118432D01*
X458242Y118355D01*
X457984Y118087D01*
X457881Y117818D01*
Y117473D01*
G01Y117818D02*
X457726Y118048D01*
X457467Y118240D01*
X457157Y118317D01*
X456847Y118240D01*
X456589Y118048D01*
X456434Y117703D01*
X456486Y117358D01*
X456692Y117013D01*
G01X459534Y120650D02*
X459482Y120918D01*
X459327Y121225D01*
X459069Y121417D01*
X458707Y121493D01*
X458346Y121417D01*
X458036Y121187D01*
X457881Y120842D01*
Y120458D01*
X457777Y120228D01*
X457519Y120037D01*
X457157Y119960D01*
X456796Y120075D01*
X456537Y120343D01*
X456434Y120650D01*
X456537Y120957D01*
X456796Y121225D01*
X457157Y121340D01*
X457519Y121263D01*
X457777Y121072D01*
X457881Y120842D01*
Y120458D01*
X458036Y120113D01*
X458346Y119883D01*
X458707Y119807D01*
X459069Y119883D01*
X459327Y120075D01*
X459482Y120382D01*
X459534Y120650D01*
G01X454034Y110583D02*
X450934D01*
Y111542D01*
X451089Y111848D01*
X451296Y112040D01*
X451709Y112117D01*
X452122Y112040D01*
X452381Y111810D01*
X452536Y111542D01*
Y110583D01*
G01Y111542D02*
X454034Y112117D01*
G01Y114910D02*
X450934D01*
X453156Y113492D01*
Y115408D01*
G01X453414Y116707D02*
X453776Y116937D01*
X453982Y117243D01*
X454034Y117588D01*
X453982Y117895D01*
X453724Y118202D01*
X453414Y118393D01*
X453104Y118432D01*
X452742Y118355D01*
X452484Y118087D01*
X452381Y117818D01*
Y117473D01*
G01Y117818D02*
X452226Y118048D01*
X451967Y118240D01*
X451657Y118317D01*
X451347Y118240D01*
X451089Y118048D01*
X450934Y117703D01*
X450986Y117358D01*
X451192Y117013D01*
G01X453672Y119998D02*
X453931Y120267D01*
X454034Y120573D01*
X453931Y120880D01*
X453621Y121148D01*
X453156Y121340D01*
X452691Y121417D01*
X452122D01*
X451657Y121340D01*
X451244Y121148D01*
X451037Y120918D01*
X450934Y120650D01*
X451037Y120343D01*
X451244Y120113D01*
X451554Y119960D01*
X451967Y119883D01*
X452329Y119960D01*
X452691Y120152D01*
X452897Y120382D01*
X452949Y120650D01*
X452846Y120957D01*
X452587Y121187D01*
X452122Y121417D01*
G01X449433Y124907D02*
X451655D01*
X452120Y125060D01*
X452430Y125367D01*
X452533Y125750D01*
X452430Y126133D01*
X452120Y126440D01*
X451655Y126593D01*
X449433D01*
G01X453433Y121792D02*
X456533Y122750D01*
X453433Y123708D01*
G01X457433Y124600D02*
X460533Y125137D01*
X457433Y125750D01*
X460533Y126363D01*
X457433Y126900D01*
G01X463533Y122750D02*
X462138D01*
X460433Y121983D01*
G01Y123517D02*
X462138Y122750D01*
G01X455050Y226583D02*
X451950D01*
Y227542D01*
X452105Y227848D01*
X452312Y228040D01*
X452725Y228117D01*
X453138Y228040D01*
X453397Y227810D01*
X453552Y227542D01*
Y226583D01*
G01Y227542D02*
X455050Y228117D01*
G01X452467Y229722D02*
X452157Y229952D01*
X452002Y230220D01*
X451950Y230527D01*
X452053Y230910D01*
X452312Y231178D01*
X452622Y231255D01*
X452932Y231217D01*
X453190Y231063D01*
X453707Y230297D01*
X454068Y229952D01*
X454585Y229722D01*
X455050Y229645D01*
Y231255D01*
G01X454430Y232707D02*
X454792Y232937D01*
X454998Y233243D01*
X455050Y233588D01*
X454998Y233895D01*
X454740Y234202D01*
X454430Y234393D01*
X454120Y234432D01*
X453758Y234355D01*
X453500Y234087D01*
X453397Y233818D01*
Y233473D01*
G01Y233818D02*
X453242Y234048D01*
X452983Y234240D01*
X452673Y234317D01*
X452363Y234240D01*
X452105Y234048D01*
X451950Y233703D01*
X452002Y233358D01*
X452208Y233013D01*
G01X455050Y236650D02*
X454998Y236918D01*
X454843Y237225D01*
X454585Y237417D01*
X454223Y237493D01*
X453862Y237417D01*
X453552Y237187D01*
X453397Y236842D01*
Y236458D01*
X453293Y236228D01*
X453035Y236037D01*
X452673Y235960D01*
X452312Y236075D01*
X452053Y236343D01*
X451950Y236650D01*
X452053Y236957D01*
X452312Y237225D01*
X452673Y237340D01*
X453035Y237263D01*
X453293Y237072D01*
X453397Y236842D01*
Y236458D01*
X453552Y236113D01*
X453862Y235883D01*
X454223Y235807D01*
X454585Y235883D01*
X454843Y236075D01*
X454998Y236382D01*
X455050Y236650D01*
G01X466034Y226583D02*
X462934D01*
Y227542D01*
X463089Y227848D01*
X463296Y228040D01*
X463709Y228117D01*
X464122Y228040D01*
X464381Y227810D01*
X464536Y227542D01*
Y226583D01*
G01Y227542D02*
X466034Y228117D01*
G01X465414Y229607D02*
X465776Y229837D01*
X465982Y230143D01*
X466034Y230488D01*
X465982Y230795D01*
X465724Y231102D01*
X465414Y231293D01*
X465104Y231332D01*
X464742Y231255D01*
X464484Y230987D01*
X464381Y230718D01*
Y230373D01*
G01Y230718D02*
X464226Y230948D01*
X463967Y231140D01*
X463657Y231217D01*
X463347Y231140D01*
X463089Y230948D01*
X462934Y230603D01*
X462986Y230258D01*
X463192Y229913D01*
G01X464742Y232822D02*
X464381Y233090D01*
X464174Y233320D01*
X464071Y233627D01*
X464174Y233895D01*
X464381Y234087D01*
X464691Y234240D01*
X465052Y234278D01*
X465362Y234240D01*
X465672Y234087D01*
X465931Y233857D01*
X466034Y233588D01*
X465931Y233282D01*
X465621Y233013D01*
X465156Y232860D01*
X464639Y232822D01*
X463967Y232898D01*
X463606Y233013D01*
X463244Y233205D01*
X462986Y233473D01*
X462934Y233742D01*
X463037Y234010D01*
X463296Y234202D01*
G01X463451Y235922D02*
X463141Y236152D01*
X462986Y236420D01*
X462934Y236727D01*
X463037Y237110D01*
X463296Y237378D01*
X463606Y237455D01*
X463916Y237417D01*
X464174Y237263D01*
X464691Y236497D01*
X465052Y236152D01*
X465569Y235922D01*
X466034Y235845D01*
Y237455D01*
G01X458534Y238583D02*
X455434D01*
Y239542D01*
X455589Y239848D01*
X455796Y240040D01*
X456209Y240117D01*
X456622Y240040D01*
X456881Y239810D01*
X457036Y239542D01*
Y238583D01*
G01Y239542D02*
X458534Y240117D01*
G01Y242910D02*
X455434D01*
X457656Y241492D01*
Y243408D01*
G01X457914Y244707D02*
X458276Y244937D01*
X458482Y245243D01*
X458534Y245588D01*
X458482Y245895D01*
X458224Y246202D01*
X457914Y246393D01*
X457604Y246432D01*
X457242Y246355D01*
X456984Y246087D01*
X456881Y245818D01*
Y245473D01*
G01Y245818D02*
X456726Y246048D01*
X456467Y246240D01*
X456157Y246317D01*
X455847Y246240D01*
X455589Y246048D01*
X455434Y245703D01*
X455486Y245358D01*
X455692Y245013D01*
G01X458069Y247807D02*
X458327Y248037D01*
X458482Y248305D01*
X458534Y248650D01*
X458431Y248995D01*
X458224Y249263D01*
X457862Y249455D01*
X457449Y249493D01*
X457036Y249417D01*
X456777Y249225D01*
X456571Y248957D01*
X456519Y248688D01*
X456571Y248420D01*
X456777Y248075D01*
X455434Y248190D01*
Y249225D01*
G01X449534Y238583D02*
X446434D01*
Y239542D01*
X446589Y239848D01*
X446796Y240040D01*
X447209Y240117D01*
X447622Y240040D01*
X447881Y239810D01*
X448036Y239542D01*
Y238583D01*
G01Y239542D02*
X449534Y240117D01*
G01X446951Y241722D02*
X446641Y241952D01*
X446486Y242220D01*
X446434Y242527D01*
X446537Y242910D01*
X446796Y243178D01*
X447106Y243255D01*
X447416Y243217D01*
X447674Y243063D01*
X448191Y242297D01*
X448552Y241952D01*
X449069Y241722D01*
X449534Y241645D01*
Y243255D01*
G01X448914Y244707D02*
X449276Y244937D01*
X449482Y245243D01*
X449534Y245588D01*
X449482Y245895D01*
X449224Y246202D01*
X448914Y246393D01*
X448604Y246432D01*
X448242Y246355D01*
X447984Y246087D01*
X447881Y245818D01*
Y245473D01*
G01Y245818D02*
X447726Y246048D01*
X447467Y246240D01*
X447157Y246317D01*
X446847Y246240D01*
X446589Y246048D01*
X446434Y245703D01*
X446486Y245358D01*
X446692Y245013D01*
G01X449534Y249110D02*
X446434D01*
X448656Y247692D01*
Y249608D01*
G01X454034Y238583D02*
X450934D01*
Y239542D01*
X451089Y239848D01*
X451296Y240040D01*
X451709Y240117D01*
X452122Y240040D01*
X452381Y239810D01*
X452536Y239542D01*
Y238583D01*
G01Y239542D02*
X454034Y240117D01*
G01X453414Y241607D02*
X453776Y241837D01*
X453982Y242143D01*
X454034Y242488D01*
X453982Y242795D01*
X453724Y243102D01*
X453414Y243293D01*
X453104Y243332D01*
X452742Y243255D01*
X452484Y242987D01*
X452381Y242718D01*
Y242373D01*
G01Y242718D02*
X452226Y242948D01*
X451967Y243140D01*
X451657Y243217D01*
X451347Y243140D01*
X451089Y242948D01*
X450934Y242603D01*
X450986Y242258D01*
X451192Y241913D01*
G01X453414Y244707D02*
X453776Y244937D01*
X453982Y245243D01*
X454034Y245588D01*
X453982Y245895D01*
X453724Y246202D01*
X453414Y246393D01*
X453104Y246432D01*
X452742Y246355D01*
X452484Y246087D01*
X452381Y245818D01*
Y245473D01*
G01Y245818D02*
X452226Y246048D01*
X451967Y246240D01*
X451657Y246317D01*
X451347Y246240D01*
X451089Y246048D01*
X450934Y245703D01*
X450986Y245358D01*
X451192Y245013D01*
G01X453672Y247998D02*
X453931Y248267D01*
X454034Y248573D01*
X453931Y248880D01*
X453621Y249148D01*
X453156Y249340D01*
X452691Y249417D01*
X452122D01*
X451657Y249340D01*
X451244Y249148D01*
X451037Y248918D01*
X450934Y248650D01*
X451037Y248343D01*
X451244Y248113D01*
X451554Y247960D01*
X451967Y247883D01*
X452329Y247960D01*
X452691Y248152D01*
X452897Y248382D01*
X452949Y248650D01*
X452846Y248957D01*
X452587Y249187D01*
X452122Y249417D01*
G01X463034Y238583D02*
X459934D01*
Y239542D01*
X460089Y239848D01*
X460296Y240040D01*
X460709Y240117D01*
X461122Y240040D01*
X461381Y239810D01*
X461536Y239542D01*
Y238583D01*
G01Y239542D02*
X463034Y240117D01*
G01X462414Y241607D02*
X462776Y241837D01*
X462982Y242143D01*
X463034Y242488D01*
X462982Y242795D01*
X462724Y243102D01*
X462414Y243293D01*
X462104Y243332D01*
X461742Y243255D01*
X461484Y242987D01*
X461381Y242718D01*
Y242373D01*
G01Y242718D02*
X461226Y242948D01*
X460967Y243140D01*
X460657Y243217D01*
X460347Y243140D01*
X460089Y242948D01*
X459934Y242603D01*
X459986Y242258D01*
X460192Y241913D01*
G01X463034Y246010D02*
X459934D01*
X462156Y244592D01*
Y246508D01*
G01X463034Y248650D02*
X462982Y248918D01*
X462827Y249225D01*
X462569Y249417D01*
X462207Y249493D01*
X461846Y249417D01*
X461536Y249187D01*
X461381Y248842D01*
Y248458D01*
X461277Y248228D01*
X461019Y248037D01*
X460657Y247960D01*
X460296Y248075D01*
X460037Y248343D01*
X459934Y248650D01*
X460037Y248957D01*
X460296Y249225D01*
X460657Y249340D01*
X461019Y249263D01*
X461277Y249072D01*
X461381Y248842D01*
Y248458D01*
X461536Y248113D01*
X461846Y247883D01*
X462207Y247807D01*
X462569Y247883D01*
X462827Y248075D01*
X462982Y248382D01*
X463034Y248650D01*
G01X449083Y283466D02*
Y286566D01*
X450042D01*
X450348Y286411D01*
X450540Y286204D01*
X450617Y285791D01*
X450540Y285378D01*
X450310Y285119D01*
X450042Y284964D01*
X449083D01*
G01X450042D02*
X450617Y283466D01*
G01X452222Y286049D02*
X452452Y286359D01*
X452720Y286514D01*
X453027Y286566D01*
X453410Y286463D01*
X453678Y286204D01*
X453755Y285894D01*
X453717Y285584D01*
X453563Y285326D01*
X452797Y284809D01*
X452452Y284448D01*
X452222Y283931D01*
X452145Y283466D01*
X453755D01*
G01X455207Y284086D02*
X455437Y283724D01*
X455743Y283518D01*
X456088Y283466D01*
X456395Y283518D01*
X456702Y283776D01*
X456893Y284086D01*
X456932Y284396D01*
X456855Y284758D01*
X456587Y285016D01*
X456318Y285119D01*
X455973D01*
G01X456318D02*
X456548Y285274D01*
X456740Y285533D01*
X456817Y285843D01*
X456740Y286153D01*
X456548Y286411D01*
X456203Y286566D01*
X455858Y286514D01*
X455513Y286308D01*
G01X459073Y283466D02*
X459150Y284138D01*
X459265Y284706D01*
X459418Y285223D01*
X459610Y285791D01*
X459917Y286566D01*
X458383D01*
G01X450693Y290792D02*
X450463Y290947D01*
X450195Y291050D01*
X449888D01*
X449543Y290895D01*
X449275Y290637D01*
X449083Y290327D01*
X448930Y289810D01*
X448892Y289345D01*
X448968Y288880D01*
X449083Y288570D01*
X449313Y288260D01*
X449582Y288053D01*
X449850Y287950D01*
X450118D01*
X450387Y288053D01*
X450617Y288208D01*
X450808Y288415D01*
G01X452222Y290533D02*
X452452Y290843D01*
X452720Y290998D01*
X453027Y291050D01*
X453410Y290947D01*
X453678Y290688D01*
X453755Y290378D01*
X453717Y290068D01*
X453563Y289810D01*
X452797Y289293D01*
X452452Y288932D01*
X452222Y288415D01*
X452145Y287950D01*
X453755D01*
G01X455207Y288570D02*
X455437Y288208D01*
X455743Y288002D01*
X456088Y287950D01*
X456395Y288002D01*
X456702Y288260D01*
X456893Y288570D01*
X456932Y288880D01*
X456855Y289242D01*
X456587Y289500D01*
X456318Y289603D01*
X455973D01*
G01X456318D02*
X456548Y289758D01*
X456740Y290017D01*
X456817Y290327D01*
X456740Y290637D01*
X456548Y290895D01*
X456203Y291050D01*
X455858Y290998D01*
X455513Y290792D01*
G01X458307Y288415D02*
X458537Y288157D01*
X458805Y288002D01*
X459150Y287950D01*
X459495Y288053D01*
X459763Y288260D01*
X459955Y288622D01*
X459993Y289035D01*
X459917Y289448D01*
X459725Y289707D01*
X459457Y289913D01*
X459188Y289965D01*
X458920Y289913D01*
X458575Y289707D01*
X458690Y291050D01*
X459725D01*
G01X450693Y295792D02*
X450463Y295947D01*
X450195Y296050D01*
X449888D01*
X449543Y295895D01*
X449275Y295637D01*
X449083Y295327D01*
X448930Y294810D01*
X448892Y294345D01*
X448968Y293880D01*
X449083Y293570D01*
X449313Y293260D01*
X449582Y293053D01*
X449850Y292950D01*
X450118D01*
X450387Y293053D01*
X450617Y293208D01*
X450808Y293415D01*
G01X452222Y295533D02*
X452452Y295843D01*
X452720Y295998D01*
X453027Y296050D01*
X453410Y295947D01*
X453678Y295688D01*
X453755Y295378D01*
X453717Y295068D01*
X453563Y294810D01*
X452797Y294293D01*
X452452Y293932D01*
X452222Y293415D01*
X452145Y292950D01*
X453755D01*
G01X455207Y293570D02*
X455437Y293208D01*
X455743Y293002D01*
X456088Y292950D01*
X456395Y293002D01*
X456702Y293260D01*
X456893Y293570D01*
X456932Y293880D01*
X456855Y294242D01*
X456587Y294500D01*
X456318Y294603D01*
X455973D01*
G01X456318D02*
X456548Y294758D01*
X456740Y295017D01*
X456817Y295327D01*
X456740Y295637D01*
X456548Y295895D01*
X456203Y296050D01*
X455858Y295998D01*
X455513Y295792D01*
G01X458422Y294242D02*
X458690Y294603D01*
X458920Y294810D01*
X459227Y294913D01*
X459495Y294810D01*
X459687Y294603D01*
X459840Y294293D01*
X459878Y293932D01*
X459840Y293622D01*
X459687Y293312D01*
X459457Y293053D01*
X459188Y292950D01*
X458882Y293053D01*
X458613Y293363D01*
X458460Y293828D01*
X458422Y294345D01*
X458498Y295017D01*
X458613Y295378D01*
X458805Y295740D01*
X459073Y295998D01*
X459342Y296050D01*
X459610Y295947D01*
X459802Y295688D01*
G01X449083Y297950D02*
Y301050D01*
X450042D01*
X450348Y300895D01*
X450540Y300688D01*
X450617Y300275D01*
X450540Y299862D01*
X450310Y299603D01*
X450042Y299448D01*
X449083D01*
G01X450042D02*
X450617Y297950D01*
G01X452950D02*
Y301050D01*
X452490Y300430D01*
G01Y297950D02*
X453410D01*
G01X456510D02*
Y301050D01*
X455092Y298828D01*
X457008D01*
G01X458307Y298570D02*
X458537Y298208D01*
X458843Y298002D01*
X459188Y297950D01*
X459495Y298002D01*
X459802Y298260D01*
X459993Y298570D01*
X460032Y298880D01*
X459955Y299242D01*
X459687Y299500D01*
X459418Y299603D01*
X459073D01*
G01X459418D02*
X459648Y299758D01*
X459840Y300017D01*
X459917Y300327D01*
X459840Y300637D01*
X459648Y300895D01*
X459303Y301050D01*
X458958Y300998D01*
X458613Y300792D01*
G01X447883Y320966D02*
Y324066D01*
X448842D01*
X449148Y323911D01*
X449340Y323704D01*
X449417Y323291D01*
X449340Y322878D01*
X449110Y322619D01*
X448842Y322464D01*
X447883D01*
G01X448842D02*
X449417Y320966D01*
G01X452210D02*
Y324066D01*
X450792Y321844D01*
X452708D01*
G01X454007Y321431D02*
X454237Y321173D01*
X454505Y321018D01*
X454850Y320966D01*
X455195Y321069D01*
X455463Y321276D01*
X455655Y321638D01*
X455693Y322051D01*
X455617Y322464D01*
X455425Y322723D01*
X455157Y322929D01*
X454888Y322981D01*
X454620Y322929D01*
X454275Y322723D01*
X454390Y324066D01*
X455425D01*
G01X457298Y321328D02*
X457567Y321069D01*
X457873Y320966D01*
X458180Y321069D01*
X458448Y321379D01*
X458640Y321844D01*
X458717Y322309D01*
Y322878D01*
X458640Y323343D01*
X458448Y323756D01*
X458218Y323963D01*
X457950Y324066D01*
X457643Y323963D01*
X457413Y323756D01*
X457260Y323446D01*
X457183Y323033D01*
X457260Y322671D01*
X457452Y322309D01*
X457682Y322103D01*
X457950Y322051D01*
X458257Y322154D01*
X458487Y322413D01*
X458717Y322878D01*
G01X450743Y328808D02*
X450513Y328963D01*
X450245Y329066D01*
X449938D01*
X449593Y328911D01*
X449325Y328653D01*
X449133Y328343D01*
X448980Y327826D01*
X448942Y327361D01*
X449018Y326896D01*
X449133Y326586D01*
X449363Y326276D01*
X449632Y326069D01*
X449900Y325966D01*
X450168D01*
X450437Y326069D01*
X450667Y326224D01*
X450858Y326431D01*
G01X452348Y326328D02*
X452617Y326069D01*
X452923Y325966D01*
X453230Y326069D01*
X453498Y326379D01*
X453690Y326844D01*
X453767Y327309D01*
Y327878D01*
X453690Y328343D01*
X453498Y328756D01*
X453268Y328963D01*
X453000Y329066D01*
X452693Y328963D01*
X452463Y328756D01*
X452310Y328446D01*
X452233Y328033D01*
X452310Y327671D01*
X452502Y327309D01*
X452732Y327103D01*
X453000Y327051D01*
X453307Y327154D01*
X453537Y327413D01*
X453767Y327878D01*
G01X456023Y325966D02*
X456100Y326638D01*
X456215Y327206D01*
X456368Y327723D01*
X456560Y328291D01*
X456867Y329066D01*
X455333D01*
G01X446439Y348122D02*
X446669Y348432D01*
X446937Y348587D01*
X447244Y348639D01*
X447627Y348536D01*
X447895Y348277D01*
X447972Y347967D01*
X447934Y347657D01*
X447780Y347399D01*
X447014Y346882D01*
X446669Y346521D01*
X446439Y346004D01*
X446362Y345539D01*
X447972D01*
G01X451708Y384743D02*
X451553Y384513D01*
X451450Y384245D01*
Y383938D01*
X451605Y383593D01*
X451863Y383325D01*
X452173Y383133D01*
X452690Y382980D01*
X453155Y382942D01*
X453620Y383018D01*
X453930Y383133D01*
X454240Y383363D01*
X454447Y383632D01*
X454550Y383900D01*
Y384168D01*
X454447Y384437D01*
X454292Y384667D01*
X454085Y384858D01*
G01X454550Y387000D02*
X454498Y387268D01*
X454343Y387575D01*
X454085Y387767D01*
X453723Y387843D01*
X453362Y387767D01*
X453052Y387537D01*
X452897Y387192D01*
Y386808D01*
X452793Y386578D01*
X452535Y386387D01*
X452173Y386310D01*
X451812Y386425D01*
X451553Y386693D01*
X451450Y387000D01*
X451553Y387307D01*
X451812Y387575D01*
X452173Y387690D01*
X452535Y387613D01*
X452793Y387422D01*
X452897Y387192D01*
Y386808D01*
X453052Y386463D01*
X453362Y386233D01*
X453723Y386157D01*
X454085Y386233D01*
X454343Y386425D01*
X454498Y386732D01*
X454550Y387000D01*
G01Y390100D02*
X451450D01*
X452070Y389640D01*
G01X454550D02*
Y390560D01*
G01X459843Y393992D02*
X459613Y394147D01*
X459345Y394250D01*
X459038D01*
X458693Y394095D01*
X458425Y393837D01*
X458233Y393527D01*
X458080Y393010D01*
X458042Y392545D01*
X458118Y392080D01*
X458233Y391770D01*
X458463Y391460D01*
X458732Y391253D01*
X459000Y391150D01*
X459268D01*
X459537Y391253D01*
X459767Y391408D01*
X459958Y391615D01*
G01X462023Y391150D02*
X462100Y391822D01*
X462215Y392390D01*
X462368Y392907D01*
X462560Y393475D01*
X462867Y394250D01*
X461333D01*
G01X464548Y391512D02*
X464817Y391253D01*
X465123Y391150D01*
X465430Y391253D01*
X465698Y391563D01*
X465890Y392028D01*
X465967Y392493D01*
Y393062D01*
X465890Y393527D01*
X465698Y393940D01*
X465468Y394147D01*
X465200Y394250D01*
X464893Y394147D01*
X464663Y393940D01*
X464510Y393630D01*
X464433Y393217D01*
X464510Y392855D01*
X464702Y392493D01*
X464932Y392287D01*
X465200Y392235D01*
X465507Y392338D01*
X465737Y392597D01*
X465967Y393062D01*
G01X458414Y388501D02*
Y385401D01*
X459948D01*
G01X462281D02*
Y388501D01*
X461821Y387881D01*
G01Y385401D02*
X462741D01*
G01X464653Y386693D02*
X464921Y387054D01*
X465151Y387261D01*
X465458Y387364D01*
X465726Y387261D01*
X465918Y387054D01*
X466071Y386744D01*
X466109Y386383D01*
X466071Y386073D01*
X465918Y385763D01*
X465688Y385504D01*
X465419Y385401D01*
X465113Y385504D01*
X464844Y385814D01*
X464691Y386279D01*
X464653Y386796D01*
X464729Y387468D01*
X464844Y387829D01*
X465036Y388191D01*
X465304Y388449D01*
X465573Y388501D01*
X465841Y388398D01*
X466033Y388139D01*
G01X466083Y77466D02*
Y80566D01*
X467042D01*
X467348Y80411D01*
X467540Y80204D01*
X467617Y79791D01*
X467540Y79378D01*
X467310Y79119D01*
X467042Y78964D01*
X466083D01*
G01X467042D02*
X467617Y77466D01*
G01X470410D02*
Y80566D01*
X468992Y78344D01*
X470908D01*
G01X472973Y77466D02*
X473050Y78138D01*
X473165Y78706D01*
X473318Y79223D01*
X473510Y79791D01*
X473817Y80566D01*
X472283D01*
G01X475307Y77931D02*
X475537Y77673D01*
X475805Y77518D01*
X476150Y77466D01*
X476495Y77569D01*
X476763Y77776D01*
X476955Y78138D01*
X476993Y78551D01*
X476917Y78964D01*
X476725Y79223D01*
X476457Y79429D01*
X476188Y79481D01*
X475920Y79429D01*
X475575Y79223D01*
X475690Y80566D01*
X476725D01*
G01X466083Y85466D02*
Y88566D01*
X467042D01*
X467348Y88411D01*
X467540Y88204D01*
X467617Y87791D01*
X467540Y87378D01*
X467310Y87119D01*
X467042Y86964D01*
X466083D01*
G01X467042D02*
X467617Y85466D01*
G01X470410D02*
Y88566D01*
X468992Y86344D01*
X470908D01*
G01X472973Y85466D02*
X473050Y86138D01*
X473165Y86706D01*
X473318Y87223D01*
X473510Y87791D01*
X473817Y88566D01*
X472283D01*
G01X476610Y85466D02*
Y88566D01*
X475192Y86344D01*
X477108D01*
G01X466083Y90466D02*
Y93566D01*
X467042D01*
X467348Y93411D01*
X467540Y93204D01*
X467617Y92791D01*
X467540Y92378D01*
X467310Y92119D01*
X467042Y91964D01*
X466083D01*
G01X467042D02*
X467617Y90466D01*
G01X470410D02*
Y93566D01*
X468992Y91344D01*
X470908D01*
G01X473050Y90466D02*
X473318Y90518D01*
X473625Y90673D01*
X473817Y90931D01*
X473893Y91293D01*
X473817Y91654D01*
X473587Y91964D01*
X473242Y92119D01*
X472858D01*
X472628Y92223D01*
X472437Y92481D01*
X472360Y92843D01*
X472475Y93204D01*
X472743Y93463D01*
X473050Y93566D01*
X473357Y93463D01*
X473625Y93204D01*
X473740Y92843D01*
X473663Y92481D01*
X473472Y92223D01*
X473242Y92119D01*
X472858D01*
X472513Y91964D01*
X472283Y91654D01*
X472207Y91293D01*
X472283Y90931D01*
X472475Y90673D01*
X472782Y90518D01*
X473050Y90466D01*
G01X475422Y91758D02*
X475690Y92119D01*
X475920Y92326D01*
X476227Y92429D01*
X476495Y92326D01*
X476687Y92119D01*
X476840Y91809D01*
X476878Y91448D01*
X476840Y91138D01*
X476687Y90828D01*
X476457Y90569D01*
X476188Y90466D01*
X475882Y90569D01*
X475613Y90879D01*
X475460Y91344D01*
X475422Y91861D01*
X475498Y92533D01*
X475613Y92894D01*
X475805Y93256D01*
X476073Y93514D01*
X476342Y93566D01*
X476610Y93463D01*
X476802Y93204D01*
G01X478450Y88350D02*
X481550D01*
G01X478450Y87468D02*
Y89232D01*
G01X481550Y90683D02*
X478450D01*
Y91603D01*
X478605Y91910D01*
X478967Y92140D01*
X479380Y92217D01*
X479793Y92140D01*
X480103Y91948D01*
X480258Y91603D01*
Y90683D01*
G01X481550Y94550D02*
X478450D01*
X479070Y94090D01*
G01X481550D02*
Y95010D01*
G01X478967Y96922D02*
X478657Y97152D01*
X478502Y97420D01*
X478450Y97727D01*
X478553Y98110D01*
X478812Y98378D01*
X479122Y98455D01*
X479432Y98417D01*
X479690Y98263D01*
X480207Y97497D01*
X480568Y97152D01*
X481085Y96922D01*
X481550Y96845D01*
Y98455D01*
G01X466083Y95466D02*
Y98566D01*
X467042D01*
X467348Y98411D01*
X467540Y98204D01*
X467617Y97791D01*
X467540Y97378D01*
X467310Y97119D01*
X467042Y96964D01*
X466083D01*
G01X467042D02*
X467617Y95466D01*
G01X470410D02*
Y98566D01*
X468992Y96344D01*
X470908D01*
G01X473050Y95466D02*
X473318Y95518D01*
X473625Y95673D01*
X473817Y95931D01*
X473893Y96293D01*
X473817Y96654D01*
X473587Y96964D01*
X473242Y97119D01*
X472858D01*
X472628Y97223D01*
X472437Y97481D01*
X472360Y97843D01*
X472475Y98204D01*
X472743Y98463D01*
X473050Y98566D01*
X473357Y98463D01*
X473625Y98204D01*
X473740Y97843D01*
X473663Y97481D01*
X473472Y97223D01*
X473242Y97119D01*
X472858D01*
X472513Y96964D01*
X472283Y96654D01*
X472207Y96293D01*
X472283Y95931D01*
X472475Y95673D01*
X472782Y95518D01*
X473050Y95466D01*
G01X475307Y95931D02*
X475537Y95673D01*
X475805Y95518D01*
X476150Y95466D01*
X476495Y95569D01*
X476763Y95776D01*
X476955Y96138D01*
X476993Y96551D01*
X476917Y96964D01*
X476725Y97223D01*
X476457Y97429D01*
X476188Y97481D01*
X475920Y97429D01*
X475575Y97223D01*
X475690Y98566D01*
X476725D01*
G01X468533Y121742D02*
X465433Y122700D01*
X468533Y123658D01*
G01X467448Y123313D02*
Y122087D01*
G01X468533Y124842D02*
X465433Y125800D01*
X468533Y126758D01*
G01X467448Y126413D02*
Y125187D01*
G01X473523Y121672D02*
X470423Y122630D01*
X473523Y123588D01*
G01X472438Y123243D02*
Y122017D01*
G01X471870Y126037D02*
X471715Y126190D01*
X471456Y126305D01*
X471095Y126382D01*
X470785Y126305D01*
X470578Y126152D01*
X470423Y125883D01*
Y124848D01*
X473523D01*
Y126113D01*
X473316Y126382D01*
X473006Y126535D01*
X472645Y126612D01*
X472283Y126535D01*
X471973Y126305D01*
X471870Y126037D01*
Y124848D01*
G01X480450Y208350D02*
X483550D01*
G01X480450Y207468D02*
Y209232D01*
G01X483550Y210683D02*
X480450D01*
Y211603D01*
X480605Y211910D01*
X480967Y212140D01*
X481380Y212217D01*
X481793Y212140D01*
X482103Y211948D01*
X482258Y211603D01*
Y210683D01*
G01X483550Y215010D02*
X480450D01*
X482672Y213592D01*
Y215508D01*
G01X483085Y216807D02*
X483343Y217037D01*
X483498Y217305D01*
X483550Y217650D01*
X483447Y217995D01*
X483240Y218263D01*
X482878Y218455D01*
X482465Y218493D01*
X482052Y218417D01*
X481793Y218225D01*
X481587Y217957D01*
X481535Y217688D01*
X481587Y217420D01*
X481793Y217075D01*
X480450Y217190D01*
Y218225D01*
G01X472708Y245093D02*
X472553Y244863D01*
X472450Y244595D01*
Y244288D01*
X472605Y243943D01*
X472863Y243675D01*
X473173Y243483D01*
X473690Y243330D01*
X474155Y243292D01*
X474620Y243368D01*
X474930Y243483D01*
X475240Y243713D01*
X475447Y243982D01*
X475550Y244250D01*
Y244518D01*
X475447Y244787D01*
X475292Y245017D01*
X475085Y245208D01*
G01X475550Y247350D02*
X472450D01*
X473070Y246890D01*
G01X475550D02*
Y247810D01*
G01Y250373D02*
X474878Y250450D01*
X474310Y250565D01*
X473793Y250718D01*
X473225Y250910D01*
X472450Y251217D01*
Y249683D01*
G01X475550Y254010D02*
X472450D01*
X474672Y252592D01*
Y254508D01*
G01X475050Y347083D02*
X471950D01*
Y348042D01*
X472105Y348348D01*
X472312Y348540D01*
X472725Y348617D01*
X473138Y348540D01*
X473397Y348310D01*
X473552Y348042D01*
Y347083D01*
G01Y348042D02*
X475050Y348617D01*
G01Y350950D02*
X471950D01*
X472570Y350490D01*
G01X475050D02*
Y351410D01*
G01Y354050D02*
X471950D01*
X472570Y353590D01*
G01X475050D02*
Y354510D01*
G01Y357610D02*
X471950D01*
X474172Y356192D01*
Y358108D01*
G01X480050Y347083D02*
X476950D01*
Y348042D01*
X477105Y348348D01*
X477312Y348540D01*
X477725Y348617D01*
X478138Y348540D01*
X478397Y348310D01*
X478552Y348042D01*
Y347083D01*
G01Y348042D02*
X480050Y348617D01*
G01Y350950D02*
X476950D01*
X477570Y350490D01*
G01X480050D02*
Y351410D01*
G01Y354050D02*
X476950D01*
X477570Y353590D01*
G01X480050D02*
Y354510D01*
G01X478758Y356422D02*
X478397Y356690D01*
X478190Y356920D01*
X478087Y357227D01*
X478190Y357495D01*
X478397Y357687D01*
X478707Y357840D01*
X479068Y357878D01*
X479378Y357840D01*
X479688Y357687D01*
X479947Y357457D01*
X480050Y357188D01*
X479947Y356882D01*
X479637Y356613D01*
X479172Y356460D01*
X478655Y356422D01*
X477983Y356498D01*
X477622Y356613D01*
X477260Y356805D01*
X477002Y357073D01*
X476950Y357342D01*
X477053Y357610D01*
X477312Y357802D01*
G01X465450Y348850D02*
X468550D01*
G01X465450Y347968D02*
Y349732D01*
G01X468550Y351183D02*
X465450D01*
Y352103D01*
X465605Y352410D01*
X465967Y352640D01*
X466380Y352717D01*
X466793Y352640D01*
X467103Y352448D01*
X467258Y352103D01*
Y351183D01*
G01X468550Y355050D02*
X465450D01*
X466070Y354590D01*
G01X468550D02*
Y355510D01*
G01X468085Y357307D02*
X468343Y357537D01*
X468498Y357805D01*
X468550Y358150D01*
X468447Y358495D01*
X468240Y358763D01*
X467878Y358955D01*
X467465Y358993D01*
X467052Y358917D01*
X466793Y358725D01*
X466587Y358457D01*
X466535Y358188D01*
X466587Y357920D01*
X466793Y357575D01*
X465450Y357690D01*
Y358725D01*
G01X473500Y365000D02*
X473768Y365052D01*
X474075Y365207D01*
X474267Y365465D01*
X474343Y365827D01*
X474267Y366188D01*
X474037Y366498D01*
X473692Y366653D01*
X473308D01*
X473078Y366757D01*
X472887Y367015D01*
X472810Y367377D01*
X472925Y367738D01*
X473193Y367997D01*
X473500Y368100D01*
X473807Y367997D01*
X474075Y367738D01*
X474190Y367377D01*
X474113Y367015D01*
X473922Y366757D01*
X473692Y366653D01*
X473308D01*
X472963Y366498D01*
X472733Y366188D01*
X472657Y365827D01*
X472733Y365465D01*
X472925Y365207D01*
X473232Y365052D01*
X473500Y365000D01*
G01X473272Y394083D02*
X473502Y394393D01*
X473770Y394548D01*
X474077Y394600D01*
X474460Y394497D01*
X474728Y394238D01*
X474805Y393928D01*
X474767Y393618D01*
X474613Y393360D01*
X473847Y392843D01*
X473502Y392482D01*
X473272Y391965D01*
X473195Y391500D01*
X474805D01*
G01X482500Y73000D02*
X482768Y73052D01*
X483075Y73207D01*
X483267Y73465D01*
X483343Y73827D01*
X483267Y74188D01*
X483037Y74498D01*
X482692Y74653D01*
X482308D01*
X482078Y74757D01*
X481887Y75015D01*
X481810Y75377D01*
X481925Y75738D01*
X482193Y75997D01*
X482500Y76100D01*
X482807Y75997D01*
X483075Y75738D01*
X483190Y75377D01*
X483113Y75015D01*
X482922Y74757D01*
X482692Y74653D01*
X482308D01*
X481963Y74498D01*
X481733Y74188D01*
X481657Y73827D01*
X481733Y73465D01*
X481925Y73207D01*
X482232Y73052D01*
X482500Y73000D01*
G01X496557Y85066D02*
Y82844D01*
X496710Y82379D01*
X497017Y82069D01*
X497400Y81966D01*
X497783Y82069D01*
X498090Y82379D01*
X498243Y82844D01*
Y85066D01*
G01X499657Y82586D02*
X499887Y82224D01*
X500193Y82018D01*
X500538Y81966D01*
X500845Y82018D01*
X501152Y82276D01*
X501343Y82586D01*
X501382Y82896D01*
X501305Y83258D01*
X501037Y83516D01*
X500768Y83619D01*
X500423D01*
G01X500768D02*
X500998Y83774D01*
X501190Y84033D01*
X501267Y84343D01*
X501190Y84653D01*
X500998Y84911D01*
X500653Y85066D01*
X500308Y85014D01*
X499963Y84808D01*
G01X503523Y81966D02*
X503600Y82638D01*
X503715Y83206D01*
X503868Y83723D01*
X504060Y84291D01*
X504367Y85066D01*
X502833D01*
G01X493293Y127142D02*
X493063Y127297D01*
X492795Y127400D01*
X492488D01*
X492143Y127245D01*
X491875Y126987D01*
X491683Y126677D01*
X491530Y126160D01*
X491492Y125695D01*
X491568Y125230D01*
X491683Y124920D01*
X491913Y124610D01*
X492182Y124403D01*
X492450Y124300D01*
X492718D01*
X492987Y124403D01*
X493217Y124558D01*
X493408Y124765D01*
G01X494822Y126883D02*
X495052Y127193D01*
X495320Y127348D01*
X495627Y127400D01*
X496010Y127297D01*
X496278Y127038D01*
X496355Y126728D01*
X496317Y126418D01*
X496163Y126160D01*
X495397Y125643D01*
X495052Y125282D01*
X494822Y124765D01*
X494745Y124300D01*
X496355D01*
G01X497998Y124662D02*
X498267Y124403D01*
X498573Y124300D01*
X498880Y124403D01*
X499148Y124713D01*
X499340Y125178D01*
X499417Y125643D01*
Y126212D01*
X499340Y126677D01*
X499148Y127090D01*
X498918Y127297D01*
X498650Y127400D01*
X498343Y127297D01*
X498113Y127090D01*
X497960Y126780D01*
X497883Y126367D01*
X497960Y126005D01*
X498152Y125643D01*
X498382Y125437D01*
X498650Y125385D01*
X498957Y125488D01*
X499187Y125747D01*
X499417Y126212D01*
G01X501022Y126883D02*
X501252Y127193D01*
X501520Y127348D01*
X501827Y127400D01*
X502210Y127297D01*
X502478Y127038D01*
X502555Y126728D01*
X502517Y126418D01*
X502363Y126160D01*
X501597Y125643D01*
X501252Y125282D01*
X501022Y124765D01*
X500945Y124300D01*
X502555D01*
G01X492583Y136950D02*
Y140050D01*
X493542D01*
X493848Y139895D01*
X494040Y139688D01*
X494117Y139275D01*
X494040Y138862D01*
X493810Y138603D01*
X493542Y138448D01*
X492583D01*
G01X493542D02*
X494117Y136950D01*
G01X495722Y139533D02*
X495952Y139843D01*
X496220Y139998D01*
X496527Y140050D01*
X496910Y139947D01*
X497178Y139688D01*
X497255Y139378D01*
X497217Y139068D01*
X497063Y138810D01*
X496297Y138293D01*
X495952Y137932D01*
X495722Y137415D01*
X495645Y136950D01*
X497255D01*
G01X498822Y139533D02*
X499052Y139843D01*
X499320Y139998D01*
X499627Y140050D01*
X500010Y139947D01*
X500278Y139688D01*
X500355Y139378D01*
X500317Y139068D01*
X500163Y138810D01*
X499397Y138293D01*
X499052Y137932D01*
X498822Y137415D01*
X498745Y136950D01*
X500355D01*
G01X502650D02*
Y140050D01*
X502190Y139430D01*
G01Y136950D02*
X503110D01*
G01X492583Y141450D02*
Y144550D01*
X493542D01*
X493848Y144395D01*
X494040Y144188D01*
X494117Y143775D01*
X494040Y143362D01*
X493810Y143103D01*
X493542Y142948D01*
X492583D01*
G01X493542D02*
X494117Y141450D01*
G01X495722Y144033D02*
X495952Y144343D01*
X496220Y144498D01*
X496527Y144550D01*
X496910Y144447D01*
X497178Y144188D01*
X497255Y143878D01*
X497217Y143568D01*
X497063Y143310D01*
X496297Y142793D01*
X495952Y142432D01*
X495722Y141915D01*
X495645Y141450D01*
X497255D01*
G01X498822Y144033D02*
X499052Y144343D01*
X499320Y144498D01*
X499627Y144550D01*
X500010Y144447D01*
X500278Y144188D01*
X500355Y143878D01*
X500317Y143568D01*
X500163Y143310D01*
X499397Y142793D01*
X499052Y142432D01*
X498822Y141915D01*
X498745Y141450D01*
X500355D01*
G01X501922Y144033D02*
X502152Y144343D01*
X502420Y144498D01*
X502727Y144550D01*
X503110Y144447D01*
X503378Y144188D01*
X503455Y143878D01*
X503417Y143568D01*
X503263Y143310D01*
X502497Y142793D01*
X502152Y142432D01*
X501922Y141915D01*
X501845Y141450D01*
X503455D01*
G01X492583Y131950D02*
Y135050D01*
X493542D01*
X493848Y134895D01*
X494040Y134688D01*
X494117Y134275D01*
X494040Y133862D01*
X493810Y133603D01*
X493542Y133448D01*
X492583D01*
G01X493542D02*
X494117Y131950D01*
G01X496450D02*
Y135050D01*
X495990Y134430D01*
G01Y131950D02*
X496910D01*
G01X498898Y132312D02*
X499167Y132053D01*
X499473Y131950D01*
X499780Y132053D01*
X500048Y132363D01*
X500240Y132828D01*
X500317Y133293D01*
Y133862D01*
X500240Y134327D01*
X500048Y134740D01*
X499818Y134947D01*
X499550Y135050D01*
X499243Y134947D01*
X499013Y134740D01*
X498860Y134430D01*
X498783Y134017D01*
X498860Y133655D01*
X499052Y133293D01*
X499282Y133087D01*
X499550Y133035D01*
X499857Y133138D01*
X500087Y133397D01*
X500317Y133862D01*
G01X503110Y131950D02*
Y135050D01*
X501692Y132828D01*
X503608D01*
G01X486633Y161450D02*
Y164550D01*
X487592D01*
X487898Y164395D01*
X488090Y164188D01*
X488167Y163775D01*
X488090Y163362D01*
X487860Y163103D01*
X487592Y162948D01*
X486633D01*
G01X487592D02*
X488167Y161450D01*
G01X489848Y161812D02*
X490117Y161553D01*
X490423Y161450D01*
X490730Y161553D01*
X490998Y161863D01*
X491190Y162328D01*
X491267Y162793D01*
Y163362D01*
X491190Y163827D01*
X490998Y164240D01*
X490768Y164447D01*
X490500Y164550D01*
X490193Y164447D01*
X489963Y164240D01*
X489810Y163930D01*
X489733Y163517D01*
X489810Y163155D01*
X490002Y162793D01*
X490232Y162587D01*
X490500Y162535D01*
X490807Y162638D01*
X491037Y162897D01*
X491267Y163362D01*
G01X492757Y162070D02*
X492987Y161708D01*
X493293Y161502D01*
X493638Y161450D01*
X493945Y161502D01*
X494252Y161760D01*
X494443Y162070D01*
X494482Y162380D01*
X494405Y162742D01*
X494137Y163000D01*
X493868Y163103D01*
X493523D01*
G01X493868D02*
X494098Y163258D01*
X494290Y163517D01*
X494367Y163827D01*
X494290Y164137D01*
X494098Y164395D01*
X493753Y164550D01*
X493408Y164498D01*
X493063Y164292D01*
G01X492933Y155591D02*
Y152491D01*
G01X492051Y155591D02*
X493815D01*
G01X495266Y152491D02*
Y155591D01*
X496186D01*
X496493Y155436D01*
X496723Y155074D01*
X496800Y154661D01*
X496723Y154248D01*
X496531Y153938D01*
X496186Y153783D01*
X495266D01*
G01X498405D02*
X498673Y154144D01*
X498903Y154351D01*
X499210Y154454D01*
X499478Y154351D01*
X499670Y154144D01*
X499823Y153834D01*
X499861Y153473D01*
X499823Y153163D01*
X499670Y152853D01*
X499440Y152594D01*
X499171Y152491D01*
X498865Y152594D01*
X498596Y152904D01*
X498443Y153369D01*
X498405Y153886D01*
X498481Y154558D01*
X498596Y154919D01*
X498788Y155281D01*
X499056Y155539D01*
X499325Y155591D01*
X499593Y155488D01*
X499785Y155229D01*
G01X501505Y155074D02*
X501735Y155384D01*
X502003Y155539D01*
X502310Y155591D01*
X502693Y155488D01*
X502961Y155229D01*
X503038Y154919D01*
X503000Y154609D01*
X502846Y154351D01*
X502080Y153834D01*
X501735Y153473D01*
X501505Y152956D01*
X501428Y152491D01*
X503038D01*
G01X485083Y165950D02*
Y169050D01*
X486042D01*
X486348Y168895D01*
X486540Y168688D01*
X486617Y168275D01*
X486540Y167862D01*
X486310Y167603D01*
X486042Y167448D01*
X485083D01*
G01X486042D02*
X486617Y165950D01*
G01X488222Y168533D02*
X488452Y168843D01*
X488720Y168998D01*
X489027Y169050D01*
X489410Y168947D01*
X489678Y168688D01*
X489755Y168378D01*
X489717Y168068D01*
X489563Y167810D01*
X488797Y167293D01*
X488452Y166932D01*
X488222Y166415D01*
X488145Y165950D01*
X489755D01*
G01X492050D02*
X492318Y166002D01*
X492625Y166157D01*
X492817Y166415D01*
X492893Y166777D01*
X492817Y167138D01*
X492587Y167448D01*
X492242Y167603D01*
X491858D01*
X491628Y167707D01*
X491437Y167965D01*
X491360Y168327D01*
X491475Y168688D01*
X491743Y168947D01*
X492050Y169050D01*
X492357Y168947D01*
X492625Y168688D01*
X492740Y168327D01*
X492663Y167965D01*
X492472Y167707D01*
X492242Y167603D01*
X491858D01*
X491513Y167448D01*
X491283Y167138D01*
X491207Y166777D01*
X491283Y166415D01*
X491475Y166157D01*
X491782Y166002D01*
X492050Y165950D01*
G01X495150D02*
X495418Y166002D01*
X495725Y166157D01*
X495917Y166415D01*
X495993Y166777D01*
X495917Y167138D01*
X495687Y167448D01*
X495342Y167603D01*
X494958D01*
X494728Y167707D01*
X494537Y167965D01*
X494460Y168327D01*
X494575Y168688D01*
X494843Y168947D01*
X495150Y169050D01*
X495457Y168947D01*
X495725Y168688D01*
X495840Y168327D01*
X495763Y167965D01*
X495572Y167707D01*
X495342Y167603D01*
X494958D01*
X494613Y167448D01*
X494383Y167138D01*
X494307Y166777D01*
X494383Y166415D01*
X494575Y166157D01*
X494882Y166002D01*
X495150Y165950D01*
G01X485083Y174950D02*
Y178050D01*
X486042D01*
X486348Y177895D01*
X486540Y177688D01*
X486617Y177275D01*
X486540Y176862D01*
X486310Y176603D01*
X486042Y176448D01*
X485083D01*
G01X486042D02*
X486617Y174950D01*
G01X488222Y177533D02*
X488452Y177843D01*
X488720Y177998D01*
X489027Y178050D01*
X489410Y177947D01*
X489678Y177688D01*
X489755Y177378D01*
X489717Y177068D01*
X489563Y176810D01*
X488797Y176293D01*
X488452Y175932D01*
X488222Y175415D01*
X488145Y174950D01*
X489755D01*
G01X492050D02*
Y178050D01*
X491590Y177430D01*
G01Y174950D02*
X492510D01*
G01X495150D02*
Y178050D01*
X494690Y177430D01*
G01Y174950D02*
X495610D01*
G01X485083Y170450D02*
Y173550D01*
X486042D01*
X486348Y173395D01*
X486540Y173188D01*
X486617Y172775D01*
X486540Y172362D01*
X486310Y172103D01*
X486042Y171948D01*
X485083D01*
G01X486042D02*
X486617Y170450D01*
G01X488222Y173033D02*
X488452Y173343D01*
X488720Y173498D01*
X489027Y173550D01*
X489410Y173447D01*
X489678Y173188D01*
X489755Y172878D01*
X489717Y172568D01*
X489563Y172310D01*
X488797Y171793D01*
X488452Y171432D01*
X488222Y170915D01*
X488145Y170450D01*
X489755D01*
G01X492050D02*
Y173550D01*
X491590Y172930D01*
G01Y170450D02*
X492510D01*
G01X494422Y173033D02*
X494652Y173343D01*
X494920Y173498D01*
X495227Y173550D01*
X495610Y173447D01*
X495878Y173188D01*
X495955Y172878D01*
X495917Y172568D01*
X495763Y172310D01*
X494997Y171793D01*
X494652Y171432D01*
X494422Y170915D01*
X494345Y170450D01*
X495955D01*
G01X486633Y195950D02*
Y199050D01*
X487592D01*
X487898Y198895D01*
X488090Y198688D01*
X488167Y198275D01*
X488090Y197862D01*
X487860Y197603D01*
X487592Y197448D01*
X486633D01*
G01X487592D02*
X488167Y195950D01*
G01X489848Y196312D02*
X490117Y196053D01*
X490423Y195950D01*
X490730Y196053D01*
X490998Y196363D01*
X491190Y196828D01*
X491267Y197293D01*
Y197862D01*
X491190Y198327D01*
X490998Y198740D01*
X490768Y198947D01*
X490500Y199050D01*
X490193Y198947D01*
X489963Y198740D01*
X489810Y198430D01*
X489733Y198017D01*
X489810Y197655D01*
X490002Y197293D01*
X490232Y197087D01*
X490500Y197035D01*
X490807Y197138D01*
X491037Y197397D01*
X491267Y197862D01*
G01X494060Y195950D02*
Y199050D01*
X492642Y196828D01*
X494558D01*
G01X485083Y209950D02*
Y213050D01*
X486042D01*
X486348Y212895D01*
X486540Y212688D01*
X486617Y212275D01*
X486540Y211862D01*
X486310Y211603D01*
X486042Y211448D01*
X485083D01*
G01X486042D02*
X486617Y209950D01*
G01X488950D02*
Y213050D01*
X488490Y212430D01*
G01Y209950D02*
X489410D01*
G01X491398Y210312D02*
X491667Y210053D01*
X491973Y209950D01*
X492280Y210053D01*
X492548Y210363D01*
X492740Y210828D01*
X492817Y211293D01*
Y211862D01*
X492740Y212327D01*
X492548Y212740D01*
X492318Y212947D01*
X492050Y213050D01*
X491743Y212947D01*
X491513Y212740D01*
X491360Y212430D01*
X491283Y212017D01*
X491360Y211655D01*
X491552Y211293D01*
X491782Y211087D01*
X492050Y211035D01*
X492357Y211138D01*
X492587Y211397D01*
X492817Y211862D01*
G01X494307Y210570D02*
X494537Y210208D01*
X494843Y210002D01*
X495188Y209950D01*
X495495Y210002D01*
X495802Y210260D01*
X495993Y210570D01*
X496032Y210880D01*
X495955Y211242D01*
X495687Y211500D01*
X495418Y211603D01*
X495073D01*
G01X495418D02*
X495648Y211758D01*
X495840Y212017D01*
X495917Y212327D01*
X495840Y212637D01*
X495648Y212895D01*
X495303Y213050D01*
X494958Y212998D01*
X494613Y212792D01*
G01X486633Y200950D02*
Y204050D01*
X487592D01*
X487898Y203895D01*
X488090Y203688D01*
X488167Y203275D01*
X488090Y202862D01*
X487860Y202603D01*
X487592Y202448D01*
X486633D01*
G01X487592D02*
X488167Y200950D01*
G01X489848Y201312D02*
X490117Y201053D01*
X490423Y200950D01*
X490730Y201053D01*
X490998Y201363D01*
X491190Y201828D01*
X491267Y202293D01*
Y202862D01*
X491190Y203327D01*
X490998Y203740D01*
X490768Y203947D01*
X490500Y204050D01*
X490193Y203947D01*
X489963Y203740D01*
X489810Y203430D01*
X489733Y203017D01*
X489810Y202655D01*
X490002Y202293D01*
X490232Y202087D01*
X490500Y202035D01*
X490807Y202138D01*
X491037Y202397D01*
X491267Y202862D01*
G01X492757Y201415D02*
X492987Y201157D01*
X493255Y201002D01*
X493600Y200950D01*
X493945Y201053D01*
X494213Y201260D01*
X494405Y201622D01*
X494443Y202035D01*
X494367Y202448D01*
X494175Y202707D01*
X493907Y202913D01*
X493638Y202965D01*
X493370Y202913D01*
X493025Y202707D01*
X493140Y204050D01*
X494175D01*
G01X485083Y205966D02*
Y209066D01*
X486042D01*
X486348Y208911D01*
X486540Y208704D01*
X486617Y208291D01*
X486540Y207878D01*
X486310Y207619D01*
X486042Y207464D01*
X485083D01*
G01X486042D02*
X486617Y205966D01*
G01X488107Y206586D02*
X488337Y206224D01*
X488643Y206018D01*
X488988Y205966D01*
X489295Y206018D01*
X489602Y206276D01*
X489793Y206586D01*
X489832Y206896D01*
X489755Y207258D01*
X489487Y207516D01*
X489218Y207619D01*
X488873D01*
G01X489218D02*
X489448Y207774D01*
X489640Y208033D01*
X489717Y208343D01*
X489640Y208653D01*
X489448Y208911D01*
X489103Y209066D01*
X488758Y209014D01*
X488413Y208808D01*
G01X491207Y206431D02*
X491437Y206173D01*
X491705Y206018D01*
X492050Y205966D01*
X492395Y206069D01*
X492663Y206276D01*
X492855Y206638D01*
X492893Y207051D01*
X492817Y207464D01*
X492625Y207723D01*
X492357Y207929D01*
X492088Y207981D01*
X491820Y207929D01*
X491475Y207723D01*
X491590Y209066D01*
X492625D01*
G01X494422Y207258D02*
X494690Y207619D01*
X494920Y207826D01*
X495227Y207929D01*
X495495Y207826D01*
X495687Y207619D01*
X495840Y207309D01*
X495878Y206948D01*
X495840Y206638D01*
X495687Y206328D01*
X495457Y206069D01*
X495188Y205966D01*
X494882Y206069D01*
X494613Y206379D01*
X494460Y206844D01*
X494422Y207361D01*
X494498Y208033D01*
X494613Y208394D01*
X494805Y208756D01*
X495073Y209014D01*
X495342Y209066D01*
X495610Y208963D01*
X495802Y208704D01*
G01X499693Y248692D02*
X499463Y248847D01*
X499195Y248950D01*
X498888D01*
X498543Y248795D01*
X498275Y248537D01*
X498083Y248227D01*
X497930Y247710D01*
X497892Y247245D01*
X497968Y246780D01*
X498083Y246470D01*
X498313Y246160D01*
X498582Y245953D01*
X498850Y245850D01*
X499118D01*
X499387Y245953D01*
X499617Y246108D01*
X499808Y246315D01*
G01X501950Y245850D02*
Y248950D01*
X501490Y248330D01*
G01Y245850D02*
X502410D01*
G01X505050D02*
X505318Y245902D01*
X505625Y246057D01*
X505817Y246315D01*
X505893Y246677D01*
X505817Y247038D01*
X505587Y247348D01*
X505242Y247503D01*
X504858D01*
X504628Y247607D01*
X504437Y247865D01*
X504360Y248227D01*
X504475Y248588D01*
X504743Y248847D01*
X505050Y248950D01*
X505357Y248847D01*
X505625Y248588D01*
X505740Y248227D01*
X505663Y247865D01*
X505472Y247607D01*
X505242Y247503D01*
X504858D01*
X504513Y247348D01*
X504283Y247038D01*
X504207Y246677D01*
X504283Y246315D01*
X504475Y246057D01*
X504782Y245902D01*
X505050Y245850D01*
G01X507307Y246470D02*
X507537Y246108D01*
X507843Y245902D01*
X508188Y245850D01*
X508495Y245902D01*
X508802Y246160D01*
X508993Y246470D01*
X509032Y246780D01*
X508955Y247142D01*
X508687Y247400D01*
X508418Y247503D01*
X508073D01*
G01X508418D02*
X508648Y247658D01*
X508840Y247917D01*
X508917Y248227D01*
X508840Y248537D01*
X508648Y248795D01*
X508303Y248950D01*
X507958Y248898D01*
X507613Y248692D01*
G01X491750Y246983D02*
X494850D01*
Y248517D01*
G01X493558Y250122D02*
X493197Y250390D01*
X492990Y250620D01*
X492887Y250927D01*
X492990Y251195D01*
X493197Y251387D01*
X493507Y251540D01*
X493868Y251578D01*
X494178Y251540D01*
X494488Y251387D01*
X494747Y251157D01*
X494850Y250888D01*
X494747Y250582D01*
X494437Y250313D01*
X493972Y250160D01*
X493455Y250122D01*
X492783Y250198D01*
X492422Y250313D01*
X492060Y250505D01*
X491802Y250773D01*
X491750Y251042D01*
X491853Y251310D01*
X492112Y251502D01*
G01X494808Y266893D02*
X494653Y266663D01*
X494550Y266395D01*
Y266088D01*
X494705Y265743D01*
X494963Y265475D01*
X495273Y265283D01*
X495790Y265130D01*
X496255Y265092D01*
X496720Y265168D01*
X497030Y265283D01*
X497340Y265513D01*
X497547Y265782D01*
X497650Y266050D01*
Y266318D01*
X497547Y266587D01*
X497392Y266817D01*
X497185Y267008D01*
G01X497650Y269150D02*
X494550D01*
X495170Y268690D01*
G01X497650D02*
Y269610D01*
G01Y272250D02*
X497598Y272518D01*
X497443Y272825D01*
X497185Y273017D01*
X496823Y273093D01*
X496462Y273017D01*
X496152Y272787D01*
X495997Y272442D01*
Y272058D01*
X495893Y271828D01*
X495635Y271637D01*
X495273Y271560D01*
X494912Y271675D01*
X494653Y271943D01*
X494550Y272250D01*
X494653Y272557D01*
X494912Y272825D01*
X495273Y272940D01*
X495635Y272863D01*
X495893Y272672D01*
X495997Y272442D01*
Y272058D01*
X496152Y271713D01*
X496462Y271483D01*
X496823Y271407D01*
X497185Y271483D01*
X497443Y271675D01*
X497598Y271982D01*
X497650Y272250D01*
G01Y275273D02*
X496978Y275350D01*
X496410Y275465D01*
X495893Y275618D01*
X495325Y275810D01*
X494550Y276117D01*
Y274583D01*
G01X497500Y253083D02*
X494400D01*
Y254042D01*
X494555Y254348D01*
X494762Y254540D01*
X495175Y254617D01*
X495588Y254540D01*
X495847Y254310D01*
X496002Y254042D01*
Y253083D01*
G01Y254042D02*
X497500Y254617D01*
G01Y256950D02*
X494400D01*
X495020Y256490D01*
G01X497500D02*
Y257410D01*
G01X496208Y259322D02*
X495847Y259590D01*
X495640Y259820D01*
X495537Y260127D01*
X495640Y260395D01*
X495847Y260587D01*
X496157Y260740D01*
X496518Y260778D01*
X496828Y260740D01*
X497138Y260587D01*
X497397Y260357D01*
X497500Y260088D01*
X497397Y259782D01*
X497087Y259513D01*
X496622Y259360D01*
X496105Y259322D01*
X495433Y259398D01*
X495072Y259513D01*
X494710Y259705D01*
X494452Y259973D01*
X494400Y260242D01*
X494503Y260510D01*
X494762Y260702D01*
G01X496208Y262422D02*
X495847Y262690D01*
X495640Y262920D01*
X495537Y263227D01*
X495640Y263495D01*
X495847Y263687D01*
X496157Y263840D01*
X496518Y263878D01*
X496828Y263840D01*
X497138Y263687D01*
X497397Y263457D01*
X497500Y263188D01*
X497397Y262882D01*
X497087Y262613D01*
X496622Y262460D01*
X496105Y262422D01*
X495433Y262498D01*
X495072Y262613D01*
X494710Y262805D01*
X494452Y263073D01*
X494400Y263342D01*
X494503Y263610D01*
X494762Y263802D01*
G01X490450Y265283D02*
X487350D01*
Y266242D01*
X487505Y266548D01*
X487712Y266740D01*
X488125Y266817D01*
X488538Y266740D01*
X488797Y266510D01*
X488952Y266242D01*
Y265283D01*
G01Y266242D02*
X490450Y266817D01*
G01Y269150D02*
X487350D01*
X487970Y268690D01*
G01X490450D02*
Y269610D01*
G01Y272710D02*
X487350D01*
X489572Y271292D01*
Y273208D01*
G01X490450Y275350D02*
X487350D01*
X487970Y274890D01*
G01X490450D02*
Y275810D01*
G01X481450Y268350D02*
X484550D01*
G01X481450Y267468D02*
Y269232D01*
G01X484550Y270683D02*
X481450D01*
Y271603D01*
X481605Y271910D01*
X481967Y272140D01*
X482380Y272217D01*
X482793Y272140D01*
X483103Y271948D01*
X483258Y271603D01*
Y270683D01*
G01X484550Y275010D02*
X481450D01*
X483672Y273592D01*
Y275508D01*
G01X481450Y277650D02*
X481553Y277343D01*
X481812Y277113D01*
X482122Y276960D01*
X482535Y276845D01*
X483000Y276807D01*
X483465Y276845D01*
X483878Y276960D01*
X484188Y277113D01*
X484447Y277343D01*
X484550Y277650D01*
X484447Y277957D01*
X484188Y278187D01*
X483878Y278340D01*
X483465Y278455D01*
X483000Y278493D01*
X482535Y278455D01*
X482122Y278340D01*
X481812Y278187D01*
X481553Y277957D01*
X481450Y277650D01*
G01X492193Y280342D02*
X491963Y280497D01*
X491695Y280600D01*
X491388D01*
X491043Y280445D01*
X490775Y280187D01*
X490583Y279877D01*
X490430Y279360D01*
X490392Y278895D01*
X490468Y278430D01*
X490583Y278120D01*
X490813Y277810D01*
X491082Y277603D01*
X491350Y277500D01*
X491618D01*
X491887Y277603D01*
X492117Y277758D01*
X492308Y277965D01*
G01X494450Y277500D02*
Y280600D01*
X493990Y279980D01*
G01Y277500D02*
X494910D01*
G01X496898Y277862D02*
X497167Y277603D01*
X497473Y277500D01*
X497780Y277603D01*
X498048Y277913D01*
X498240Y278378D01*
X498317Y278843D01*
Y279412D01*
X498240Y279877D01*
X498048Y280290D01*
X497818Y280497D01*
X497550Y280600D01*
X497243Y280497D01*
X497013Y280290D01*
X496860Y279980D01*
X496783Y279567D01*
X496860Y279205D01*
X497052Y278843D01*
X497282Y278637D01*
X497550Y278585D01*
X497857Y278688D01*
X498087Y278947D01*
X498317Y279412D01*
G01X500650Y277500D02*
Y280600D01*
X500190Y279980D01*
G01Y277500D02*
X501110D01*
G01X489997Y308096D02*
Y311196D01*
X490994Y308613D01*
X491991Y311196D01*
Y308096D01*
G01X494861D02*
X493327D01*
Y311196D01*
X494861D01*
G01X494247Y309698D02*
X493327D01*
G01X497654Y308096D02*
Y311196D01*
X496236Y308974D01*
X498152D01*
G01X490050Y347083D02*
X486950D01*
Y348042D01*
X487105Y348348D01*
X487312Y348540D01*
X487725Y348617D01*
X488138Y348540D01*
X488397Y348310D01*
X488552Y348042D01*
Y347083D01*
G01Y348042D02*
X490050Y348617D01*
G01Y350950D02*
X486950D01*
X487570Y350490D01*
G01X490050D02*
Y351410D01*
G01Y354050D02*
X486950D01*
X487570Y353590D01*
G01X490050D02*
Y354510D01*
G01X489430Y356307D02*
X489792Y356537D01*
X489998Y356843D01*
X490050Y357188D01*
X489998Y357495D01*
X489740Y357802D01*
X489430Y357993D01*
X489120Y358032D01*
X488758Y357955D01*
X488500Y357687D01*
X488397Y357418D01*
Y357073D01*
G01Y357418D02*
X488242Y357648D01*
X487983Y357840D01*
X487673Y357917D01*
X487363Y357840D01*
X487105Y357648D01*
X486950Y357303D01*
X487002Y356958D01*
X487208Y356613D01*
G01X485050Y347083D02*
X481950D01*
Y348042D01*
X482105Y348348D01*
X482312Y348540D01*
X482725Y348617D01*
X483138Y348540D01*
X483397Y348310D01*
X483552Y348042D01*
Y347083D01*
G01Y348042D02*
X485050Y348617D01*
G01Y350950D02*
X481950D01*
X482570Y350490D01*
G01X485050D02*
Y351410D01*
G01Y354050D02*
X481950D01*
X482570Y353590D01*
G01X485050D02*
Y354510D01*
G01Y357073D02*
X484378Y357150D01*
X483810Y357265D01*
X483293Y357418D01*
X482725Y357610D01*
X481950Y357917D01*
Y356383D01*
G01X500050Y347083D02*
X496950D01*
Y348042D01*
X497105Y348348D01*
X497312Y348540D01*
X497725Y348617D01*
X498138Y348540D01*
X498397Y348310D01*
X498552Y348042D01*
Y347083D01*
G01Y348042D02*
X500050Y348617D01*
G01Y350950D02*
X496950D01*
X497570Y350490D01*
G01X500050D02*
Y351410D01*
G01Y354050D02*
X496950D01*
X497570Y353590D01*
G01X500050D02*
Y354510D01*
G01X497467Y356422D02*
X497157Y356652D01*
X497002Y356920D01*
X496950Y357227D01*
X497053Y357610D01*
X497312Y357878D01*
X497622Y357955D01*
X497932Y357917D01*
X498190Y357763D01*
X498707Y356997D01*
X499068Y356652D01*
X499585Y356422D01*
X500050Y356345D01*
Y357955D01*
G01X495050Y347083D02*
X491950D01*
Y348042D01*
X492105Y348348D01*
X492312Y348540D01*
X492725Y348617D01*
X493138Y348540D01*
X493397Y348310D01*
X493552Y348042D01*
Y347083D01*
G01Y348042D02*
X495050Y348617D01*
G01X492467Y350222D02*
X492157Y350452D01*
X492002Y350720D01*
X491950Y351027D01*
X492053Y351410D01*
X492312Y351678D01*
X492622Y351755D01*
X492932Y351717D01*
X493190Y351563D01*
X493707Y350797D01*
X494068Y350452D01*
X494585Y350222D01*
X495050Y350145D01*
Y351755D01*
G01X493758Y353322D02*
X493397Y353590D01*
X493190Y353820D01*
X493087Y354127D01*
X493190Y354395D01*
X493397Y354587D01*
X493707Y354740D01*
X494068Y354778D01*
X494378Y354740D01*
X494688Y354587D01*
X494947Y354357D01*
X495050Y354088D01*
X494947Y353782D01*
X494637Y353513D01*
X494172Y353360D01*
X493655Y353322D01*
X492983Y353398D01*
X492622Y353513D01*
X492260Y353705D01*
X492002Y353973D01*
X491950Y354242D01*
X492053Y354510D01*
X492312Y354702D01*
G01X495050Y357150D02*
X494998Y357418D01*
X494843Y357725D01*
X494585Y357917D01*
X494223Y357993D01*
X493862Y357917D01*
X493552Y357687D01*
X493397Y357342D01*
Y356958D01*
X493293Y356728D01*
X493035Y356537D01*
X492673Y356460D01*
X492312Y356575D01*
X492053Y356843D01*
X491950Y357150D01*
X492053Y357457D01*
X492312Y357725D01*
X492673Y357840D01*
X493035Y357763D01*
X493293Y357572D01*
X493397Y357342D01*
Y356958D01*
X493552Y356613D01*
X493862Y356383D01*
X494223Y356307D01*
X494585Y356383D01*
X494843Y356575D01*
X494998Y356882D01*
X495050Y357150D01*
G01X496572Y364705D02*
X496649Y365377D01*
X496764Y365945D01*
X496917Y366462D01*
X497109Y367030D01*
X497416Y367805D01*
X495882D01*
G01X495500Y391000D02*
Y394100D01*
X495040Y393480D01*
G01Y391000D02*
X495960D01*
G01X486652Y376699D02*
X483552D01*
Y377619D01*
X483707Y377926D01*
X484069Y378156D01*
X484482Y378233D01*
X484895Y378156D01*
X485205Y377964D01*
X485360Y377619D01*
Y376699D01*
G01X484069Y379838D02*
X483759Y380068D01*
X483604Y380336D01*
X483552Y380643D01*
X483655Y381026D01*
X483914Y381294D01*
X484224Y381371D01*
X484534Y381333D01*
X484792Y381179D01*
X485309Y380413D01*
X485670Y380068D01*
X486187Y379838D01*
X486652Y379761D01*
Y381371D01*
G01X489997Y410458D02*
Y413558D01*
X490994Y410975D01*
X491991Y413558D01*
Y410458D01*
G01X494861D02*
X493327D01*
Y413558D01*
X494861D01*
G01X494247Y412060D02*
X493327D01*
G01X496351Y411078D02*
X496581Y410716D01*
X496887Y410510D01*
X497232Y410458D01*
X497539Y410510D01*
X497846Y410768D01*
X498037Y411078D01*
X498076Y411388D01*
X497999Y411750D01*
X497731Y412008D01*
X497462Y412111D01*
X497117D01*
G01X497462D02*
X497692Y412266D01*
X497884Y412525D01*
X497961Y412835D01*
X497884Y413145D01*
X497692Y413403D01*
X497347Y413558D01*
X497002Y413506D01*
X496657Y413300D01*
G01X515693Y253392D02*
X515463Y253547D01*
X515195Y253650D01*
X514888D01*
X514543Y253495D01*
X514275Y253237D01*
X514083Y252927D01*
X513930Y252410D01*
X513892Y251945D01*
X513968Y251480D01*
X514083Y251170D01*
X514313Y250860D01*
X514582Y250653D01*
X514850Y250550D01*
X515118D01*
X515387Y250653D01*
X515617Y250808D01*
X515808Y251015D01*
G01X517950Y250550D02*
Y253650D01*
X517490Y253030D01*
G01Y250550D02*
X518410D01*
G01X520398Y250912D02*
X520667Y250653D01*
X520973Y250550D01*
X521280Y250653D01*
X521548Y250963D01*
X521740Y251428D01*
X521817Y251893D01*
Y252462D01*
X521740Y252927D01*
X521548Y253340D01*
X521318Y253547D01*
X521050Y253650D01*
X520743Y253547D01*
X520513Y253340D01*
X520360Y253030D01*
X520283Y252617D01*
X520360Y252255D01*
X520552Y251893D01*
X520782Y251687D01*
X521050Y251635D01*
X521357Y251738D01*
X521587Y251997D01*
X521817Y252462D01*
G01X523307Y251015D02*
X523537Y250757D01*
X523805Y250602D01*
X524150Y250550D01*
X524495Y250653D01*
X524763Y250860D01*
X524955Y251222D01*
X524993Y251635D01*
X524917Y252048D01*
X524725Y252307D01*
X524457Y252513D01*
X524188Y252565D01*
X523920Y252513D01*
X523575Y252307D01*
X523690Y253650D01*
X524725D01*
G01X500893Y254692D02*
X500663Y254847D01*
X500395Y254950D01*
X500088D01*
X499743Y254795D01*
X499475Y254537D01*
X499283Y254227D01*
X499130Y253710D01*
X499092Y253245D01*
X499168Y252780D01*
X499283Y252470D01*
X499513Y252160D01*
X499782Y251953D01*
X500050Y251850D01*
X500318D01*
X500587Y251953D01*
X500817Y252108D01*
X501008Y252315D01*
G01X503150Y251850D02*
Y254950D01*
X502690Y254330D01*
G01Y251850D02*
X503610D01*
G01X506250D02*
X506518Y251902D01*
X506825Y252057D01*
X507017Y252315D01*
X507093Y252677D01*
X507017Y253038D01*
X506787Y253348D01*
X506442Y253503D01*
X506058D01*
X505828Y253607D01*
X505637Y253865D01*
X505560Y254227D01*
X505675Y254588D01*
X505943Y254847D01*
X506250Y254950D01*
X506557Y254847D01*
X506825Y254588D01*
X506940Y254227D01*
X506863Y253865D01*
X506672Y253607D01*
X506442Y253503D01*
X506058D01*
X505713Y253348D01*
X505483Y253038D01*
X505407Y252677D01*
X505483Y252315D01*
X505675Y252057D01*
X505982Y251902D01*
X506250Y251850D01*
G01X508622Y253142D02*
X508890Y253503D01*
X509120Y253710D01*
X509427Y253813D01*
X509695Y253710D01*
X509887Y253503D01*
X510040Y253193D01*
X510078Y252832D01*
X510040Y252522D01*
X509887Y252212D01*
X509657Y251953D01*
X509388Y251850D01*
X509082Y251953D01*
X508813Y252263D01*
X508660Y252728D01*
X508622Y253245D01*
X508698Y253917D01*
X508813Y254278D01*
X509005Y254640D01*
X509273Y254898D01*
X509542Y254950D01*
X509810Y254847D01*
X510002Y254588D01*
G01X502493Y260992D02*
X502263Y261147D01*
X501995Y261250D01*
X501688D01*
X501343Y261095D01*
X501075Y260837D01*
X500883Y260527D01*
X500730Y260010D01*
X500692Y259545D01*
X500768Y259080D01*
X500883Y258770D01*
X501113Y258460D01*
X501382Y258253D01*
X501650Y258150D01*
X501918D01*
X502187Y258253D01*
X502417Y258408D01*
X502608Y258615D01*
G01X504750Y258150D02*
Y261250D01*
X504290Y260630D01*
G01Y258150D02*
X505210D01*
G01X507850D02*
X508118Y258202D01*
X508425Y258357D01*
X508617Y258615D01*
X508693Y258977D01*
X508617Y259338D01*
X508387Y259648D01*
X508042Y259803D01*
X507658D01*
X507428Y259907D01*
X507237Y260165D01*
X507160Y260527D01*
X507275Y260888D01*
X507543Y261147D01*
X507850Y261250D01*
X508157Y261147D01*
X508425Y260888D01*
X508540Y260527D01*
X508463Y260165D01*
X508272Y259907D01*
X508042Y259803D01*
X507658D01*
X507313Y259648D01*
X507083Y259338D01*
X507007Y258977D01*
X507083Y258615D01*
X507275Y258357D01*
X507582Y258202D01*
X507850Y258150D01*
G01X510298Y258512D02*
X510567Y258253D01*
X510873Y258150D01*
X511180Y258253D01*
X511448Y258563D01*
X511640Y259028D01*
X511717Y259493D01*
Y260062D01*
X511640Y260527D01*
X511448Y260940D01*
X511218Y261147D01*
X510950Y261250D01*
X510643Y261147D01*
X510413Y260940D01*
X510260Y260630D01*
X510183Y260217D01*
X510260Y259855D01*
X510452Y259493D01*
X510682Y259287D01*
X510950Y259235D01*
X511257Y259338D01*
X511487Y259597D01*
X511717Y260062D01*
G01X514493Y260492D02*
X514263Y260647D01*
X513995Y260750D01*
X513688D01*
X513343Y260595D01*
X513075Y260337D01*
X512883Y260027D01*
X512730Y259510D01*
X512692Y259045D01*
X512768Y258580D01*
X512883Y258270D01*
X513113Y257960D01*
X513382Y257753D01*
X513650Y257650D01*
X513918D01*
X514187Y257753D01*
X514417Y257908D01*
X514608Y258115D01*
G01X516750Y257650D02*
Y260750D01*
X516290Y260130D01*
G01Y257650D02*
X517210D01*
G01X519198Y258012D02*
X519467Y257753D01*
X519773Y257650D01*
X520080Y257753D01*
X520348Y258063D01*
X520540Y258528D01*
X520617Y258993D01*
Y259562D01*
X520540Y260027D01*
X520348Y260440D01*
X520118Y260647D01*
X519850Y260750D01*
X519543Y260647D01*
X519313Y260440D01*
X519160Y260130D01*
X519083Y259717D01*
X519160Y259355D01*
X519352Y258993D01*
X519582Y258787D01*
X519850Y258735D01*
X520157Y258838D01*
X520387Y259097D01*
X520617Y259562D01*
G01X522873Y257650D02*
X522950Y258322D01*
X523065Y258890D01*
X523218Y259407D01*
X523410Y259975D01*
X523717Y260750D01*
X522183D01*
G01X502050Y263950D02*
X498950D01*
X499570Y263490D01*
G01X502050D02*
Y264410D01*
G01X498950Y267050D02*
X499053Y266743D01*
X499312Y266513D01*
X499622Y266360D01*
X500035Y266245D01*
X500500Y266207D01*
X500965Y266245D01*
X501378Y266360D01*
X501688Y266513D01*
X501947Y266743D01*
X502050Y267050D01*
X501947Y267357D01*
X501688Y267587D01*
X501378Y267740D01*
X500965Y267855D01*
X500500Y267893D01*
X500035Y267855D01*
X499622Y267740D01*
X499312Y267587D01*
X499053Y267357D01*
X498950Y267050D01*
G01X505851Y273391D02*
Y271169D01*
X506004Y270704D01*
X506311Y270394D01*
X506694Y270291D01*
X507077Y270394D01*
X507384Y270704D01*
X507537Y271169D01*
Y273391D01*
G01X509066Y272874D02*
X509296Y273184D01*
X509564Y273339D01*
X509871Y273391D01*
X510254Y273288D01*
X510522Y273029D01*
X510599Y272719D01*
X510561Y272409D01*
X510407Y272151D01*
X509641Y271634D01*
X509296Y271273D01*
X509066Y270756D01*
X508989Y270291D01*
X510599D01*
G01X512894D02*
Y273391D01*
X512434Y272771D01*
G01Y270291D02*
X513354D01*
G01X499772Y274742D02*
X500040Y275103D01*
X500270Y275310D01*
X500577Y275413D01*
X500845Y275310D01*
X501037Y275103D01*
X501190Y274793D01*
X501228Y274432D01*
X501190Y274122D01*
X501037Y273812D01*
X500807Y273553D01*
X500538Y273450D01*
X500232Y273553D01*
X499963Y273863D01*
X499810Y274328D01*
X499772Y274845D01*
X499848Y275517D01*
X499963Y275878D01*
X500155Y276240D01*
X500423Y276498D01*
X500692Y276550D01*
X500960Y276447D01*
X501152Y276188D01*
G01X507193Y378792D02*
X506963Y378947D01*
X506695Y379050D01*
X506388D01*
X506043Y378895D01*
X505775Y378637D01*
X505583Y378327D01*
X505430Y377810D01*
X505392Y377345D01*
X505468Y376880D01*
X505583Y376570D01*
X505813Y376260D01*
X506082Y376053D01*
X506350Y375950D01*
X506618D01*
X506887Y376053D01*
X507117Y376208D01*
X507308Y376415D01*
G01X508722Y378533D02*
X508952Y378843D01*
X509220Y378998D01*
X509527Y379050D01*
X509910Y378947D01*
X510178Y378688D01*
X510255Y378378D01*
X510217Y378068D01*
X510063Y377810D01*
X509297Y377293D01*
X508952Y376932D01*
X508722Y376415D01*
X508645Y375950D01*
X510255D01*
G01X512473D02*
X512550Y376622D01*
X512665Y377190D01*
X512818Y377707D01*
X513010Y378275D01*
X513317Y379050D01*
X511783D01*
G01X514922Y378533D02*
X515152Y378843D01*
X515420Y378998D01*
X515727Y379050D01*
X516110Y378947D01*
X516378Y378688D01*
X516455Y378378D01*
X516417Y378068D01*
X516263Y377810D01*
X515497Y377293D01*
X515152Y376932D01*
X514922Y376415D01*
X514845Y375950D01*
X516455D01*
G01X503708Y384743D02*
X503553Y384513D01*
X503450Y384245D01*
Y383938D01*
X503605Y383593D01*
X503863Y383325D01*
X504173Y383133D01*
X504690Y382980D01*
X505155Y382942D01*
X505620Y383018D01*
X505930Y383133D01*
X506240Y383363D01*
X506447Y383632D01*
X506550Y383900D01*
Y384168D01*
X506447Y384437D01*
X506292Y384667D01*
X506085Y384858D01*
G01X506550Y386923D02*
X505878Y387000D01*
X505310Y387115D01*
X504793Y387268D01*
X504225Y387460D01*
X503450Y387767D01*
Y386233D01*
G01X503967Y389372D02*
X503657Y389602D01*
X503502Y389870D01*
X503450Y390177D01*
X503553Y390560D01*
X503812Y390828D01*
X504122Y390905D01*
X504432Y390867D01*
X504690Y390713D01*
X505207Y389947D01*
X505568Y389602D01*
X506085Y389372D01*
X506550Y389295D01*
Y390905D01*
G01X510367Y384352D02*
X513467D01*
Y385886D01*
G01Y388219D02*
X510367D01*
X510987Y387759D01*
G01X513467D02*
Y388679D01*
G01X513002Y390476D02*
X513260Y390706D01*
X513415Y390974D01*
X513467Y391319D01*
X513364Y391664D01*
X513157Y391932D01*
X512795Y392124D01*
X512382Y392162D01*
X511969Y392086D01*
X511710Y391894D01*
X511504Y391626D01*
X511452Y391357D01*
X511504Y391089D01*
X511710Y390744D01*
X510367Y390859D01*
Y391894D01*
G01X521583Y74966D02*
Y78066D01*
X522542D01*
X522848Y77911D01*
X523040Y77704D01*
X523117Y77291D01*
X523040Y76878D01*
X522810Y76619D01*
X522542Y76464D01*
X521583D01*
G01X522542D02*
X523117Y74966D01*
G01X525910D02*
Y78066D01*
X524492Y75844D01*
X526408D01*
G01X528473Y74966D02*
X528550Y75638D01*
X528665Y76206D01*
X528818Y76723D01*
X529010Y77291D01*
X529317Y78066D01*
X527783D01*
G01X530922Y76258D02*
X531190Y76619D01*
X531420Y76826D01*
X531727Y76929D01*
X531995Y76826D01*
X532187Y76619D01*
X532340Y76309D01*
X532378Y75948D01*
X532340Y75638D01*
X532187Y75328D01*
X531957Y75069D01*
X531688Y74966D01*
X531382Y75069D01*
X531113Y75379D01*
X530960Y75844D01*
X530922Y76361D01*
X530998Y77033D01*
X531113Y77394D01*
X531305Y77756D01*
X531573Y78014D01*
X531842Y78066D01*
X532110Y77963D01*
X532302Y77704D01*
G01X517748Y72862D02*
X518017Y72603D01*
X518323Y72500D01*
X518630Y72603D01*
X518898Y72913D01*
X519090Y73378D01*
X519167Y73843D01*
Y74412D01*
X519090Y74877D01*
X518898Y75290D01*
X518668Y75497D01*
X518400Y75600D01*
X518093Y75497D01*
X517863Y75290D01*
X517710Y74980D01*
X517633Y74567D01*
X517710Y74205D01*
X517902Y73843D01*
X518132Y73637D01*
X518400Y73585D01*
X518707Y73688D01*
X518937Y73947D01*
X519167Y74412D01*
G01X524743Y94324D02*
X524513Y94479D01*
X524245Y94582D01*
X523938D01*
X523593Y94427D01*
X523325Y94169D01*
X523133Y93859D01*
X522980Y93342D01*
X522942Y92877D01*
X523018Y92412D01*
X523133Y92102D01*
X523363Y91792D01*
X523632Y91585D01*
X523900Y91482D01*
X524168D01*
X524437Y91585D01*
X524667Y91740D01*
X524858Y91947D01*
G01X526348Y91844D02*
X526617Y91585D01*
X526923Y91482D01*
X527230Y91585D01*
X527498Y91895D01*
X527690Y92360D01*
X527767Y92825D01*
Y93394D01*
X527690Y93859D01*
X527498Y94272D01*
X527268Y94479D01*
X527000Y94582D01*
X526693Y94479D01*
X526463Y94272D01*
X526310Y93962D01*
X526233Y93549D01*
X526310Y93187D01*
X526502Y92825D01*
X526732Y92619D01*
X527000Y92567D01*
X527307Y92670D01*
X527537Y92929D01*
X527767Y93394D01*
G01X529372Y94065D02*
X529602Y94375D01*
X529870Y94530D01*
X530177Y94582D01*
X530560Y94479D01*
X530828Y94220D01*
X530905Y93910D01*
X530867Y93600D01*
X530713Y93342D01*
X529947Y92825D01*
X529602Y92464D01*
X529372Y91947D01*
X529295Y91482D01*
X530905D01*
G01X521583Y80966D02*
Y84066D01*
X522542D01*
X522848Y83911D01*
X523040Y83704D01*
X523117Y83291D01*
X523040Y82878D01*
X522810Y82619D01*
X522542Y82464D01*
X521583D01*
G01X522542D02*
X523117Y80966D01*
G01X525910D02*
Y84066D01*
X524492Y81844D01*
X526408D01*
G01X528473Y80966D02*
X528550Y81638D01*
X528665Y82206D01*
X528818Y82723D01*
X529010Y83291D01*
X529317Y84066D01*
X527783D01*
G01X531573Y80966D02*
X531650Y81638D01*
X531765Y82206D01*
X531918Y82723D01*
X532110Y83291D01*
X532417Y84066D01*
X530883D01*
G01X521583Y85966D02*
Y89066D01*
X522542D01*
X522848Y88911D01*
X523040Y88704D01*
X523117Y88291D01*
X523040Y87878D01*
X522810Y87619D01*
X522542Y87464D01*
X521583D01*
G01X522542D02*
X523117Y85966D01*
G01X525910D02*
Y89066D01*
X524492Y86844D01*
X526408D01*
G01X528550Y85966D02*
X528818Y86018D01*
X529125Y86173D01*
X529317Y86431D01*
X529393Y86793D01*
X529317Y87154D01*
X529087Y87464D01*
X528742Y87619D01*
X528358D01*
X528128Y87723D01*
X527937Y87981D01*
X527860Y88343D01*
X527975Y88704D01*
X528243Y88963D01*
X528550Y89066D01*
X528857Y88963D01*
X529125Y88704D01*
X529240Y88343D01*
X529163Y87981D01*
X528972Y87723D01*
X528742Y87619D01*
X528358D01*
X528013Y87464D01*
X527783Y87154D01*
X527707Y86793D01*
X527783Y86431D01*
X527975Y86173D01*
X528282Y86018D01*
X528550Y85966D01*
G01X532110D02*
Y89066D01*
X530692Y86844D01*
X532608D01*
G01X518150Y91000D02*
Y94100D01*
X517690Y93480D01*
G01Y91000D02*
X518610D01*
G01X520522Y92292D02*
X520790Y92653D01*
X521020Y92860D01*
X521327Y92963D01*
X521595Y92860D01*
X521787Y92653D01*
X521940Y92343D01*
X521978Y91982D01*
X521940Y91672D01*
X521787Y91362D01*
X521557Y91103D01*
X521288Y91000D01*
X520982Y91103D01*
X520713Y91413D01*
X520560Y91878D01*
X520522Y92395D01*
X520598Y93067D01*
X520713Y93428D01*
X520905Y93790D01*
X521173Y94048D01*
X521442Y94100D01*
X521710Y93997D01*
X521902Y93738D01*
G01X520193Y125292D02*
X519963Y125447D01*
X519695Y125550D01*
X519388D01*
X519043Y125395D01*
X518775Y125137D01*
X518583Y124827D01*
X518430Y124310D01*
X518392Y123845D01*
X518468Y123380D01*
X518583Y123070D01*
X518813Y122760D01*
X519082Y122553D01*
X519350Y122450D01*
X519618D01*
X519887Y122553D01*
X520117Y122708D01*
X520308Y122915D01*
G01X522450Y122450D02*
Y125550D01*
X521990Y124930D01*
G01Y122450D02*
X522910D01*
G01X525473D02*
X525550Y123122D01*
X525665Y123690D01*
X525818Y124207D01*
X526010Y124775D01*
X526317Y125550D01*
X524783D01*
G01X527807Y123070D02*
X528037Y122708D01*
X528343Y122502D01*
X528688Y122450D01*
X528995Y122502D01*
X529302Y122760D01*
X529493Y123070D01*
X529532Y123380D01*
X529455Y123742D01*
X529187Y124000D01*
X528918Y124103D01*
X528573D01*
G01X528918D02*
X529148Y124258D01*
X529340Y124517D01*
X529417Y124827D01*
X529340Y125137D01*
X529148Y125395D01*
X528803Y125550D01*
X528458Y125498D01*
X528113Y125292D01*
G01X520693Y148292D02*
X520463Y148447D01*
X520195Y148550D01*
X519888D01*
X519543Y148395D01*
X519275Y148137D01*
X519083Y147827D01*
X518930Y147310D01*
X518892Y146845D01*
X518968Y146380D01*
X519083Y146070D01*
X519313Y145760D01*
X519582Y145553D01*
X519850Y145450D01*
X520118D01*
X520387Y145553D01*
X520617Y145708D01*
X520808Y145915D01*
G01X522950Y145450D02*
Y148550D01*
X522490Y147930D01*
G01Y145450D02*
X523410D01*
G01X525973D02*
X526050Y146122D01*
X526165Y146690D01*
X526318Y147207D01*
X526510Y147775D01*
X526817Y148550D01*
X525283D01*
G01X529073Y145450D02*
X529150Y146122D01*
X529265Y146690D01*
X529418Y147207D01*
X529610Y147775D01*
X529917Y148550D01*
X528383D01*
G01X520693Y135792D02*
X520463Y135947D01*
X520195Y136050D01*
X519888D01*
X519543Y135895D01*
X519275Y135637D01*
X519083Y135327D01*
X518930Y134810D01*
X518892Y134345D01*
X518968Y133880D01*
X519083Y133570D01*
X519313Y133260D01*
X519582Y133053D01*
X519850Y132950D01*
X520118D01*
X520387Y133053D01*
X520617Y133208D01*
X520808Y133415D01*
G01X522950Y132950D02*
Y136050D01*
X522490Y135430D01*
G01Y132950D02*
X523410D01*
G01X525973D02*
X526050Y133622D01*
X526165Y134190D01*
X526318Y134707D01*
X526510Y135275D01*
X526817Y136050D01*
X525283D01*
G01X528422Y134242D02*
X528690Y134603D01*
X528920Y134810D01*
X529227Y134913D01*
X529495Y134810D01*
X529687Y134603D01*
X529840Y134293D01*
X529878Y133932D01*
X529840Y133622D01*
X529687Y133312D01*
X529457Y133053D01*
X529188Y132950D01*
X528882Y133053D01*
X528613Y133363D01*
X528460Y133828D01*
X528422Y134345D01*
X528498Y135017D01*
X528613Y135378D01*
X528805Y135740D01*
X529073Y135998D01*
X529342Y136050D01*
X529610Y135947D01*
X529802Y135688D01*
G01X520693Y160792D02*
X520463Y160947D01*
X520195Y161050D01*
X519888D01*
X519543Y160895D01*
X519275Y160637D01*
X519083Y160327D01*
X518930Y159810D01*
X518892Y159345D01*
X518968Y158880D01*
X519083Y158570D01*
X519313Y158260D01*
X519582Y158053D01*
X519850Y157950D01*
X520118D01*
X520387Y158053D01*
X520617Y158208D01*
X520808Y158415D01*
G01X522950Y157950D02*
Y161050D01*
X522490Y160430D01*
G01Y157950D02*
X523410D01*
G01X525973D02*
X526050Y158622D01*
X526165Y159190D01*
X526318Y159707D01*
X526510Y160275D01*
X526817Y161050D01*
X525283D01*
G01X528307Y158415D02*
X528537Y158157D01*
X528805Y158002D01*
X529150Y157950D01*
X529495Y158053D01*
X529763Y158260D01*
X529955Y158622D01*
X529993Y159035D01*
X529917Y159448D01*
X529725Y159707D01*
X529457Y159913D01*
X529188Y159965D01*
X528920Y159913D01*
X528575Y159707D01*
X528690Y161050D01*
X529725D01*
G01X533158Y178693D02*
X533003Y178463D01*
X532900Y178195D01*
Y177888D01*
X533055Y177543D01*
X533313Y177275D01*
X533623Y177083D01*
X534140Y176930D01*
X534605Y176892D01*
X535070Y176968D01*
X535380Y177083D01*
X535690Y177313D01*
X535897Y177582D01*
X536000Y177850D01*
Y178118D01*
X535897Y178387D01*
X535742Y178617D01*
X535535Y178808D01*
G01X533417Y180222D02*
X533107Y180452D01*
X532952Y180720D01*
X532900Y181027D01*
X533003Y181410D01*
X533262Y181678D01*
X533572Y181755D01*
X533882Y181717D01*
X534140Y181563D01*
X534657Y180797D01*
X535018Y180452D01*
X535535Y180222D01*
X536000Y180145D01*
Y181755D01*
G01Y183973D02*
X535328Y184050D01*
X534760Y184165D01*
X534243Y184318D01*
X533675Y184510D01*
X532900Y184817D01*
Y183283D01*
G01Y187150D02*
X533003Y186843D01*
X533262Y186613D01*
X533572Y186460D01*
X533985Y186345D01*
X534450Y186307D01*
X534915Y186345D01*
X535328Y186460D01*
X535638Y186613D01*
X535897Y186843D01*
X536000Y187150D01*
X535897Y187457D01*
X535638Y187687D01*
X535328Y187840D01*
X534915Y187955D01*
X534450Y187993D01*
X533985Y187955D01*
X533572Y187840D01*
X533262Y187687D01*
X533003Y187457D01*
X532900Y187150D01*
G01X517352Y174133D02*
Y171033D01*
X518886D01*
G01X521219D02*
Y174133D01*
X520759Y173513D01*
G01Y171033D02*
X521679D01*
G01X523591Y173616D02*
X523821Y173926D01*
X524089Y174081D01*
X524396Y174133D01*
X524779Y174030D01*
X525047Y173771D01*
X525124Y173461D01*
X525086Y173151D01*
X524932Y172893D01*
X524166Y172376D01*
X523821Y172015D01*
X523591Y171498D01*
X523514Y171033D01*
X525124D01*
G01X531808Y222093D02*
X531653Y221863D01*
X531550Y221595D01*
Y221288D01*
X531705Y220943D01*
X531963Y220675D01*
X532273Y220483D01*
X532790Y220330D01*
X533255Y220292D01*
X533720Y220368D01*
X534030Y220483D01*
X534340Y220713D01*
X534547Y220982D01*
X534650Y221250D01*
Y221518D01*
X534547Y221787D01*
X534392Y222017D01*
X534185Y222208D01*
G01X532067Y223622D02*
X531757Y223852D01*
X531602Y224120D01*
X531550Y224427D01*
X531653Y224810D01*
X531912Y225078D01*
X532222Y225155D01*
X532532Y225117D01*
X532790Y224963D01*
X533307Y224197D01*
X533668Y223852D01*
X534185Y223622D01*
X534650Y223545D01*
Y225155D01*
G01X534185Y226607D02*
X534443Y226837D01*
X534598Y227105D01*
X534650Y227450D01*
X534547Y227795D01*
X534340Y228063D01*
X533978Y228255D01*
X533565Y228293D01*
X533152Y228217D01*
X532893Y228025D01*
X532687Y227757D01*
X532635Y227488D01*
X532687Y227220D01*
X532893Y226875D01*
X531550Y226990D01*
Y228025D01*
G01X534185Y229707D02*
X534443Y229937D01*
X534598Y230205D01*
X534650Y230550D01*
X534547Y230895D01*
X534340Y231163D01*
X533978Y231355D01*
X533565Y231393D01*
X533152Y231317D01*
X532893Y231125D01*
X532687Y230857D01*
X532635Y230588D01*
X532687Y230320D01*
X532893Y229975D01*
X531550Y230090D01*
Y231125D01*
G01X529350Y257783D02*
X526250D01*
Y258742D01*
X526405Y259048D01*
X526612Y259240D01*
X527025Y259317D01*
X527438Y259240D01*
X527697Y259010D01*
X527852Y258742D01*
Y257783D01*
G01Y258742D02*
X529350Y259317D01*
G01Y261650D02*
X526250D01*
X526870Y261190D01*
G01X529350D02*
Y262110D01*
G01Y264750D02*
X529298Y265018D01*
X529143Y265325D01*
X528885Y265517D01*
X528523Y265593D01*
X528162Y265517D01*
X527852Y265287D01*
X527697Y264942D01*
Y264558D01*
X527593Y264328D01*
X527335Y264137D01*
X526973Y264060D01*
X526612Y264175D01*
X526353Y264443D01*
X526250Y264750D01*
X526353Y265057D01*
X526612Y265325D01*
X526973Y265440D01*
X527335Y265363D01*
X527593Y265172D01*
X527697Y264942D01*
Y264558D01*
X527852Y264213D01*
X528162Y263983D01*
X528523Y263907D01*
X528885Y263983D01*
X529143Y264175D01*
X529298Y264482D01*
X529350Y264750D01*
G01Y267773D02*
X528678Y267850D01*
X528110Y267965D01*
X527593Y268118D01*
X527025Y268310D01*
X526250Y268617D01*
Y267083D01*
G01X534350Y257783D02*
X531250D01*
Y258742D01*
X531405Y259048D01*
X531612Y259240D01*
X532025Y259317D01*
X532438Y259240D01*
X532697Y259010D01*
X532852Y258742D01*
Y257783D01*
G01Y258742D02*
X534350Y259317D01*
G01Y261650D02*
X531250D01*
X531870Y261190D01*
G01X534350D02*
Y262110D01*
G01X533988Y264098D02*
X534247Y264367D01*
X534350Y264673D01*
X534247Y264980D01*
X533937Y265248D01*
X533472Y265440D01*
X533007Y265517D01*
X532438D01*
X531973Y265440D01*
X531560Y265248D01*
X531353Y265018D01*
X531250Y264750D01*
X531353Y264443D01*
X531560Y264213D01*
X531870Y264060D01*
X532283Y263983D01*
X532645Y264060D01*
X533007Y264252D01*
X533213Y264482D01*
X533265Y264750D01*
X533162Y265057D01*
X532903Y265287D01*
X532438Y265517D01*
G01X531250Y267850D02*
X531353Y267543D01*
X531612Y267313D01*
X531922Y267160D01*
X532335Y267045D01*
X532800Y267007D01*
X533265Y267045D01*
X533678Y267160D01*
X533988Y267313D01*
X534247Y267543D01*
X534350Y267850D01*
X534247Y268157D01*
X533988Y268387D01*
X533678Y268540D01*
X533265Y268655D01*
X532800Y268693D01*
X532335Y268655D01*
X531922Y268540D01*
X531612Y268387D01*
X531353Y268157D01*
X531250Y267850D01*
G01X529850Y255150D02*
Y252050D01*
G01X528968Y255150D02*
X530732D01*
G01X532183Y252050D02*
Y255150D01*
X533103D01*
X533410Y254995D01*
X533640Y254633D01*
X533717Y254220D01*
X533640Y253807D01*
X533448Y253497D01*
X533103Y253342D01*
X532183D01*
G01X535207Y252515D02*
X535437Y252257D01*
X535705Y252102D01*
X536050Y252050D01*
X536395Y252153D01*
X536663Y252360D01*
X536855Y252722D01*
X536893Y253135D01*
X536817Y253548D01*
X536625Y253807D01*
X536357Y254013D01*
X536088Y254065D01*
X535820Y254013D01*
X535475Y253807D01*
X535590Y255150D01*
X536625D01*
G01X538422Y253342D02*
X538690Y253703D01*
X538920Y253910D01*
X539227Y254013D01*
X539495Y253910D01*
X539687Y253703D01*
X539840Y253393D01*
X539878Y253032D01*
X539840Y252722D01*
X539687Y252412D01*
X539457Y252153D01*
X539188Y252050D01*
X538882Y252153D01*
X538613Y252463D01*
X538460Y252928D01*
X538422Y253445D01*
X538498Y254117D01*
X538613Y254478D01*
X538805Y254840D01*
X539073Y255098D01*
X539342Y255150D01*
X539610Y255047D01*
X539802Y254788D01*
G01X524193Y273792D02*
X523963Y273947D01*
X523695Y274050D01*
X523388D01*
X523043Y273895D01*
X522775Y273637D01*
X522583Y273327D01*
X522430Y272810D01*
X522392Y272345D01*
X522468Y271880D01*
X522583Y271570D01*
X522813Y271260D01*
X523082Y271053D01*
X523350Y270950D01*
X523618D01*
X523887Y271053D01*
X524117Y271208D01*
X524308Y271415D01*
G01X526450Y270950D02*
Y274050D01*
X525990Y273430D01*
G01Y270950D02*
X526910D01*
G01X528898Y271312D02*
X529167Y271053D01*
X529473Y270950D01*
X529780Y271053D01*
X530048Y271363D01*
X530240Y271828D01*
X530317Y272293D01*
Y272862D01*
X530240Y273327D01*
X530048Y273740D01*
X529818Y273947D01*
X529550Y274050D01*
X529243Y273947D01*
X529013Y273740D01*
X528860Y273430D01*
X528783Y273017D01*
X528860Y272655D01*
X529052Y272293D01*
X529282Y272087D01*
X529550Y272035D01*
X529857Y272138D01*
X530087Y272397D01*
X530317Y272862D01*
G01X531807Y271570D02*
X532037Y271208D01*
X532343Y271002D01*
X532688Y270950D01*
X532995Y271002D01*
X533302Y271260D01*
X533493Y271570D01*
X533532Y271880D01*
X533455Y272242D01*
X533187Y272500D01*
X532918Y272603D01*
X532573D01*
G01X532918D02*
X533148Y272758D01*
X533340Y273017D01*
X533417Y273327D01*
X533340Y273637D01*
X533148Y273895D01*
X532803Y274050D01*
X532458Y273998D01*
X532113Y273792D01*
G01X528550Y276083D02*
X525450D01*
Y277042D01*
X525605Y277348D01*
X525812Y277540D01*
X526225Y277617D01*
X526638Y277540D01*
X526897Y277310D01*
X527052Y277042D01*
Y276083D01*
G01Y277042D02*
X528550Y277617D01*
G01Y279950D02*
X525450D01*
X526070Y279490D01*
G01X528550D02*
Y280410D01*
G01Y282973D02*
X527878Y283050D01*
X527310Y283165D01*
X526793Y283318D01*
X526225Y283510D01*
X525450Y283817D01*
Y282283D01*
G01X528188Y285498D02*
X528447Y285767D01*
X528550Y286073D01*
X528447Y286380D01*
X528137Y286648D01*
X527672Y286840D01*
X527207Y286917D01*
X526638D01*
X526173Y286840D01*
X525760Y286648D01*
X525553Y286418D01*
X525450Y286150D01*
X525553Y285843D01*
X525760Y285613D01*
X526070Y285460D01*
X526483Y285383D01*
X526845Y285460D01*
X527207Y285652D01*
X527413Y285882D01*
X527465Y286150D01*
X527362Y286457D01*
X527103Y286687D01*
X526638Y286917D01*
G01X533550Y276083D02*
X530450D01*
Y277042D01*
X530605Y277348D01*
X530812Y277540D01*
X531225Y277617D01*
X531638Y277540D01*
X531897Y277310D01*
X532052Y277042D01*
Y276083D01*
G01Y277042D02*
X533550Y277617D01*
G01Y279950D02*
X530450D01*
X531070Y279490D01*
G01X533550D02*
Y280410D01*
G01Y283050D02*
X533498Y283318D01*
X533343Y283625D01*
X533085Y283817D01*
X532723Y283893D01*
X532362Y283817D01*
X532052Y283587D01*
X531897Y283242D01*
Y282858D01*
X531793Y282628D01*
X531535Y282437D01*
X531173Y282360D01*
X530812Y282475D01*
X530553Y282743D01*
X530450Y283050D01*
X530553Y283357D01*
X530812Y283625D01*
X531173Y283740D01*
X531535Y283663D01*
X531793Y283472D01*
X531897Y283242D01*
Y282858D01*
X532052Y282513D01*
X532362Y282283D01*
X532723Y282207D01*
X533085Y282283D01*
X533343Y282475D01*
X533498Y282782D01*
X533550Y283050D01*
G01X530967Y285422D02*
X530657Y285652D01*
X530502Y285920D01*
X530450Y286227D01*
X530553Y286610D01*
X530812Y286878D01*
X531122Y286955D01*
X531432Y286917D01*
X531690Y286763D01*
X532207Y285997D01*
X532568Y285652D01*
X533085Y285422D01*
X533550Y285345D01*
Y286955D01*
G01X521081Y274885D02*
X521311Y274627D01*
X521579Y274472D01*
X521924Y274420D01*
X522269Y274523D01*
X522537Y274730D01*
X522729Y275092D01*
X522767Y275505D01*
X522691Y275918D01*
X522499Y276177D01*
X522231Y276383D01*
X521962Y276435D01*
X521694Y276383D01*
X521349Y276177D01*
X521464Y277520D01*
X522499D01*
G01X523542Y328600D02*
X524500Y331700D01*
X525458Y328600D01*
G01X525113Y329685D02*
X523887D01*
G01X523076Y368243D02*
X522921Y368013D01*
X522818Y367745D01*
Y367438D01*
X522973Y367093D01*
X523231Y366825D01*
X523541Y366633D01*
X524058Y366480D01*
X524523Y366442D01*
X524988Y366518D01*
X525298Y366633D01*
X525608Y366863D01*
X525815Y367132D01*
X525918Y367400D01*
Y367668D01*
X525815Y367937D01*
X525660Y368167D01*
X525453Y368358D01*
G01X525918Y370500D02*
X522818D01*
X523438Y370040D01*
G01X525918D02*
Y370960D01*
G01X522818Y373600D02*
X522921Y373293D01*
X523180Y373063D01*
X523490Y372910D01*
X523903Y372795D01*
X524368Y372757D01*
X524833Y372795D01*
X525246Y372910D01*
X525556Y373063D01*
X525815Y373293D01*
X525918Y373600D01*
X525815Y373907D01*
X525556Y374137D01*
X525246Y374290D01*
X524833Y374405D01*
X524368Y374443D01*
X523903Y374405D01*
X523490Y374290D01*
X523180Y374137D01*
X522921Y373907D01*
X522818Y373600D01*
G01X531276Y369793D02*
X531121Y369563D01*
X531018Y369295D01*
Y368988D01*
X531173Y368643D01*
X531431Y368375D01*
X531741Y368183D01*
X532258Y368030D01*
X532723Y367992D01*
X533188Y368068D01*
X533498Y368183D01*
X533808Y368413D01*
X534015Y368682D01*
X534118Y368950D01*
Y369218D01*
X534015Y369487D01*
X533860Y369717D01*
X533653Y369908D01*
G01X533756Y371398D02*
X534015Y371667D01*
X534118Y371973D01*
X534015Y372280D01*
X533705Y372548D01*
X533240Y372740D01*
X532775Y372817D01*
X532206D01*
X531741Y372740D01*
X531328Y372548D01*
X531121Y372318D01*
X531018Y372050D01*
X531121Y371743D01*
X531328Y371513D01*
X531638Y371360D01*
X532051Y371283D01*
X532413Y371360D01*
X532775Y371552D01*
X532981Y371782D01*
X533033Y372050D01*
X532930Y372357D01*
X532671Y372587D01*
X532206Y372817D01*
G01X532393Y383992D02*
X532163Y384147D01*
X531895Y384250D01*
X531588D01*
X531243Y384095D01*
X530975Y383837D01*
X530783Y383527D01*
X530630Y383010D01*
X530592Y382545D01*
X530668Y382080D01*
X530783Y381770D01*
X531013Y381460D01*
X531282Y381253D01*
X531550Y381150D01*
X531818D01*
X532087Y381253D01*
X532317Y381408D01*
X532508Y381615D01*
G01X533922Y382442D02*
X534190Y382803D01*
X534420Y383010D01*
X534727Y383113D01*
X534995Y383010D01*
X535187Y382803D01*
X535340Y382493D01*
X535378Y382132D01*
X535340Y381822D01*
X535187Y381512D01*
X534957Y381253D01*
X534688Y381150D01*
X534382Y381253D01*
X534113Y381563D01*
X533960Y382028D01*
X533922Y382545D01*
X533998Y383217D01*
X534113Y383578D01*
X534305Y383940D01*
X534573Y384198D01*
X534842Y384250D01*
X535110Y384147D01*
X535302Y383888D01*
G01X531783Y388650D02*
Y391750D01*
X532742D01*
X533048Y391595D01*
X533240Y391388D01*
X533317Y390975D01*
X533240Y390562D01*
X533010Y390303D01*
X532742Y390148D01*
X531783D01*
G01X532742D02*
X533317Y388650D01*
G01X534998Y389012D02*
X535267Y388753D01*
X535573Y388650D01*
X535880Y388753D01*
X536148Y389063D01*
X536340Y389528D01*
X536417Y389993D01*
Y390562D01*
X536340Y391027D01*
X536148Y391440D01*
X535918Y391647D01*
X535650Y391750D01*
X535343Y391647D01*
X535113Y391440D01*
X534960Y391130D01*
X534883Y390717D01*
X534960Y390355D01*
X535152Y389993D01*
X535382Y389787D01*
X535650Y389735D01*
X535957Y389838D01*
X536187Y390097D01*
X536417Y390562D01*
G01X530233Y394150D02*
Y397250D01*
X531192D01*
X531498Y397095D01*
X531690Y396888D01*
X531767Y396475D01*
X531690Y396062D01*
X531460Y395803D01*
X531192Y395648D01*
X530233D01*
G01X531192D02*
X531767Y394150D01*
G01X534100D02*
Y397250D01*
X533640Y396630D01*
G01Y394150D02*
X534560D01*
G01X537200D02*
Y397250D01*
X536740Y396630D01*
G01Y394150D02*
X537660D01*
G01X525933Y408091D02*
Y404991D01*
G01X525051Y408091D02*
X526815D01*
G01X528266Y404991D02*
Y408091D01*
X529186D01*
X529493Y407936D01*
X529723Y407574D01*
X529800Y407161D01*
X529723Y406748D01*
X529531Y406438D01*
X529186Y406283D01*
X528266D01*
G01X532593Y404991D02*
Y408091D01*
X531175Y405869D01*
X533091D01*
G01X535693Y404991D02*
Y408091D01*
X534275Y405869D01*
X536191D01*
G01X527042Y422500D02*
X528000Y425600D01*
X528958Y422500D01*
G01X528613Y423585D02*
X527387D01*
G01X528843Y412842D02*
X528613Y412997D01*
X528345Y413100D01*
X528038D01*
X527693Y412945D01*
X527425Y412687D01*
X527233Y412377D01*
X527080Y411860D01*
X527042Y411395D01*
X527118Y410930D01*
X527233Y410620D01*
X527463Y410310D01*
X527732Y410103D01*
X528000Y410000D01*
X528268D01*
X528537Y410103D01*
X528767Y410258D01*
X528958Y410465D01*
G01X529850Y414058D02*
X526750D01*
Y414824D01*
X526905Y415131D01*
X527112Y415361D01*
X527422Y415553D01*
X527783Y415706D01*
X528300Y415744D01*
X528817Y415706D01*
X529178Y415553D01*
X529488Y415361D01*
X529695Y415131D01*
X529850Y414824D01*
Y414058D01*
G01X529437Y417196D02*
X529695Y417503D01*
X529850Y417848D01*
Y418154D01*
X529695Y418461D01*
X529437Y418691D01*
X529075Y418806D01*
X528713Y418729D01*
X528403Y418538D01*
X528197Y418193D01*
X528093Y417733D01*
X527887Y417464D01*
X527525Y417349D01*
X527163Y417426D01*
X526905Y417618D01*
X526750Y417886D01*
Y418154D01*
X526853Y418423D01*
X527112Y418653D01*
G01X529488Y420449D02*
X529747Y420718D01*
X529850Y421024D01*
X529747Y421331D01*
X529437Y421599D01*
X528972Y421791D01*
X528507Y421868D01*
X527938D01*
X527473Y421791D01*
X527060Y421599D01*
X526853Y421369D01*
X526750Y421101D01*
X526853Y420794D01*
X527060Y420564D01*
X527370Y420411D01*
X527783Y420334D01*
X528145Y420411D01*
X528507Y420603D01*
X528713Y420833D01*
X528765Y421101D01*
X528662Y421408D01*
X528403Y421638D01*
X527938Y421868D01*
G01X541193Y64792D02*
X540963Y64947D01*
X540695Y65050D01*
X540388D01*
X540043Y64895D01*
X539775Y64637D01*
X539583Y64327D01*
X539430Y63810D01*
X539392Y63345D01*
X539468Y62880D01*
X539583Y62570D01*
X539813Y62260D01*
X540082Y62053D01*
X540350Y61950D01*
X540618D01*
X540887Y62053D01*
X541117Y62208D01*
X541308Y62415D01*
G01X542722Y64533D02*
X542952Y64843D01*
X543220Y64998D01*
X543527Y65050D01*
X543910Y64947D01*
X544178Y64688D01*
X544255Y64378D01*
X544217Y64068D01*
X544063Y63810D01*
X543297Y63293D01*
X542952Y62932D01*
X542722Y62415D01*
X542645Y61950D01*
X544255D01*
G01X545707Y62570D02*
X545937Y62208D01*
X546243Y62002D01*
X546588Y61950D01*
X546895Y62002D01*
X547202Y62260D01*
X547393Y62570D01*
X547432Y62880D01*
X547355Y63242D01*
X547087Y63500D01*
X546818Y63603D01*
X546473D01*
G01X546818D02*
X547048Y63758D01*
X547240Y64017D01*
X547317Y64327D01*
X547240Y64637D01*
X547048Y64895D01*
X546703Y65050D01*
X546358Y64998D01*
X546013Y64792D01*
G01X550110Y61950D02*
Y65050D01*
X548692Y62828D01*
X550608D01*
G01X537083Y67450D02*
Y70550D01*
X538042D01*
X538348Y70395D01*
X538540Y70188D01*
X538617Y69775D01*
X538540Y69362D01*
X538310Y69103D01*
X538042Y68948D01*
X537083D01*
G01X538042D02*
X538617Y67450D01*
G01X540222Y70033D02*
X540452Y70343D01*
X540720Y70498D01*
X541027Y70550D01*
X541410Y70447D01*
X541678Y70188D01*
X541755Y69878D01*
X541717Y69568D01*
X541563Y69310D01*
X540797Y68793D01*
X540452Y68432D01*
X540222Y67915D01*
X540145Y67450D01*
X541755D01*
G01X543207Y68070D02*
X543437Y67708D01*
X543743Y67502D01*
X544088Y67450D01*
X544395Y67502D01*
X544702Y67760D01*
X544893Y68070D01*
X544932Y68380D01*
X544855Y68742D01*
X544587Y69000D01*
X544318Y69103D01*
X543973D01*
G01X544318D02*
X544548Y69258D01*
X544740Y69517D01*
X544817Y69827D01*
X544740Y70137D01*
X544548Y70395D01*
X544203Y70550D01*
X543858Y70498D01*
X543513Y70292D01*
G01X547150Y67450D02*
Y70550D01*
X546690Y69930D01*
G01Y67450D02*
X547610D01*
G01X550993Y80492D02*
X550763Y80647D01*
X550495Y80750D01*
X550188D01*
X549843Y80595D01*
X549575Y80337D01*
X549383Y80027D01*
X549230Y79510D01*
X549192Y79045D01*
X549268Y78580D01*
X549383Y78270D01*
X549613Y77960D01*
X549882Y77753D01*
X550150Y77650D01*
X550418D01*
X550687Y77753D01*
X550917Y77908D01*
X551108Y78115D01*
G01X552522Y80233D02*
X552752Y80543D01*
X553020Y80698D01*
X553327Y80750D01*
X553710Y80647D01*
X553978Y80388D01*
X554055Y80078D01*
X554017Y79768D01*
X553863Y79510D01*
X553097Y78993D01*
X552752Y78632D01*
X552522Y78115D01*
X552445Y77650D01*
X554055D01*
G01X556810D02*
Y80750D01*
X555392Y78528D01*
X557308D01*
G01X558722Y80233D02*
X558952Y80543D01*
X559220Y80698D01*
X559527Y80750D01*
X559910Y80647D01*
X560178Y80388D01*
X560255Y80078D01*
X560217Y79768D01*
X560063Y79510D01*
X559297Y78993D01*
X558952Y78632D01*
X558722Y78115D01*
X558645Y77650D01*
X560255D01*
G01X547893Y87592D02*
X547663Y87747D01*
X547395Y87850D01*
X547088D01*
X546743Y87695D01*
X546475Y87437D01*
X546283Y87127D01*
X546130Y86610D01*
X546092Y86145D01*
X546168Y85680D01*
X546283Y85370D01*
X546513Y85060D01*
X546782Y84853D01*
X547050Y84750D01*
X547318D01*
X547587Y84853D01*
X547817Y85008D01*
X548008Y85215D01*
G01X549422Y87333D02*
X549652Y87643D01*
X549920Y87798D01*
X550227Y87850D01*
X550610Y87747D01*
X550878Y87488D01*
X550955Y87178D01*
X550917Y86868D01*
X550763Y86610D01*
X549997Y86093D01*
X549652Y85732D01*
X549422Y85215D01*
X549345Y84750D01*
X550955D01*
G01X552407Y85370D02*
X552637Y85008D01*
X552943Y84802D01*
X553288Y84750D01*
X553595Y84802D01*
X553902Y85060D01*
X554093Y85370D01*
X554132Y85680D01*
X554055Y86042D01*
X553787Y86300D01*
X553518Y86403D01*
X553173D01*
G01X553518D02*
X553748Y86558D01*
X553940Y86817D01*
X554017Y87127D01*
X553940Y87437D01*
X553748Y87695D01*
X553403Y87850D01*
X553058Y87798D01*
X552713Y87592D01*
G01X555698Y85112D02*
X555967Y84853D01*
X556273Y84750D01*
X556580Y84853D01*
X556848Y85163D01*
X557040Y85628D01*
X557117Y86093D01*
Y86662D01*
X557040Y87127D01*
X556848Y87540D01*
X556618Y87747D01*
X556350Y87850D01*
X556043Y87747D01*
X555813Y87540D01*
X555660Y87230D01*
X555583Y86817D01*
X555660Y86455D01*
X555852Y86093D01*
X556082Y85887D01*
X556350Y85835D01*
X556657Y85938D01*
X556887Y86197D01*
X557117Y86662D01*
G01X535850Y81100D02*
Y78000D01*
G01X534968Y81100D02*
X536732D01*
G01X538183Y78000D02*
Y81100D01*
X539103D01*
X539410Y80945D01*
X539640Y80583D01*
X539717Y80170D01*
X539640Y79757D01*
X539448Y79447D01*
X539103Y79292D01*
X538183D01*
G01X541207Y78465D02*
X541437Y78207D01*
X541705Y78052D01*
X542050Y78000D01*
X542395Y78103D01*
X542663Y78310D01*
X542855Y78672D01*
X542893Y79085D01*
X542817Y79498D01*
X542625Y79757D01*
X542357Y79963D01*
X542088Y80015D01*
X541820Y79963D01*
X541475Y79757D01*
X541590Y81100D01*
X542625D01*
G01X545073Y78000D02*
X545150Y78672D01*
X545265Y79240D01*
X545418Y79757D01*
X545610Y80325D01*
X545917Y81100D01*
X544383D01*
G01X536933Y97591D02*
Y94491D01*
G01X536051Y97591D02*
X537815D01*
G01X539266Y94491D02*
Y97591D01*
X540186D01*
X540493Y97436D01*
X540723Y97074D01*
X540800Y96661D01*
X540723Y96248D01*
X540531Y95938D01*
X540186Y95783D01*
X539266D01*
G01X543593Y94491D02*
Y97591D01*
X542175Y95369D01*
X544091D01*
G01X545505Y95783D02*
X545773Y96144D01*
X546003Y96351D01*
X546310Y96454D01*
X546578Y96351D01*
X546770Y96144D01*
X546923Y95834D01*
X546961Y95473D01*
X546923Y95163D01*
X546770Y94853D01*
X546540Y94594D01*
X546271Y94491D01*
X545965Y94594D01*
X545696Y94904D01*
X545543Y95369D01*
X545505Y95886D01*
X545581Y96558D01*
X545696Y96919D01*
X545888Y97281D01*
X546156Y97539D01*
X546425Y97591D01*
X546693Y97488D01*
X546885Y97229D01*
G01X537708Y159193D02*
X537553Y158963D01*
X537450Y158695D01*
Y158388D01*
X537605Y158043D01*
X537863Y157775D01*
X538173Y157583D01*
X538690Y157430D01*
X539155Y157392D01*
X539620Y157468D01*
X539930Y157583D01*
X540240Y157813D01*
X540447Y158082D01*
X540550Y158350D01*
Y158618D01*
X540447Y158887D01*
X540292Y159117D01*
X540085Y159308D01*
G01X537967Y160722D02*
X537657Y160952D01*
X537502Y161220D01*
X537450Y161527D01*
X537553Y161910D01*
X537812Y162178D01*
X538122Y162255D01*
X538432Y162217D01*
X538690Y162063D01*
X539207Y161297D01*
X539568Y160952D01*
X540085Y160722D01*
X540550Y160645D01*
Y162255D01*
G01Y164473D02*
X539878Y164550D01*
X539310Y164665D01*
X538793Y164818D01*
X538225Y165010D01*
X537450Y165317D01*
Y163783D01*
G01X540550Y167650D02*
X537450D01*
X538070Y167190D01*
G01X540550D02*
Y168110D01*
G01X539708Y177693D02*
X539553Y177463D01*
X539450Y177195D01*
Y176888D01*
X539605Y176543D01*
X539863Y176275D01*
X540173Y176083D01*
X540690Y175930D01*
X541155Y175892D01*
X541620Y175968D01*
X541930Y176083D01*
X542240Y176313D01*
X542447Y176582D01*
X542550Y176850D01*
Y177118D01*
X542447Y177387D01*
X542292Y177617D01*
X542085Y177808D01*
G01X539967Y179222D02*
X539657Y179452D01*
X539502Y179720D01*
X539450Y180027D01*
X539553Y180410D01*
X539812Y180678D01*
X540122Y180755D01*
X540432Y180717D01*
X540690Y180563D01*
X541207Y179797D01*
X541568Y179452D01*
X542085Y179222D01*
X542550Y179145D01*
Y180755D01*
G01X541258Y182322D02*
X540897Y182590D01*
X540690Y182820D01*
X540587Y183127D01*
X540690Y183395D01*
X540897Y183587D01*
X541207Y183740D01*
X541568Y183778D01*
X541878Y183740D01*
X542188Y183587D01*
X542447Y183357D01*
X542550Y183088D01*
X542447Y182782D01*
X542137Y182513D01*
X541672Y182360D01*
X541155Y182322D01*
X540483Y182398D01*
X540122Y182513D01*
X539760Y182705D01*
X539502Y182973D01*
X539450Y183242D01*
X539553Y183510D01*
X539812Y183702D01*
G01X542550Y186150D02*
X542498Y186418D01*
X542343Y186725D01*
X542085Y186917D01*
X541723Y186993D01*
X541362Y186917D01*
X541052Y186687D01*
X540897Y186342D01*
Y185958D01*
X540793Y185728D01*
X540535Y185537D01*
X540173Y185460D01*
X539812Y185575D01*
X539553Y185843D01*
X539450Y186150D01*
X539553Y186457D01*
X539812Y186725D01*
X540173Y186840D01*
X540535Y186763D01*
X540793Y186572D01*
X540897Y186342D01*
Y185958D01*
X541052Y185613D01*
X541362Y185383D01*
X541723Y185307D01*
X542085Y185383D01*
X542343Y185575D01*
X542498Y185882D01*
X542550Y186150D01*
G01X543708Y207193D02*
X543553Y206963D01*
X543450Y206695D01*
Y206388D01*
X543605Y206043D01*
X543863Y205775D01*
X544173Y205583D01*
X544690Y205430D01*
X545155Y205392D01*
X545620Y205468D01*
X545930Y205583D01*
X546240Y205813D01*
X546447Y206082D01*
X546550Y206350D01*
Y206618D01*
X546447Y206887D01*
X546292Y207117D01*
X546085Y207308D01*
G01X543967Y208722D02*
X543657Y208952D01*
X543502Y209220D01*
X543450Y209527D01*
X543553Y209910D01*
X543812Y210178D01*
X544122Y210255D01*
X544432Y210217D01*
X544690Y210063D01*
X545207Y209297D01*
X545568Y208952D01*
X546085Y208722D01*
X546550Y208645D01*
Y210255D01*
G01X545258Y211822D02*
X544897Y212090D01*
X544690Y212320D01*
X544587Y212627D01*
X544690Y212895D01*
X544897Y213087D01*
X545207Y213240D01*
X545568Y213278D01*
X545878Y213240D01*
X546188Y213087D01*
X546447Y212857D01*
X546550Y212588D01*
X546447Y212282D01*
X546137Y212013D01*
X545672Y211860D01*
X545155Y211822D01*
X544483Y211898D01*
X544122Y212013D01*
X543760Y212205D01*
X543502Y212473D01*
X543450Y212742D01*
X543553Y213010D01*
X543812Y213202D01*
G01X546550Y215650D02*
X543450D01*
X544070Y215190D01*
G01X546550D02*
Y216110D01*
G01X537208Y205193D02*
X537053Y204963D01*
X536950Y204695D01*
Y204388D01*
X537105Y204043D01*
X537363Y203775D01*
X537673Y203583D01*
X538190Y203430D01*
X538655Y203392D01*
X539120Y203468D01*
X539430Y203583D01*
X539740Y203813D01*
X539947Y204082D01*
X540050Y204350D01*
Y204618D01*
X539947Y204887D01*
X539792Y205117D01*
X539585Y205308D01*
G01X537467Y206722D02*
X537157Y206952D01*
X537002Y207220D01*
X536950Y207527D01*
X537053Y207910D01*
X537312Y208178D01*
X537622Y208255D01*
X537932Y208217D01*
X538190Y208063D01*
X538707Y207297D01*
X539068Y206952D01*
X539585Y206722D01*
X540050Y206645D01*
Y208255D01*
G01X538758Y209822D02*
X538397Y210090D01*
X538190Y210320D01*
X538087Y210627D01*
X538190Y210895D01*
X538397Y211087D01*
X538707Y211240D01*
X539068Y211278D01*
X539378Y211240D01*
X539688Y211087D01*
X539947Y210857D01*
X540050Y210588D01*
X539947Y210282D01*
X539637Y210013D01*
X539172Y209860D01*
X538655Y209822D01*
X537983Y209898D01*
X537622Y210013D01*
X537260Y210205D01*
X537002Y210473D01*
X536950Y210742D01*
X537053Y211010D01*
X537312Y211202D01*
G01X536950Y213650D02*
X537053Y213343D01*
X537312Y213113D01*
X537622Y212960D01*
X538035Y212845D01*
X538500Y212807D01*
X538965Y212845D01*
X539378Y212960D01*
X539688Y213113D01*
X539947Y213343D01*
X540050Y213650D01*
X539947Y213957D01*
X539688Y214187D01*
X539378Y214340D01*
X538965Y214455D01*
X538500Y214493D01*
X538035Y214455D01*
X537622Y214340D01*
X537312Y214187D01*
X537053Y213957D01*
X536950Y213650D01*
G01X547657Y209465D02*
X547887Y209207D01*
X548155Y209052D01*
X548500Y209000D01*
X548845Y209103D01*
X549113Y209310D01*
X549305Y209672D01*
X549343Y210085D01*
X549267Y210498D01*
X549075Y210757D01*
X548807Y210963D01*
X548538Y211015D01*
X548270Y210963D01*
X547925Y210757D01*
X548040Y212100D01*
X549075D01*
G01X549708Y230193D02*
X549553Y229963D01*
X549450Y229695D01*
Y229388D01*
X549605Y229043D01*
X549863Y228775D01*
X550173Y228583D01*
X550690Y228430D01*
X551155Y228392D01*
X551620Y228468D01*
X551930Y228583D01*
X552240Y228813D01*
X552447Y229082D01*
X552550Y229350D01*
Y229618D01*
X552447Y229887D01*
X552292Y230117D01*
X552085Y230308D01*
G01X549967Y231722D02*
X549657Y231952D01*
X549502Y232220D01*
X549450Y232527D01*
X549553Y232910D01*
X549812Y233178D01*
X550122Y233255D01*
X550432Y233217D01*
X550690Y233063D01*
X551207Y232297D01*
X551568Y231952D01*
X552085Y231722D01*
X552550Y231645D01*
Y233255D01*
G01X552085Y234707D02*
X552343Y234937D01*
X552498Y235205D01*
X552550Y235550D01*
X552447Y235895D01*
X552240Y236163D01*
X551878Y236355D01*
X551465Y236393D01*
X551052Y236317D01*
X550793Y236125D01*
X550587Y235857D01*
X550535Y235588D01*
X550587Y235320D01*
X550793Y234975D01*
X549450Y235090D01*
Y236125D01*
G01X552550Y238650D02*
X552498Y238918D01*
X552343Y239225D01*
X552085Y239417D01*
X551723Y239493D01*
X551362Y239417D01*
X551052Y239187D01*
X550897Y238842D01*
Y238458D01*
X550793Y238228D01*
X550535Y238037D01*
X550173Y237960D01*
X549812Y238075D01*
X549553Y238343D01*
X549450Y238650D01*
X549553Y238957D01*
X549812Y239225D01*
X550173Y239340D01*
X550535Y239263D01*
X550793Y239072D01*
X550897Y238842D01*
Y238458D01*
X551052Y238113D01*
X551362Y237883D01*
X551723Y237807D01*
X552085Y237883D01*
X552343Y238075D01*
X552498Y238382D01*
X552550Y238650D01*
G01X548050Y229083D02*
X544950D01*
Y230042D01*
X545105Y230348D01*
X545312Y230540D01*
X545725Y230617D01*
X546138Y230540D01*
X546397Y230310D01*
X546552Y230042D01*
Y229083D01*
G01Y230042D02*
X548050Y230617D01*
G01X545467Y232222D02*
X545157Y232452D01*
X545002Y232720D01*
X544950Y233027D01*
X545053Y233410D01*
X545312Y233678D01*
X545622Y233755D01*
X545932Y233717D01*
X546190Y233563D01*
X546707Y232797D01*
X547068Y232452D01*
X547585Y232222D01*
X548050Y232145D01*
Y233755D01*
G01Y236510D02*
X544950D01*
X547172Y235092D01*
Y237008D01*
G01X547585Y238307D02*
X547843Y238537D01*
X547998Y238805D01*
X548050Y239150D01*
X547947Y239495D01*
X547740Y239763D01*
X547378Y239955D01*
X546965Y239993D01*
X546552Y239917D01*
X546293Y239725D01*
X546087Y239457D01*
X546035Y239188D01*
X546087Y238920D01*
X546293Y238575D01*
X544950Y238690D01*
Y239725D01*
G01X548529Y223805D02*
Y226905D01*
X548069Y226285D01*
G01Y223805D02*
X548989D01*
G01X551629D02*
X551897Y223857D01*
X552204Y224012D01*
X552396Y224270D01*
X552472Y224632D01*
X552396Y224993D01*
X552166Y225303D01*
X551821Y225458D01*
X551437D01*
X551207Y225562D01*
X551016Y225820D01*
X550939Y226182D01*
X551054Y226543D01*
X551322Y226802D01*
X551629Y226905D01*
X551936Y226802D01*
X552204Y226543D01*
X552319Y226182D01*
X552242Y225820D01*
X552051Y225562D01*
X551821Y225458D01*
X551437D01*
X551092Y225303D01*
X550862Y224993D01*
X550786Y224632D01*
X550862Y224270D01*
X551054Y224012D01*
X551361Y223857D01*
X551629Y223805D01*
G01X537950Y223183D02*
X541050D01*
Y224717D01*
G01X540688Y226398D02*
X540947Y226667D01*
X541050Y226973D01*
X540947Y227280D01*
X540637Y227548D01*
X540172Y227740D01*
X539707Y227817D01*
X539138D01*
X538673Y227740D01*
X538260Y227548D01*
X538053Y227318D01*
X537950Y227050D01*
X538053Y226743D01*
X538260Y226513D01*
X538570Y226360D01*
X538983Y226283D01*
X539345Y226360D01*
X539707Y226552D01*
X539913Y226782D01*
X539965Y227050D01*
X539862Y227357D01*
X539603Y227587D01*
X539138Y227817D01*
G01X538450Y231850D02*
X541550D01*
G01X538450Y230968D02*
Y232732D01*
G01X541550Y234183D02*
X538450D01*
Y235103D01*
X538605Y235410D01*
X538967Y235640D01*
X539380Y235717D01*
X539793Y235640D01*
X540103Y235448D01*
X540258Y235103D01*
Y234183D01*
G01X541085Y237207D02*
X541343Y237437D01*
X541498Y237705D01*
X541550Y238050D01*
X541447Y238395D01*
X541240Y238663D01*
X540878Y238855D01*
X540465Y238893D01*
X540052Y238817D01*
X539793Y238625D01*
X539587Y238357D01*
X539535Y238088D01*
X539587Y237820D01*
X539793Y237475D01*
X538450Y237590D01*
Y238625D01*
G01X538967Y240422D02*
X538657Y240652D01*
X538502Y240920D01*
X538450Y241227D01*
X538553Y241610D01*
X538812Y241878D01*
X539122Y241955D01*
X539432Y241917D01*
X539690Y241763D01*
X540207Y240997D01*
X540568Y240652D01*
X541085Y240422D01*
X541550Y240345D01*
Y241955D01*
G01X540772Y261033D02*
X541002Y261343D01*
X541270Y261498D01*
X541577Y261550D01*
X541960Y261447D01*
X542228Y261188D01*
X542305Y260878D01*
X542267Y260568D01*
X542113Y260310D01*
X541347Y259793D01*
X541002Y259432D01*
X540772Y258915D01*
X540695Y258450D01*
X542305D01*
G01X539950Y301000D02*
Y304100D01*
X539490Y303480D01*
G01Y301000D02*
X540410D01*
G01X543050Y304100D02*
X542743Y303997D01*
X542513Y303738D01*
X542360Y303428D01*
X542245Y303015D01*
X542207Y302550D01*
X542245Y302085D01*
X542360Y301672D01*
X542513Y301362D01*
X542743Y301103D01*
X543050Y301000D01*
X543357Y301103D01*
X543587Y301362D01*
X543740Y301672D01*
X543855Y302085D01*
X543893Y302550D01*
X543855Y303015D01*
X543740Y303428D01*
X543587Y303738D01*
X543357Y303997D01*
X543050Y304100D01*
G01X538293Y331892D02*
X538063Y332047D01*
X537795Y332150D01*
X537488D01*
X537143Y331995D01*
X536875Y331737D01*
X536683Y331427D01*
X536530Y330910D01*
X536492Y330445D01*
X536568Y329980D01*
X536683Y329670D01*
X536913Y329360D01*
X537182Y329153D01*
X537450Y329050D01*
X537718D01*
X537987Y329153D01*
X538217Y329308D01*
X538408Y329515D01*
G01X539783Y329050D02*
Y332150D01*
X540742D01*
X541048Y331995D01*
X541240Y331788D01*
X541317Y331375D01*
X541240Y330962D01*
X541010Y330703D01*
X540742Y330548D01*
X539783D01*
G01X540742D02*
X541317Y329050D01*
G01X543650D02*
Y332150D01*
X543190Y331530D01*
G01Y329050D02*
X544110D01*
G01X546750Y332150D02*
X546443Y332047D01*
X546213Y331788D01*
X546060Y331478D01*
X545945Y331065D01*
X545907Y330600D01*
X545945Y330135D01*
X546060Y329722D01*
X546213Y329412D01*
X546443Y329153D01*
X546750Y329050D01*
X547057Y329153D01*
X547287Y329412D01*
X547440Y329722D01*
X547555Y330135D01*
X547593Y330600D01*
X547555Y331065D01*
X547440Y331478D01*
X547287Y331788D01*
X547057Y332047D01*
X546750Y332150D01*
G01X546772Y355350D02*
Y358450D01*
X548228D01*
G01X547692Y356952D02*
X546772D01*
G01X549757Y358450D02*
Y356228D01*
X549910Y355763D01*
X550217Y355453D01*
X550600Y355350D01*
X550983Y355453D01*
X551290Y355763D01*
X551443Y356228D01*
Y358450D01*
G01X553700Y355350D02*
Y358450D01*
X553240Y357830D01*
G01Y355350D02*
X554160D01*
G01X538751Y367841D02*
X538981Y368151D01*
X539249Y368306D01*
X539556Y368358D01*
X539939Y368255D01*
X540207Y367996D01*
X540284Y367686D01*
X540246Y367376D01*
X540092Y367118D01*
X539326Y366601D01*
X538981Y366240D01*
X538751Y365723D01*
X538674Y365258D01*
X540284D01*
G01X542579Y368358D02*
X542272Y368255D01*
X542042Y367996D01*
X541889Y367686D01*
X541774Y367273D01*
X541736Y366808D01*
X541774Y366343D01*
X541889Y365930D01*
X542042Y365620D01*
X542272Y365361D01*
X542579Y365258D01*
X542886Y365361D01*
X543116Y365620D01*
X543269Y365930D01*
X543384Y366343D01*
X543422Y366808D01*
X543384Y367273D01*
X543269Y367686D01*
X543116Y367996D01*
X542886Y368255D01*
X542579Y368358D01*
G01X549757Y376282D02*
Y374060D01*
X549910Y373595D01*
X550217Y373285D01*
X550600Y373182D01*
X550983Y373285D01*
X551290Y373595D01*
X551443Y374060D01*
Y376282D01*
G01X553700Y373182D02*
Y376282D01*
X553240Y375662D01*
G01Y373182D02*
X554160D01*
G01X548893Y392492D02*
X548663Y392647D01*
X548395Y392750D01*
X548088D01*
X547743Y392595D01*
X547475Y392337D01*
X547283Y392027D01*
X547130Y391510D01*
X547092Y391045D01*
X547168Y390580D01*
X547283Y390270D01*
X547513Y389960D01*
X547782Y389753D01*
X548050Y389650D01*
X548318D01*
X548587Y389753D01*
X548817Y389908D01*
X549008Y390115D01*
G01X551150Y389650D02*
X551418Y389702D01*
X551725Y389857D01*
X551917Y390115D01*
X551993Y390477D01*
X551917Y390838D01*
X551687Y391148D01*
X551342Y391303D01*
X550958D01*
X550728Y391407D01*
X550537Y391665D01*
X550460Y392027D01*
X550575Y392388D01*
X550843Y392647D01*
X551150Y392750D01*
X551457Y392647D01*
X551725Y392388D01*
X551840Y392027D01*
X551763Y391665D01*
X551572Y391407D01*
X551342Y391303D01*
X550958D01*
X550613Y391148D01*
X550383Y390838D01*
X550307Y390477D01*
X550383Y390115D01*
X550575Y389857D01*
X550882Y389702D01*
X551150Y389650D01*
G01X539479Y381006D02*
Y384106D01*
X539019Y383486D01*
G01Y381006D02*
X539939D01*
G01X541851Y383589D02*
X542081Y383899D01*
X542349Y384054D01*
X542656Y384106D01*
X543039Y384003D01*
X543307Y383744D01*
X543384Y383434D01*
X543346Y383124D01*
X543192Y382866D01*
X542426Y382349D01*
X542081Y381988D01*
X541851Y381471D01*
X541774Y381006D01*
X543384D01*
G01X552343Y405792D02*
X552113Y405947D01*
X551845Y406050D01*
X551538D01*
X551193Y405895D01*
X550925Y405637D01*
X550733Y405327D01*
X550580Y404810D01*
X550542Y404345D01*
X550618Y403880D01*
X550733Y403570D01*
X550963Y403260D01*
X551232Y403053D01*
X551500Y402950D01*
X551768D01*
X552037Y403053D01*
X552267Y403208D01*
X552458Y403415D01*
G01X543843Y405292D02*
X543613Y405447D01*
X543345Y405550D01*
X543038D01*
X542693Y405395D01*
X542425Y405137D01*
X542233Y404827D01*
X542080Y404310D01*
X542042Y403845D01*
X542118Y403380D01*
X542233Y403070D01*
X542463Y402760D01*
X542732Y402553D01*
X543000Y402450D01*
X543268D01*
X543537Y402553D01*
X543767Y402708D01*
X543958Y402915D01*
G01X545054Y406884D02*
X541954D01*
Y407650D01*
X542109Y407957D01*
X542316Y408187D01*
X542626Y408379D01*
X542987Y408532D01*
X543504Y408570D01*
X544021Y408532D01*
X544382Y408379D01*
X544692Y408187D01*
X544899Y407957D01*
X545054Y407650D01*
Y406884D01*
G01X544641Y410022D02*
X544899Y410329D01*
X545054Y410674D01*
Y410980D01*
X544899Y411287D01*
X544641Y411517D01*
X544279Y411632D01*
X543917Y411555D01*
X543607Y411364D01*
X543401Y411019D01*
X543297Y410559D01*
X543091Y410290D01*
X542729Y410175D01*
X542367Y410252D01*
X542109Y410444D01*
X541954Y410712D01*
Y410980D01*
X542057Y411249D01*
X542316Y411479D01*
G01X543762Y413199D02*
X543401Y413467D01*
X543194Y413697D01*
X543091Y414004D01*
X543194Y414272D01*
X543401Y414464D01*
X543711Y414617D01*
X544072Y414655D01*
X544382Y414617D01*
X544692Y414464D01*
X544951Y414234D01*
X545054Y413965D01*
X544951Y413659D01*
X544641Y413390D01*
X544176Y413237D01*
X543659Y413199D01*
X542987Y413275D01*
X542626Y413390D01*
X542264Y413582D01*
X542006Y413850D01*
X541954Y414119D01*
X542057Y414387D01*
X542316Y414579D01*
G01X544676Y395150D02*
Y398250D01*
X545635D01*
X545941Y398095D01*
X546133Y397888D01*
X546210Y397475D01*
X546133Y397062D01*
X545903Y396803D01*
X545635Y396648D01*
X544676D01*
G01X545635D02*
X546210Y395150D01*
G01X548543D02*
Y398250D01*
X548083Y397630D01*
G01Y395150D02*
X549003D01*
G01X550915Y397733D02*
X551145Y398043D01*
X551413Y398198D01*
X551720Y398250D01*
X552103Y398147D01*
X552371Y397888D01*
X552448Y397578D01*
X552410Y397268D01*
X552256Y397010D01*
X551490Y396493D01*
X551145Y396132D01*
X550915Y395615D01*
X550838Y395150D01*
X552448D01*
G01X550542Y412450D02*
X551500Y415550D01*
X552458Y412450D01*
G01X552113Y413535D02*
X550887D01*
G01X547843Y421792D02*
X547613Y421947D01*
X547345Y422050D01*
X547038D01*
X546693Y421895D01*
X546425Y421637D01*
X546233Y421327D01*
X546080Y420810D01*
X546042Y420345D01*
X546118Y419880D01*
X546233Y419570D01*
X546463Y419260D01*
X546732Y419053D01*
X547000Y418950D01*
X547268D01*
X547537Y419053D01*
X547767Y419208D01*
X547958Y419415D01*
G01X545050Y420557D02*
X541950D01*
Y421323D01*
X542105Y421630D01*
X542312Y421860D01*
X542622Y422052D01*
X542983Y422205D01*
X543500Y422243D01*
X544017Y422205D01*
X544378Y422052D01*
X544688Y421860D01*
X544895Y421630D01*
X545050Y421323D01*
Y420557D01*
G01X544637Y423695D02*
X544895Y424002D01*
X545050Y424347D01*
Y424653D01*
X544895Y424960D01*
X544637Y425190D01*
X544275Y425305D01*
X543913Y425228D01*
X543603Y425037D01*
X543397Y424692D01*
X543293Y424232D01*
X543087Y423963D01*
X542725Y423848D01*
X542363Y423925D01*
X542105Y424117D01*
X541950Y424385D01*
Y424653D01*
X542053Y424922D01*
X542312Y425152D01*
G01X545050Y427600D02*
X541950D01*
X542570Y427140D01*
G01X545050D02*
Y428060D01*
G01X539042Y413450D02*
X540000Y416550D01*
X540958Y413450D01*
G01X540613Y414535D02*
X539387D01*
G01X541542Y429905D02*
X542500Y433005D01*
X543458Y429905D01*
G01X543113Y430990D02*
X541887D01*
G01X553657Y62465D02*
X553887Y62207D01*
X554155Y62052D01*
X554500Y62000D01*
X554845Y62103D01*
X555113Y62310D01*
X555305Y62672D01*
X555343Y63085D01*
X555267Y63498D01*
X555075Y63757D01*
X554807Y63963D01*
X554538Y64015D01*
X554270Y63963D01*
X553925Y63757D01*
X554040Y65100D01*
X555075D01*
G01X558557Y69450D02*
Y67228D01*
X558710Y66763D01*
X559017Y66453D01*
X559400Y66350D01*
X559783Y66453D01*
X560090Y66763D01*
X560243Y67228D01*
Y69450D01*
G01X561772Y68933D02*
X562002Y69243D01*
X562270Y69398D01*
X562577Y69450D01*
X562960Y69347D01*
X563228Y69088D01*
X563305Y68778D01*
X563267Y68468D01*
X563113Y68210D01*
X562347Y67693D01*
X562002Y67332D01*
X561772Y66815D01*
X561695Y66350D01*
X563305D01*
G01X564757Y66815D02*
X564987Y66557D01*
X565255Y66402D01*
X565600Y66350D01*
X565945Y66453D01*
X566213Y66660D01*
X566405Y67022D01*
X566443Y67435D01*
X566367Y67848D01*
X566175Y68107D01*
X565907Y68313D01*
X565638Y68365D01*
X565370Y68313D01*
X565025Y68107D01*
X565140Y69450D01*
X566175D01*
G01X562708Y92693D02*
X562553Y92463D01*
X562450Y92195D01*
Y91888D01*
X562605Y91543D01*
X562863Y91275D01*
X563173Y91083D01*
X563690Y90930D01*
X564155Y90892D01*
X564620Y90968D01*
X564930Y91083D01*
X565240Y91313D01*
X565447Y91582D01*
X565550Y91850D01*
Y92118D01*
X565447Y92387D01*
X565292Y92617D01*
X565085Y92808D01*
G01X562967Y94222D02*
X562657Y94452D01*
X562502Y94720D01*
X562450Y95027D01*
X562553Y95410D01*
X562812Y95678D01*
X563122Y95755D01*
X563432Y95717D01*
X563690Y95563D01*
X564207Y94797D01*
X564568Y94452D01*
X565085Y94222D01*
X565550Y94145D01*
Y95755D01*
G01X562967Y97322D02*
X562657Y97552D01*
X562502Y97820D01*
X562450Y98127D01*
X562553Y98510D01*
X562812Y98778D01*
X563122Y98855D01*
X563432Y98817D01*
X563690Y98663D01*
X564207Y97897D01*
X564568Y97552D01*
X565085Y97322D01*
X565550Y97245D01*
Y98855D01*
G01X564258Y100422D02*
X563897Y100690D01*
X563690Y100920D01*
X563587Y101227D01*
X563690Y101495D01*
X563897Y101687D01*
X564207Y101840D01*
X564568Y101878D01*
X564878Y101840D01*
X565188Y101687D01*
X565447Y101457D01*
X565550Y101188D01*
X565447Y100882D01*
X565137Y100613D01*
X564672Y100460D01*
X564155Y100422D01*
X563483Y100498D01*
X563122Y100613D01*
X562760Y100805D01*
X562502Y101073D01*
X562450Y101342D01*
X562553Y101610D01*
X562812Y101802D01*
G01X563193Y80492D02*
X562963Y80647D01*
X562695Y80750D01*
X562388D01*
X562043Y80595D01*
X561775Y80337D01*
X561583Y80027D01*
X561430Y79510D01*
X561392Y79045D01*
X561468Y78580D01*
X561583Y78270D01*
X561813Y77960D01*
X562082Y77753D01*
X562350Y77650D01*
X562618D01*
X562887Y77753D01*
X563117Y77908D01*
X563308Y78115D01*
G01X564722Y80233D02*
X564952Y80543D01*
X565220Y80698D01*
X565527Y80750D01*
X565910Y80647D01*
X566178Y80388D01*
X566255Y80078D01*
X566217Y79768D01*
X566063Y79510D01*
X565297Y78993D01*
X564952Y78632D01*
X564722Y78115D01*
X564645Y77650D01*
X566255D01*
G01X567707Y78270D02*
X567937Y77908D01*
X568243Y77702D01*
X568588Y77650D01*
X568895Y77702D01*
X569202Y77960D01*
X569393Y78270D01*
X569432Y78580D01*
X569355Y78942D01*
X569087Y79200D01*
X568818Y79303D01*
X568473D01*
G01X568818D02*
X569048Y79458D01*
X569240Y79717D01*
X569317Y80027D01*
X569240Y80337D01*
X569048Y80595D01*
X568703Y80750D01*
X568358Y80698D01*
X568013Y80492D01*
G01X571650Y80750D02*
X571343Y80647D01*
X571113Y80388D01*
X570960Y80078D01*
X570845Y79665D01*
X570807Y79200D01*
X570845Y78735D01*
X570960Y78322D01*
X571113Y78012D01*
X571343Y77753D01*
X571650Y77650D01*
X571957Y77753D01*
X572187Y78012D01*
X572340Y78322D01*
X572455Y78735D01*
X572493Y79200D01*
X572455Y79665D01*
X572340Y80078D01*
X572187Y80388D01*
X571957Y80647D01*
X571650Y80750D01*
G01X556208Y92693D02*
X556053Y92463D01*
X555950Y92195D01*
Y91888D01*
X556105Y91543D01*
X556363Y91275D01*
X556673Y91083D01*
X557190Y90930D01*
X557655Y90892D01*
X558120Y90968D01*
X558430Y91083D01*
X558740Y91313D01*
X558947Y91582D01*
X559050Y91850D01*
Y92118D01*
X558947Y92387D01*
X558792Y92617D01*
X558585Y92808D01*
G01X556467Y94222D02*
X556157Y94452D01*
X556002Y94720D01*
X555950Y95027D01*
X556053Y95410D01*
X556312Y95678D01*
X556622Y95755D01*
X556932Y95717D01*
X557190Y95563D01*
X557707Y94797D01*
X558068Y94452D01*
X558585Y94222D01*
X559050Y94145D01*
Y95755D01*
G01X556467Y97322D02*
X556157Y97552D01*
X556002Y97820D01*
X555950Y98127D01*
X556053Y98510D01*
X556312Y98778D01*
X556622Y98855D01*
X556932Y98817D01*
X557190Y98663D01*
X557707Y97897D01*
X558068Y97552D01*
X558585Y97322D01*
X559050Y97245D01*
Y98855D01*
G01Y101610D02*
X555950D01*
X558172Y100192D01*
Y102108D01*
G01X562693Y87192D02*
X562463Y87347D01*
X562195Y87450D01*
X561888D01*
X561543Y87295D01*
X561275Y87037D01*
X561083Y86727D01*
X560930Y86210D01*
X560892Y85745D01*
X560968Y85280D01*
X561083Y84970D01*
X561313Y84660D01*
X561582Y84453D01*
X561850Y84350D01*
X562118D01*
X562387Y84453D01*
X562617Y84608D01*
X562808Y84815D01*
G01X564222Y86933D02*
X564452Y87243D01*
X564720Y87398D01*
X565027Y87450D01*
X565410Y87347D01*
X565678Y87088D01*
X565755Y86778D01*
X565717Y86468D01*
X565563Y86210D01*
X564797Y85693D01*
X564452Y85332D01*
X564222Y84815D01*
X564145Y84350D01*
X565755D01*
G01X567322Y86933D02*
X567552Y87243D01*
X567820Y87398D01*
X568127Y87450D01*
X568510Y87347D01*
X568778Y87088D01*
X568855Y86778D01*
X568817Y86468D01*
X568663Y86210D01*
X567897Y85693D01*
X567552Y85332D01*
X567322Y84815D01*
X567245Y84350D01*
X568855D01*
G01X571150D02*
X571418Y84402D01*
X571725Y84557D01*
X571917Y84815D01*
X571993Y85177D01*
X571917Y85538D01*
X571687Y85848D01*
X571342Y86003D01*
X570958D01*
X570728Y86107D01*
X570537Y86365D01*
X570460Y86727D01*
X570575Y87088D01*
X570843Y87347D01*
X571150Y87450D01*
X571457Y87347D01*
X571725Y87088D01*
X571840Y86727D01*
X571763Y86365D01*
X571572Y86107D01*
X571342Y86003D01*
X570958D01*
X570613Y85848D01*
X570383Y85538D01*
X570307Y85177D01*
X570383Y84815D01*
X570575Y84557D01*
X570882Y84402D01*
X571150Y84350D01*
G01X563193Y161842D02*
X562963Y161997D01*
X562695Y162100D01*
X562388D01*
X562043Y161945D01*
X561775Y161687D01*
X561583Y161377D01*
X561430Y160860D01*
X561392Y160395D01*
X561468Y159930D01*
X561583Y159620D01*
X561813Y159310D01*
X562082Y159103D01*
X562350Y159000D01*
X562618D01*
X562887Y159103D01*
X563117Y159258D01*
X563308Y159465D01*
G01X564722Y161583D02*
X564952Y161893D01*
X565220Y162048D01*
X565527Y162100D01*
X565910Y161997D01*
X566178Y161738D01*
X566255Y161428D01*
X566217Y161118D01*
X566063Y160860D01*
X565297Y160343D01*
X564952Y159982D01*
X564722Y159465D01*
X564645Y159000D01*
X566255D01*
G01X567822Y160292D02*
X568090Y160653D01*
X568320Y160860D01*
X568627Y160963D01*
X568895Y160860D01*
X569087Y160653D01*
X569240Y160343D01*
X569278Y159982D01*
X569240Y159672D01*
X569087Y159362D01*
X568857Y159103D01*
X568588Y159000D01*
X568282Y159103D01*
X568013Y159413D01*
X567860Y159878D01*
X567822Y160395D01*
X567898Y161067D01*
X568013Y161428D01*
X568205Y161790D01*
X568473Y162048D01*
X568742Y162100D01*
X569010Y161997D01*
X569202Y161738D01*
G01X570998Y159362D02*
X571267Y159103D01*
X571573Y159000D01*
X571880Y159103D01*
X572148Y159413D01*
X572340Y159878D01*
X572417Y160343D01*
Y160912D01*
X572340Y161377D01*
X572148Y161790D01*
X571918Y161997D01*
X571650Y162100D01*
X571343Y161997D01*
X571113Y161790D01*
X570960Y161480D01*
X570883Y161067D01*
X570960Y160705D01*
X571152Y160343D01*
X571382Y160137D01*
X571650Y160085D01*
X571957Y160188D01*
X572187Y160447D01*
X572417Y160912D01*
G01X558181Y162638D02*
X557871Y162868D01*
X557716Y163136D01*
X557664Y163443D01*
X557767Y163826D01*
X558026Y164094D01*
X558336Y164171D01*
X558646Y164133D01*
X558904Y163979D01*
X559421Y163213D01*
X559782Y162868D01*
X560299Y162638D01*
X560764Y162561D01*
Y164171D01*
G01X556950Y180683D02*
X560050D01*
Y182217D01*
G01X559585Y183707D02*
X559843Y183937D01*
X559998Y184205D01*
X560050Y184550D01*
X559947Y184895D01*
X559740Y185163D01*
X559378Y185355D01*
X558965Y185393D01*
X558552Y185317D01*
X558293Y185125D01*
X558087Y184857D01*
X558035Y184588D01*
X558087Y184320D01*
X558293Y183975D01*
X556950Y184090D01*
Y185125D01*
G01X566500Y209000D02*
X566768Y209052D01*
X567075Y209207D01*
X567267Y209465D01*
X567343Y209827D01*
X567267Y210188D01*
X567037Y210498D01*
X566692Y210653D01*
X566308D01*
X566078Y210757D01*
X565887Y211015D01*
X565810Y211377D01*
X565925Y211738D01*
X566193Y211997D01*
X566500Y212100D01*
X566807Y211997D01*
X567075Y211738D01*
X567190Y211377D01*
X567113Y211015D01*
X566922Y210757D01*
X566692Y210653D01*
X566308D01*
X565963Y210498D01*
X565733Y210188D01*
X565657Y209827D01*
X565733Y209465D01*
X565925Y209207D01*
X566232Y209052D01*
X566500Y209000D01*
G01X551272Y205292D02*
X551540Y205653D01*
X551770Y205860D01*
X552077Y205963D01*
X552345Y205860D01*
X552537Y205653D01*
X552690Y205343D01*
X552728Y204982D01*
X552690Y204672D01*
X552537Y204362D01*
X552307Y204103D01*
X552038Y204000D01*
X551732Y204103D01*
X551463Y204413D01*
X551310Y204878D01*
X551272Y205395D01*
X551348Y206067D01*
X551463Y206428D01*
X551655Y206790D01*
X551923Y207048D01*
X552192Y207100D01*
X552460Y206997D01*
X552652Y206738D01*
G01X563423Y204500D02*
X563500Y205172D01*
X563615Y205740D01*
X563768Y206257D01*
X563960Y206825D01*
X564267Y207600D01*
X562733D01*
G01X553557Y217542D02*
Y215320D01*
X553710Y214855D01*
X554017Y214545D01*
X554400Y214442D01*
X554783Y214545D01*
X555090Y214855D01*
X555243Y215320D01*
Y217542D01*
G01X556772Y217025D02*
X557002Y217335D01*
X557270Y217490D01*
X557577Y217542D01*
X557960Y217439D01*
X558228Y217180D01*
X558305Y216870D01*
X558267Y216560D01*
X558113Y216302D01*
X557347Y215785D01*
X557002Y215424D01*
X556772Y214907D01*
X556695Y214442D01*
X558305D01*
G01X559872Y215734D02*
X560140Y216095D01*
X560370Y216302D01*
X560677Y216405D01*
X560945Y216302D01*
X561137Y216095D01*
X561290Y215785D01*
X561328Y215424D01*
X561290Y215114D01*
X561137Y214804D01*
X560907Y214545D01*
X560638Y214442D01*
X560332Y214545D01*
X560063Y214855D01*
X559910Y215320D01*
X559872Y215837D01*
X559948Y216509D01*
X560063Y216870D01*
X560255Y217232D01*
X560523Y217490D01*
X560792Y217542D01*
X561060Y217439D01*
X561252Y217180D01*
G01X560430Y204235D02*
X557330D01*
X557950Y203775D01*
G01X560430D02*
Y204695D01*
G01X554208Y230693D02*
X554053Y230463D01*
X553950Y230195D01*
Y229888D01*
X554105Y229543D01*
X554363Y229275D01*
X554673Y229083D01*
X555190Y228930D01*
X555655Y228892D01*
X556120Y228968D01*
X556430Y229083D01*
X556740Y229313D01*
X556947Y229582D01*
X557050Y229850D01*
Y230118D01*
X556947Y230387D01*
X556792Y230617D01*
X556585Y230808D01*
G01X554467Y232222D02*
X554157Y232452D01*
X554002Y232720D01*
X553950Y233027D01*
X554053Y233410D01*
X554312Y233678D01*
X554622Y233755D01*
X554932Y233717D01*
X555190Y233563D01*
X555707Y232797D01*
X556068Y232452D01*
X556585Y232222D01*
X557050Y232145D01*
Y233755D01*
G01X556585Y235207D02*
X556843Y235437D01*
X556998Y235705D01*
X557050Y236050D01*
X556947Y236395D01*
X556740Y236663D01*
X556378Y236855D01*
X555965Y236893D01*
X555552Y236817D01*
X555293Y236625D01*
X555087Y236357D01*
X555035Y236088D01*
X555087Y235820D01*
X555293Y235475D01*
X553950Y235590D01*
Y236625D01*
G01X555758Y238422D02*
X555397Y238690D01*
X555190Y238920D01*
X555087Y239227D01*
X555190Y239495D01*
X555397Y239687D01*
X555707Y239840D01*
X556068Y239878D01*
X556378Y239840D01*
X556688Y239687D01*
X556947Y239457D01*
X557050Y239188D01*
X556947Y238882D01*
X556637Y238613D01*
X556172Y238460D01*
X555655Y238422D01*
X554983Y238498D01*
X554622Y238613D01*
X554260Y238805D01*
X554002Y239073D01*
X553950Y239342D01*
X554053Y239610D01*
X554312Y239802D01*
G01X558708Y230693D02*
X558553Y230463D01*
X558450Y230195D01*
Y229888D01*
X558605Y229543D01*
X558863Y229275D01*
X559173Y229083D01*
X559690Y228930D01*
X560155Y228892D01*
X560620Y228968D01*
X560930Y229083D01*
X561240Y229313D01*
X561447Y229582D01*
X561550Y229850D01*
Y230118D01*
X561447Y230387D01*
X561292Y230617D01*
X561085Y230808D01*
G01X558967Y232222D02*
X558657Y232452D01*
X558502Y232720D01*
X558450Y233027D01*
X558553Y233410D01*
X558812Y233678D01*
X559122Y233755D01*
X559432Y233717D01*
X559690Y233563D01*
X560207Y232797D01*
X560568Y232452D01*
X561085Y232222D01*
X561550Y232145D01*
Y233755D01*
G01X561085Y235207D02*
X561343Y235437D01*
X561498Y235705D01*
X561550Y236050D01*
X561447Y236395D01*
X561240Y236663D01*
X560878Y236855D01*
X560465Y236893D01*
X560052Y236817D01*
X559793Y236625D01*
X559587Y236357D01*
X559535Y236088D01*
X559587Y235820D01*
X559793Y235475D01*
X558450Y235590D01*
Y236625D01*
G01X561188Y238498D02*
X561447Y238767D01*
X561550Y239073D01*
X561447Y239380D01*
X561137Y239648D01*
X560672Y239840D01*
X560207Y239917D01*
X559638D01*
X559173Y239840D01*
X558760Y239648D01*
X558553Y239418D01*
X558450Y239150D01*
X558553Y238843D01*
X558760Y238613D01*
X559070Y238460D01*
X559483Y238383D01*
X559845Y238460D01*
X560207Y238652D01*
X560413Y238882D01*
X560465Y239150D01*
X560362Y239457D01*
X560103Y239687D01*
X559638Y239917D01*
G01X563208Y228193D02*
X563053Y227963D01*
X562950Y227695D01*
Y227388D01*
X563105Y227043D01*
X563363Y226775D01*
X563673Y226583D01*
X564190Y226430D01*
X564655Y226392D01*
X565120Y226468D01*
X565430Y226583D01*
X565740Y226813D01*
X565947Y227082D01*
X566050Y227350D01*
Y227618D01*
X565947Y227887D01*
X565792Y228117D01*
X565585Y228308D01*
G01X563467Y229722D02*
X563157Y229952D01*
X563002Y230220D01*
X562950Y230527D01*
X563053Y230910D01*
X563312Y231178D01*
X563622Y231255D01*
X563932Y231217D01*
X564190Y231063D01*
X564707Y230297D01*
X565068Y229952D01*
X565585Y229722D01*
X566050Y229645D01*
Y231255D01*
G01X564758Y232822D02*
X564397Y233090D01*
X564190Y233320D01*
X564087Y233627D01*
X564190Y233895D01*
X564397Y234087D01*
X564707Y234240D01*
X565068Y234278D01*
X565378Y234240D01*
X565688Y234087D01*
X565947Y233857D01*
X566050Y233588D01*
X565947Y233282D01*
X565637Y233013D01*
X565172Y232860D01*
X564655Y232822D01*
X563983Y232898D01*
X563622Y233013D01*
X563260Y233205D01*
X563002Y233473D01*
X562950Y233742D01*
X563053Y234010D01*
X563312Y234202D01*
G01X566050Y237110D02*
X562950D01*
X565172Y235692D01*
Y237608D01*
G01X565950Y220000D02*
Y223100D01*
X565490Y222480D01*
G01Y220000D02*
X566410D01*
G01X568322Y222583D02*
X568552Y222893D01*
X568820Y223048D01*
X569127Y223100D01*
X569510Y222997D01*
X569778Y222738D01*
X569855Y222428D01*
X569817Y222118D01*
X569663Y221860D01*
X568897Y221343D01*
X568552Y220982D01*
X568322Y220465D01*
X568245Y220000D01*
X569855D01*
G01X559450Y223000D02*
Y226100D01*
X558990Y225480D01*
G01Y223000D02*
X559910D01*
G01X561707Y223620D02*
X561937Y223258D01*
X562243Y223052D01*
X562588Y223000D01*
X562895Y223052D01*
X563202Y223310D01*
X563393Y223620D01*
X563432Y223930D01*
X563355Y224292D01*
X563087Y224550D01*
X562818Y224653D01*
X562473D01*
G01X562818D02*
X563048Y224808D01*
X563240Y225067D01*
X563317Y225377D01*
X563240Y225687D01*
X563048Y225945D01*
X562703Y226100D01*
X562358Y226048D01*
X562013Y225842D01*
G01X562083Y239950D02*
Y243050D01*
X563042D01*
X563348Y242895D01*
X563540Y242688D01*
X563617Y242275D01*
X563540Y241862D01*
X563310Y241603D01*
X563042Y241448D01*
X562083D01*
G01X563042D02*
X563617Y239950D01*
G01X565222Y242533D02*
X565452Y242843D01*
X565720Y242998D01*
X566027Y243050D01*
X566410Y242947D01*
X566678Y242688D01*
X566755Y242378D01*
X566717Y242068D01*
X566563Y241810D01*
X565797Y241293D01*
X565452Y240932D01*
X565222Y240415D01*
X565145Y239950D01*
X566755D01*
G01X568207Y240415D02*
X568437Y240157D01*
X568705Y240002D01*
X569050Y239950D01*
X569395Y240053D01*
X569663Y240260D01*
X569855Y240622D01*
X569893Y241035D01*
X569817Y241448D01*
X569625Y241707D01*
X569357Y241913D01*
X569088Y241965D01*
X568820Y241913D01*
X568475Y241707D01*
X568590Y243050D01*
X569625D01*
G01X572610Y239950D02*
Y243050D01*
X571192Y240828D01*
X573108D01*
G01X561730Y278233D02*
X562040Y278425D01*
X562247Y278655D01*
X562350Y278923D01*
X562247Y279230D01*
X562040Y279460D01*
X561730Y279690D01*
X561317Y279767D01*
X559250D01*
G01X562350Y282100D02*
X559250D01*
X559870Y281640D01*
G01X562350D02*
Y282560D01*
G01Y285660D02*
X559250D01*
X561472Y284242D01*
Y286158D01*
G01X559343Y332442D02*
X559113Y332597D01*
X558845Y332700D01*
X558538D01*
X558193Y332545D01*
X557925Y332287D01*
X557733Y331977D01*
X557580Y331460D01*
X557542Y330995D01*
X557618Y330530D01*
X557733Y330220D01*
X557963Y329910D01*
X558232Y329703D01*
X558500Y329600D01*
X558768D01*
X559037Y329703D01*
X559267Y329858D01*
X559458Y330065D01*
G01X560893Y358192D02*
X560663Y358347D01*
X560395Y358450D01*
X560088D01*
X559743Y358295D01*
X559475Y358037D01*
X559283Y357727D01*
X559130Y357210D01*
X559092Y356745D01*
X559168Y356280D01*
X559283Y355970D01*
X559513Y355660D01*
X559782Y355453D01*
X560050Y355350D01*
X560318D01*
X560587Y355453D01*
X560817Y355608D01*
X561008Y355815D01*
G01X562422Y357933D02*
X562652Y358243D01*
X562920Y358398D01*
X563227Y358450D01*
X563610Y358347D01*
X563878Y358088D01*
X563955Y357778D01*
X563917Y357468D01*
X563763Y357210D01*
X562997Y356693D01*
X562652Y356332D01*
X562422Y355815D01*
X562345Y355350D01*
X563955D01*
G01X558850Y349050D02*
Y345950D01*
G01X557968Y349050D02*
X559732D01*
G01X561183Y345950D02*
Y349050D01*
X562103D01*
X562410Y348895D01*
X562640Y348533D01*
X562717Y348120D01*
X562640Y347707D01*
X562448Y347397D01*
X562103Y347242D01*
X561183D01*
G01X565510Y345950D02*
Y349050D01*
X564092Y346828D01*
X566008D01*
G01X567307Y346570D02*
X567537Y346208D01*
X567843Y346002D01*
X568188Y345950D01*
X568495Y346002D01*
X568802Y346260D01*
X568993Y346570D01*
X569032Y346880D01*
X568955Y347242D01*
X568687Y347500D01*
X568418Y347603D01*
X568073D01*
G01X568418D02*
X568648Y347758D01*
X568840Y348017D01*
X568917Y348327D01*
X568840Y348637D01*
X568648Y348895D01*
X568303Y349050D01*
X567958Y348998D01*
X567613Y348792D01*
G01X554133Y389950D02*
Y393050D01*
X555092D01*
X555398Y392895D01*
X555590Y392688D01*
X555667Y392275D01*
X555590Y391862D01*
X555360Y391603D01*
X555092Y391448D01*
X554133D01*
G01X555092D02*
X555667Y389950D01*
G01X558000D02*
Y393050D01*
X557540Y392430D01*
G01Y389950D02*
X558460D01*
G01X561560D02*
Y393050D01*
X560142Y390828D01*
X562058D01*
G01X565519Y381368D02*
X565788Y381109D01*
X566094Y381006D01*
X566401Y381109D01*
X566669Y381419D01*
X566861Y381884D01*
X566938Y382349D01*
Y382918D01*
X566861Y383383D01*
X566669Y383796D01*
X566439Y384003D01*
X566171Y384106D01*
X565864Y384003D01*
X565634Y383796D01*
X565481Y383486D01*
X565404Y383073D01*
X565481Y382711D01*
X565673Y382349D01*
X565903Y382143D01*
X566171Y382091D01*
X566478Y382194D01*
X566708Y382453D01*
X566938Y382918D01*
G01X568676Y406884D02*
X565576D01*
Y407650D01*
X565731Y407957D01*
X565938Y408187D01*
X566248Y408379D01*
X566609Y408532D01*
X567126Y408570D01*
X567643Y408532D01*
X568004Y408379D01*
X568314Y408187D01*
X568521Y407957D01*
X568676Y407650D01*
Y406884D01*
G01X568263Y410022D02*
X568521Y410329D01*
X568676Y410674D01*
Y410980D01*
X568521Y411287D01*
X568263Y411517D01*
X567901Y411632D01*
X567539Y411555D01*
X567229Y411364D01*
X567023Y411019D01*
X566919Y410559D01*
X566713Y410290D01*
X566351Y410175D01*
X565989Y410252D01*
X565731Y410444D01*
X565576Y410712D01*
Y410980D01*
X565679Y411249D01*
X565938Y411479D01*
G01X568676Y413927D02*
X568624Y414195D01*
X568469Y414502D01*
X568211Y414694D01*
X567849Y414770D01*
X567488Y414694D01*
X567178Y414464D01*
X567023Y414119D01*
Y413735D01*
X566919Y413505D01*
X566661Y413314D01*
X566299Y413237D01*
X565938Y413352D01*
X565679Y413620D01*
X565576Y413927D01*
X565679Y414234D01*
X565938Y414502D01*
X566299Y414617D01*
X566661Y414540D01*
X566919Y414349D01*
X567023Y414119D01*
Y413735D01*
X567178Y413390D01*
X567488Y413160D01*
X567849Y413084D01*
X568211Y413160D01*
X568469Y413352D01*
X568624Y413659D01*
X568676Y413927D01*
G01X556865Y406884D02*
X553765D01*
Y407650D01*
X553920Y407957D01*
X554127Y408187D01*
X554437Y408379D01*
X554798Y408532D01*
X555315Y408570D01*
X555832Y408532D01*
X556193Y408379D01*
X556503Y408187D01*
X556710Y407957D01*
X556865Y407650D01*
Y406884D01*
G01X556452Y410022D02*
X556710Y410329D01*
X556865Y410674D01*
Y410980D01*
X556710Y411287D01*
X556452Y411517D01*
X556090Y411632D01*
X555728Y411555D01*
X555418Y411364D01*
X555212Y411019D01*
X555108Y410559D01*
X554902Y410290D01*
X554540Y410175D01*
X554178Y410252D01*
X553920Y410444D01*
X553765Y410712D01*
Y410980D01*
X553868Y411249D01*
X554127Y411479D01*
G01X556865Y413850D02*
X556193Y413927D01*
X555625Y414042D01*
X555108Y414195D01*
X554540Y414387D01*
X553765Y414694D01*
Y413160D01*
G01X554133Y394450D02*
Y397550D01*
X555092D01*
X555398Y397395D01*
X555590Y397188D01*
X555667Y396775D01*
X555590Y396362D01*
X555360Y396103D01*
X555092Y395948D01*
X554133D01*
G01X555092D02*
X555667Y394450D01*
G01X558000D02*
Y397550D01*
X557540Y396930D01*
G01Y394450D02*
X558460D01*
G01X560257Y395070D02*
X560487Y394708D01*
X560793Y394502D01*
X561138Y394450D01*
X561445Y394502D01*
X561752Y394760D01*
X561943Y395070D01*
X561982Y395380D01*
X561905Y395742D01*
X561637Y396000D01*
X561368Y396103D01*
X561023D01*
G01X561368D02*
X561598Y396258D01*
X561790Y396517D01*
X561867Y396827D01*
X561790Y397137D01*
X561598Y397395D01*
X561253Y397550D01*
X560908Y397498D01*
X560563Y397292D01*
G01X555933Y402591D02*
Y399491D01*
G01X555051Y402591D02*
X556815D01*
G01X558266Y399491D02*
Y402591D01*
X559186D01*
X559493Y402436D01*
X559723Y402074D01*
X559800Y401661D01*
X559723Y401248D01*
X559531Y400938D01*
X559186Y400783D01*
X558266D01*
G01X561290Y400111D02*
X561520Y399749D01*
X561826Y399543D01*
X562171Y399491D01*
X562478Y399543D01*
X562785Y399801D01*
X562976Y400111D01*
X563015Y400421D01*
X562938Y400783D01*
X562670Y401041D01*
X562401Y401144D01*
X562056D01*
G01X562401D02*
X562631Y401299D01*
X562823Y401558D01*
X562900Y401868D01*
X562823Y402178D01*
X562631Y402436D01*
X562286Y402591D01*
X561941Y402539D01*
X561596Y402333D01*
G01X564505Y400783D02*
X564773Y401144D01*
X565003Y401351D01*
X565310Y401454D01*
X565578Y401351D01*
X565770Y401144D01*
X565923Y400834D01*
X565961Y400473D01*
X565923Y400163D01*
X565770Y399853D01*
X565540Y399594D01*
X565271Y399491D01*
X564965Y399594D01*
X564696Y399904D01*
X564543Y400369D01*
X564505Y400886D01*
X564581Y401558D01*
X564696Y401919D01*
X564888Y402281D01*
X565156Y402539D01*
X565425Y402591D01*
X565693Y402488D01*
X565885Y402229D01*
G01X567733Y398091D02*
Y394991D01*
G01X566851Y398091D02*
X568615D01*
G01X570066Y394991D02*
Y398091D01*
X570986D01*
X571293Y397936D01*
X571523Y397574D01*
X571600Y397161D01*
X571523Y396748D01*
X571331Y396438D01*
X570986Y396283D01*
X570066D01*
G01X573090Y395611D02*
X573320Y395249D01*
X573626Y395043D01*
X573971Y394991D01*
X574278Y395043D01*
X574585Y395301D01*
X574776Y395611D01*
X574815Y395921D01*
X574738Y396283D01*
X574470Y396541D01*
X574201Y396644D01*
X573856D01*
G01X574201D02*
X574431Y396799D01*
X574623Y397058D01*
X574700Y397368D01*
X574623Y397678D01*
X574431Y397936D01*
X574086Y398091D01*
X573741Y398039D01*
X573396Y397833D01*
G01X576956Y394991D02*
X577033Y395663D01*
X577148Y396231D01*
X577301Y396748D01*
X577493Y397316D01*
X577800Y398091D01*
X576266D01*
G01X559343Y418792D02*
X559113Y418947D01*
X558845Y419050D01*
X558538D01*
X558193Y418895D01*
X557925Y418637D01*
X557733Y418327D01*
X557580Y417810D01*
X557542Y417345D01*
X557618Y416880D01*
X557733Y416570D01*
X557963Y416260D01*
X558232Y416053D01*
X558500Y415950D01*
X558768D01*
X559037Y416053D01*
X559267Y416208D01*
X559458Y416415D01*
G01X556550Y420557D02*
X553450D01*
Y421323D01*
X553605Y421630D01*
X553812Y421860D01*
X554122Y422052D01*
X554483Y422205D01*
X555000Y422243D01*
X555517Y422205D01*
X555878Y422052D01*
X556188Y421860D01*
X556395Y421630D01*
X556550Y421323D01*
Y420557D01*
G01X556137Y423695D02*
X556395Y424002D01*
X556550Y424347D01*
Y424653D01*
X556395Y424960D01*
X556137Y425190D01*
X555775Y425305D01*
X555413Y425228D01*
X555103Y425037D01*
X554897Y424692D01*
X554793Y424232D01*
X554587Y423963D01*
X554225Y423848D01*
X553863Y423925D01*
X553605Y424117D01*
X553450Y424385D01*
Y424653D01*
X553553Y424922D01*
X553812Y425152D01*
G01X553967Y426872D02*
X553657Y427102D01*
X553502Y427370D01*
X553450Y427677D01*
X553553Y428060D01*
X553812Y428328D01*
X554122Y428405D01*
X554432Y428367D01*
X554690Y428213D01*
X555207Y427447D01*
X555568Y427102D01*
X556085Y426872D01*
X556550Y426795D01*
Y428405D01*
G01X568676Y420663D02*
X565576D01*
Y421429D01*
X565731Y421736D01*
X565938Y421966D01*
X566248Y422158D01*
X566609Y422311D01*
X567126Y422349D01*
X567643Y422311D01*
X568004Y422158D01*
X568314Y421966D01*
X568521Y421736D01*
X568676Y421429D01*
Y420663D01*
G01X568263Y423801D02*
X568521Y424108D01*
X568676Y424453D01*
Y424759D01*
X568521Y425066D01*
X568263Y425296D01*
X567901Y425411D01*
X567539Y425334D01*
X567229Y425143D01*
X567023Y424798D01*
X566919Y424338D01*
X566713Y424069D01*
X566351Y423954D01*
X565989Y424031D01*
X565731Y424223D01*
X565576Y424491D01*
Y424759D01*
X565679Y425028D01*
X565938Y425258D01*
G01X568056Y426863D02*
X568418Y427093D01*
X568624Y427399D01*
X568676Y427744D01*
X568624Y428051D01*
X568366Y428358D01*
X568056Y428549D01*
X567746Y428588D01*
X567384Y428511D01*
X567126Y428243D01*
X567023Y427974D01*
Y427629D01*
G01Y427974D02*
X566868Y428204D01*
X566609Y428396D01*
X566299Y428473D01*
X565989Y428396D01*
X565731Y428204D01*
X565576Y427859D01*
X565628Y427514D01*
X565834Y427169D01*
G01X553979Y429905D02*
X554937Y433005D01*
X555895Y429905D01*
G01X555550Y430990D02*
X554324D01*
G01X566542Y430450D02*
X567500Y433550D01*
X568458Y430450D01*
G01X568113Y431535D02*
X566887D01*
G01X574193Y60842D02*
X573963Y60997D01*
X573695Y61100D01*
X573388D01*
X573043Y60945D01*
X572775Y60687D01*
X572583Y60377D01*
X572430Y59860D01*
X572392Y59395D01*
X572468Y58930D01*
X572583Y58620D01*
X572813Y58310D01*
X573082Y58103D01*
X573350Y58000D01*
X573618D01*
X573887Y58103D01*
X574117Y58258D01*
X574308Y58465D01*
G01X575722Y60583D02*
X575952Y60893D01*
X576220Y61048D01*
X576527Y61100D01*
X576910Y60997D01*
X577178Y60738D01*
X577255Y60428D01*
X577217Y60118D01*
X577063Y59860D01*
X576297Y59343D01*
X575952Y58982D01*
X575722Y58465D01*
X575645Y58000D01*
X577255D01*
G01X578707Y58620D02*
X578937Y58258D01*
X579243Y58052D01*
X579588Y58000D01*
X579895Y58052D01*
X580202Y58310D01*
X580393Y58620D01*
X580432Y58930D01*
X580355Y59292D01*
X580087Y59550D01*
X579818Y59653D01*
X579473D01*
G01X579818D02*
X580048Y59808D01*
X580240Y60067D01*
X580317Y60377D01*
X580240Y60687D01*
X580048Y60945D01*
X579703Y61100D01*
X579358Y61048D01*
X579013Y60842D01*
G01X582650Y58000D02*
Y61100D01*
X582190Y60480D01*
G01Y58000D02*
X583110D01*
G01X575908Y64093D02*
X575753Y63863D01*
X575650Y63595D01*
Y63288D01*
X575805Y62943D01*
X576063Y62675D01*
X576373Y62483D01*
X576890Y62330D01*
X577355Y62292D01*
X577820Y62368D01*
X578130Y62483D01*
X578440Y62713D01*
X578647Y62982D01*
X578750Y63250D01*
Y63518D01*
X578647Y63787D01*
X578492Y64017D01*
X578285Y64208D01*
G01X576167Y65622D02*
X575857Y65852D01*
X575702Y66120D01*
X575650Y66427D01*
X575753Y66810D01*
X576012Y67078D01*
X576322Y67155D01*
X576632Y67117D01*
X576890Y66963D01*
X577407Y66197D01*
X577768Y65852D01*
X578285Y65622D01*
X578750Y65545D01*
Y67155D01*
G01X576167Y68722D02*
X575857Y68952D01*
X575702Y69220D01*
X575650Y69527D01*
X575753Y69910D01*
X576012Y70178D01*
X576322Y70255D01*
X576632Y70217D01*
X576890Y70063D01*
X577407Y69297D01*
X577768Y68952D01*
X578285Y68722D01*
X578750Y68645D01*
Y70255D01*
G01Y72473D02*
X578078Y72550D01*
X577510Y72665D01*
X576993Y72818D01*
X576425Y73010D01*
X575650Y73317D01*
Y71783D01*
G01X579000Y75083D02*
X575900D01*
Y76042D01*
X576055Y76348D01*
X576262Y76540D01*
X576675Y76617D01*
X577088Y76540D01*
X577347Y76310D01*
X577502Y76042D01*
Y75083D01*
G01Y76042D02*
X579000Y76617D01*
G01X576417Y78222D02*
X576107Y78452D01*
X575952Y78720D01*
X575900Y79027D01*
X576003Y79410D01*
X576262Y79678D01*
X576572Y79755D01*
X576882Y79717D01*
X577140Y79563D01*
X577657Y78797D01*
X578018Y78452D01*
X578535Y78222D01*
X579000Y78145D01*
Y79755D01*
G01X576417Y81322D02*
X576107Y81552D01*
X575952Y81820D01*
X575900Y82127D01*
X576003Y82510D01*
X576262Y82778D01*
X576572Y82855D01*
X576882Y82817D01*
X577140Y82663D01*
X577657Y81897D01*
X578018Y81552D01*
X578535Y81322D01*
X579000Y81245D01*
Y82855D01*
G01Y85150D02*
X578948Y85418D01*
X578793Y85725D01*
X578535Y85917D01*
X578173Y85993D01*
X577812Y85917D01*
X577502Y85687D01*
X577347Y85342D01*
Y84958D01*
X577243Y84728D01*
X576985Y84537D01*
X576623Y84460D01*
X576262Y84575D01*
X576003Y84843D01*
X575900Y85150D01*
X576003Y85457D01*
X576262Y85725D01*
X576623Y85840D01*
X576985Y85763D01*
X577243Y85572D01*
X577347Y85342D01*
Y84958D01*
X577502Y84613D01*
X577812Y84383D01*
X578173Y84307D01*
X578535Y84383D01*
X578793Y84575D01*
X578948Y84882D01*
X579000Y85150D01*
G01X569772Y63292D02*
X570040Y63653D01*
X570270Y63860D01*
X570577Y63963D01*
X570845Y63860D01*
X571037Y63653D01*
X571190Y63343D01*
X571228Y62982D01*
X571190Y62672D01*
X571037Y62362D01*
X570807Y62103D01*
X570538Y62000D01*
X570232Y62103D01*
X569963Y62413D01*
X569810Y62878D01*
X569772Y63395D01*
X569848Y64067D01*
X569963Y64428D01*
X570155Y64790D01*
X570423Y65048D01*
X570692Y65100D01*
X570960Y64997D01*
X571152Y64738D01*
G01X569950Y72000D02*
Y75100D01*
X569490Y74480D01*
G01Y72000D02*
X570410D01*
G01X573050Y75100D02*
X572743Y74997D01*
X572513Y74738D01*
X572360Y74428D01*
X572245Y74015D01*
X572207Y73550D01*
X572245Y73085D01*
X572360Y72672D01*
X572513Y72362D01*
X572743Y72103D01*
X573050Y72000D01*
X573357Y72103D01*
X573587Y72362D01*
X573740Y72672D01*
X573855Y73085D01*
X573893Y73550D01*
X573855Y74015D01*
X573740Y74428D01*
X573587Y74738D01*
X573357Y74997D01*
X573050Y75100D01*
G01X568450Y92133D02*
X571550D01*
Y93667D01*
G01Y96000D02*
X568450D01*
X569070Y95540D01*
G01X571550D02*
Y96460D01*
G01X570930Y98257D02*
X571292Y98487D01*
X571498Y98793D01*
X571550Y99138D01*
X571498Y99445D01*
X571240Y99752D01*
X570930Y99943D01*
X570620Y99982D01*
X570258Y99905D01*
X570000Y99637D01*
X569897Y99368D01*
Y99023D01*
G01Y99368D02*
X569742Y99598D01*
X569483Y99790D01*
X569173Y99867D01*
X568863Y99790D01*
X568605Y99598D01*
X568450Y99253D01*
X568502Y98908D01*
X568708Y98563D01*
G01X575933Y106391D02*
Y103291D01*
G01X575051Y106391D02*
X576815D01*
G01X578266Y103291D02*
Y106391D01*
X579186D01*
X579493Y106236D01*
X579723Y105874D01*
X579800Y105461D01*
X579723Y105048D01*
X579531Y104738D01*
X579186Y104583D01*
X578266D01*
G01X581405Y105874D02*
X581635Y106184D01*
X581903Y106339D01*
X582210Y106391D01*
X582593Y106288D01*
X582861Y106029D01*
X582938Y105719D01*
X582900Y105409D01*
X582746Y105151D01*
X581980Y104634D01*
X581635Y104273D01*
X581405Y103756D01*
X581328Y103291D01*
X582938D01*
G01X584505Y105874D02*
X584735Y106184D01*
X585003Y106339D01*
X585310Y106391D01*
X585693Y106288D01*
X585961Y106029D01*
X586038Y105719D01*
X586000Y105409D01*
X585846Y105151D01*
X585080Y104634D01*
X584735Y104273D01*
X584505Y103756D01*
X584428Y103291D01*
X586038D01*
G01X574850Y99050D02*
Y95950D01*
G01X573968Y99050D02*
X575732D01*
G01X577183Y95950D02*
Y99050D01*
X578103D01*
X578410Y98895D01*
X578640Y98533D01*
X578717Y98120D01*
X578640Y97707D01*
X578448Y97397D01*
X578103Y97242D01*
X577183D01*
G01X581510Y95950D02*
Y99050D01*
X580092Y96828D01*
X582008D01*
G01X584150Y95950D02*
Y99050D01*
X583690Y98430D01*
G01Y95950D02*
X584610D01*
G01X581350Y185550D02*
Y182450D01*
G01X580468Y185550D02*
X582232D01*
G01X583683Y182450D02*
Y185550D01*
X584603D01*
X584910Y185395D01*
X585140Y185033D01*
X585217Y184620D01*
X585140Y184207D01*
X584948Y183897D01*
X584603Y183742D01*
X583683D01*
G01X586822Y185033D02*
X587052Y185343D01*
X587320Y185498D01*
X587627Y185550D01*
X588010Y185447D01*
X588278Y185188D01*
X588355Y184878D01*
X588317Y184568D01*
X588163Y184310D01*
X587397Y183793D01*
X587052Y183432D01*
X586822Y182915D01*
X586745Y182450D01*
X588355D01*
G01X590573D02*
X590650Y183122D01*
X590765Y183690D01*
X590918Y184207D01*
X591110Y184775D01*
X591417Y185550D01*
X589883D01*
G01X568708Y209193D02*
X568553Y208963D01*
X568450Y208695D01*
Y208388D01*
X568605Y208043D01*
X568863Y207775D01*
X569173Y207583D01*
X569690Y207430D01*
X570155Y207392D01*
X570620Y207468D01*
X570930Y207583D01*
X571240Y207813D01*
X571447Y208082D01*
X571550Y208350D01*
Y208618D01*
X571447Y208887D01*
X571292Y209117D01*
X571085Y209308D01*
G01X568967Y210722D02*
X568657Y210952D01*
X568502Y211220D01*
X568450Y211527D01*
X568553Y211910D01*
X568812Y212178D01*
X569122Y212255D01*
X569432Y212217D01*
X569690Y212063D01*
X570207Y211297D01*
X570568Y210952D01*
X571085Y210722D01*
X571550Y210645D01*
Y212255D01*
G01X570258Y213822D02*
X569897Y214090D01*
X569690Y214320D01*
X569587Y214627D01*
X569690Y214895D01*
X569897Y215087D01*
X570207Y215240D01*
X570568Y215278D01*
X570878Y215240D01*
X571188Y215087D01*
X571447Y214857D01*
X571550Y214588D01*
X571447Y214282D01*
X571137Y214013D01*
X570672Y213860D01*
X570155Y213822D01*
X569483Y213898D01*
X569122Y214013D01*
X568760Y214205D01*
X568502Y214473D01*
X568450Y214742D01*
X568553Y215010D01*
X568812Y215202D01*
G01X568967Y216922D02*
X568657Y217152D01*
X568502Y217420D01*
X568450Y217727D01*
X568553Y218110D01*
X568812Y218378D01*
X569122Y218455D01*
X569432Y218417D01*
X569690Y218263D01*
X570207Y217497D01*
X570568Y217152D01*
X571085Y216922D01*
X571550Y216845D01*
Y218455D01*
G01X574708Y208193D02*
X574553Y207963D01*
X574450Y207695D01*
Y207388D01*
X574605Y207043D01*
X574863Y206775D01*
X575173Y206583D01*
X575690Y206430D01*
X576155Y206392D01*
X576620Y206468D01*
X576930Y206583D01*
X577240Y206813D01*
X577447Y207082D01*
X577550Y207350D01*
Y207618D01*
X577447Y207887D01*
X577292Y208117D01*
X577085Y208308D01*
G01X574967Y209722D02*
X574657Y209952D01*
X574502Y210220D01*
X574450Y210527D01*
X574553Y210910D01*
X574812Y211178D01*
X575122Y211255D01*
X575432Y211217D01*
X575690Y211063D01*
X576207Y210297D01*
X576568Y209952D01*
X577085Y209722D01*
X577550Y209645D01*
Y211255D01*
G01X577085Y212707D02*
X577343Y212937D01*
X577498Y213205D01*
X577550Y213550D01*
X577447Y213895D01*
X577240Y214163D01*
X576878Y214355D01*
X576465Y214393D01*
X576052Y214317D01*
X575793Y214125D01*
X575587Y213857D01*
X575535Y213588D01*
X575587Y213320D01*
X575793Y212975D01*
X574450Y213090D01*
Y214125D01*
G01X577550Y216573D02*
X576878Y216650D01*
X576310Y216765D01*
X575793Y216918D01*
X575225Y217110D01*
X574450Y217417D01*
Y215883D01*
G01X568708Y228693D02*
X568553Y228463D01*
X568450Y228195D01*
Y227888D01*
X568605Y227543D01*
X568863Y227275D01*
X569173Y227083D01*
X569690Y226930D01*
X570155Y226892D01*
X570620Y226968D01*
X570930Y227083D01*
X571240Y227313D01*
X571447Y227582D01*
X571550Y227850D01*
Y228118D01*
X571447Y228387D01*
X571292Y228617D01*
X571085Y228808D01*
G01X568967Y230222D02*
X568657Y230452D01*
X568502Y230720D01*
X568450Y231027D01*
X568553Y231410D01*
X568812Y231678D01*
X569122Y231755D01*
X569432Y231717D01*
X569690Y231563D01*
X570207Y230797D01*
X570568Y230452D01*
X571085Y230222D01*
X571550Y230145D01*
Y231755D01*
G01X570258Y233322D02*
X569897Y233590D01*
X569690Y233820D01*
X569587Y234127D01*
X569690Y234395D01*
X569897Y234587D01*
X570207Y234740D01*
X570568Y234778D01*
X570878Y234740D01*
X571188Y234587D01*
X571447Y234357D01*
X571550Y234088D01*
X571447Y233782D01*
X571137Y233513D01*
X570672Y233360D01*
X570155Y233322D01*
X569483Y233398D01*
X569122Y233513D01*
X568760Y233705D01*
X568502Y233973D01*
X568450Y234242D01*
X568553Y234510D01*
X568812Y234702D01*
G01X571550Y237073D02*
X570878Y237150D01*
X570310Y237265D01*
X569793Y237418D01*
X569225Y237610D01*
X568450Y237917D01*
Y236383D01*
G01X576950Y229083D02*
X573850D01*
Y230042D01*
X574005Y230348D01*
X574212Y230540D01*
X574625Y230617D01*
X575038Y230540D01*
X575297Y230310D01*
X575452Y230042D01*
Y229083D01*
G01Y230042D02*
X576950Y230617D01*
G01X574367Y232222D02*
X574057Y232452D01*
X573902Y232720D01*
X573850Y233027D01*
X573953Y233410D01*
X574212Y233678D01*
X574522Y233755D01*
X574832Y233717D01*
X575090Y233563D01*
X575607Y232797D01*
X575968Y232452D01*
X576485Y232222D01*
X576950Y232145D01*
Y233755D01*
G01X576485Y235207D02*
X576743Y235437D01*
X576898Y235705D01*
X576950Y236050D01*
X576847Y236395D01*
X576640Y236663D01*
X576278Y236855D01*
X575865Y236893D01*
X575452Y236817D01*
X575193Y236625D01*
X574987Y236357D01*
X574935Y236088D01*
X574987Y235820D01*
X575193Y235475D01*
X573850Y235590D01*
Y236625D01*
G01X576485Y238307D02*
X576743Y238537D01*
X576898Y238805D01*
X576950Y239150D01*
X576847Y239495D01*
X576640Y239763D01*
X576278Y239955D01*
X575865Y239993D01*
X575452Y239917D01*
X575193Y239725D01*
X574987Y239457D01*
X574935Y239188D01*
X574987Y238920D01*
X575193Y238575D01*
X573850Y238690D01*
Y239725D01*
G01X571583Y223000D02*
Y226100D01*
X572542D01*
X572848Y225945D01*
X573040Y225738D01*
X573117Y225325D01*
X573040Y224912D01*
X572810Y224653D01*
X572542Y224498D01*
X571583D01*
G01X572542D02*
X573117Y223000D01*
G01X574722Y225583D02*
X574952Y225893D01*
X575220Y226048D01*
X575527Y226100D01*
X575910Y225997D01*
X576178Y225738D01*
X576255Y225428D01*
X576217Y225118D01*
X576063Y224860D01*
X575297Y224343D01*
X574952Y223982D01*
X574722Y223465D01*
X574645Y223000D01*
X576255D01*
G01X579010D02*
Y226100D01*
X577592Y223878D01*
X579508D01*
G01X581650Y223000D02*
X581918Y223052D01*
X582225Y223207D01*
X582417Y223465D01*
X582493Y223827D01*
X582417Y224188D01*
X582187Y224498D01*
X581842Y224653D01*
X581458D01*
X581228Y224757D01*
X581037Y225015D01*
X580960Y225377D01*
X581075Y225738D01*
X581343Y225997D01*
X581650Y226100D01*
X581957Y225997D01*
X582225Y225738D01*
X582340Y225377D01*
X582263Y225015D01*
X582072Y224757D01*
X581842Y224653D01*
X581458D01*
X581113Y224498D01*
X580883Y224188D01*
X580807Y223827D01*
X580883Y223465D01*
X581075Y223207D01*
X581382Y223052D01*
X581650Y223000D01*
G01X573350Y248050D02*
Y244950D01*
G01X572468Y248050D02*
X574232D01*
G01X575683Y244950D02*
Y248050D01*
X576603D01*
X576910Y247895D01*
X577140Y247533D01*
X577217Y247120D01*
X577140Y246707D01*
X576948Y246397D01*
X576603Y246242D01*
X575683D01*
G01X578707Y245570D02*
X578937Y245208D01*
X579243Y245002D01*
X579588Y244950D01*
X579895Y245002D01*
X580202Y245260D01*
X580393Y245570D01*
X580432Y245880D01*
X580355Y246242D01*
X580087Y246500D01*
X579818Y246603D01*
X579473D01*
G01X579818D02*
X580048Y246758D01*
X580240Y247017D01*
X580317Y247327D01*
X580240Y247637D01*
X580048Y247895D01*
X579703Y248050D01*
X579358Y247998D01*
X579013Y247792D01*
G01X581998Y245312D02*
X582267Y245053D01*
X582573Y244950D01*
X582880Y245053D01*
X583148Y245363D01*
X583340Y245828D01*
X583417Y246293D01*
Y246862D01*
X583340Y247327D01*
X583148Y247740D01*
X582918Y247947D01*
X582650Y248050D01*
X582343Y247947D01*
X582113Y247740D01*
X581960Y247430D01*
X581883Y247017D01*
X581960Y246655D01*
X582152Y246293D01*
X582382Y246087D01*
X582650Y246035D01*
X582957Y246138D01*
X583187Y246397D01*
X583417Y246862D01*
G01X578500Y260500D02*
Y263600D01*
X578040Y262980D01*
G01Y260500D02*
X578960D01*
G01X576848Y300862D02*
X577117Y300603D01*
X577423Y300500D01*
X577730Y300603D01*
X577998Y300913D01*
X578190Y301378D01*
X578267Y301843D01*
Y302412D01*
X578190Y302877D01*
X577998Y303290D01*
X577768Y303497D01*
X577500Y303600D01*
X577193Y303497D01*
X576963Y303290D01*
X576810Y302980D01*
X576733Y302567D01*
X576810Y302205D01*
X577002Y301843D01*
X577232Y301637D01*
X577500Y301585D01*
X577807Y301688D01*
X578037Y301947D01*
X578267Y302412D01*
G01X573393Y357992D02*
X573163Y358147D01*
X572895Y358250D01*
X572588D01*
X572243Y358095D01*
X571975Y357837D01*
X571783Y357527D01*
X571630Y357010D01*
X571592Y356545D01*
X571668Y356080D01*
X571783Y355770D01*
X572013Y355460D01*
X572282Y355253D01*
X572550Y355150D01*
X572818D01*
X573087Y355253D01*
X573317Y355408D01*
X573508Y355615D01*
G01X574807Y355770D02*
X575037Y355408D01*
X575343Y355202D01*
X575688Y355150D01*
X575995Y355202D01*
X576302Y355460D01*
X576493Y355770D01*
X576532Y356080D01*
X576455Y356442D01*
X576187Y356700D01*
X575918Y356803D01*
X575573D01*
G01X575918D02*
X576148Y356958D01*
X576340Y357217D01*
X576417Y357527D01*
X576340Y357837D01*
X576148Y358095D01*
X575803Y358250D01*
X575458Y358198D01*
X575113Y357992D01*
G01X571783Y350150D02*
Y353250D01*
X572742D01*
X573048Y353095D01*
X573240Y352888D01*
X573317Y352475D01*
X573240Y352062D01*
X573010Y351803D01*
X572742Y351648D01*
X571783D01*
G01X572742D02*
X573317Y350150D01*
G01X574807Y350615D02*
X575037Y350357D01*
X575305Y350202D01*
X575650Y350150D01*
X575995Y350253D01*
X576263Y350460D01*
X576455Y350822D01*
X576493Y351235D01*
X576417Y351648D01*
X576225Y351907D01*
X575957Y352113D01*
X575688Y352165D01*
X575420Y352113D01*
X575075Y351907D01*
X575190Y353250D01*
X576225D01*
G01X571783Y345150D02*
Y348250D01*
X572742D01*
X573048Y348095D01*
X573240Y347888D01*
X573317Y347475D01*
X573240Y347062D01*
X573010Y346803D01*
X572742Y346648D01*
X571783D01*
G01X572742D02*
X573317Y345150D01*
G01X576110D02*
Y348250D01*
X574692Y346028D01*
X576608D01*
G01X571393Y372492D02*
X571163Y372647D01*
X570895Y372750D01*
X570588D01*
X570243Y372595D01*
X569975Y372337D01*
X569783Y372027D01*
X569630Y371510D01*
X569592Y371045D01*
X569668Y370580D01*
X569783Y370270D01*
X570013Y369960D01*
X570282Y369753D01*
X570550Y369650D01*
X570818D01*
X571087Y369753D01*
X571317Y369908D01*
X571508Y370115D01*
G01X574110Y369650D02*
Y372750D01*
X572692Y370528D01*
X574608D01*
G01X571783Y365150D02*
Y368250D01*
X572742D01*
X573048Y368095D01*
X573240Y367888D01*
X573317Y367475D01*
X573240Y367062D01*
X573010Y366803D01*
X572742Y366648D01*
X571783D01*
G01X572742D02*
X573317Y365150D01*
G01X575650D02*
X575918Y365202D01*
X576225Y365357D01*
X576417Y365615D01*
X576493Y365977D01*
X576417Y366338D01*
X576187Y366648D01*
X575842Y366803D01*
X575458D01*
X575228Y366907D01*
X575037Y367165D01*
X574960Y367527D01*
X575075Y367888D01*
X575343Y368147D01*
X575650Y368250D01*
X575957Y368147D01*
X576225Y367888D01*
X576340Y367527D01*
X576263Y367165D01*
X576072Y366907D01*
X575842Y366803D01*
X575458D01*
X575113Y366648D01*
X574883Y366338D01*
X574807Y365977D01*
X574883Y365615D01*
X575075Y365357D01*
X575382Y365202D01*
X575650Y365150D01*
G01X571783Y360150D02*
Y363250D01*
X572742D01*
X573048Y363095D01*
X573240Y362888D01*
X573317Y362475D01*
X573240Y362062D01*
X573010Y361803D01*
X572742Y361648D01*
X571783D01*
G01X572742D02*
X573317Y360150D01*
G01X575573D02*
X575650Y360822D01*
X575765Y361390D01*
X575918Y361907D01*
X576110Y362475D01*
X576417Y363250D01*
X574883D01*
G01X573393Y386992D02*
X573163Y387147D01*
X572895Y387250D01*
X572588D01*
X572243Y387095D01*
X571975Y386837D01*
X571783Y386527D01*
X571630Y386010D01*
X571592Y385545D01*
X571668Y385080D01*
X571783Y384770D01*
X572013Y384460D01*
X572282Y384253D01*
X572550Y384150D01*
X572818D01*
X573087Y384253D01*
X573317Y384408D01*
X573508Y384615D01*
G01X575573Y384150D02*
X575650Y384822D01*
X575765Y385390D01*
X575918Y385907D01*
X576110Y386475D01*
X576417Y387250D01*
X574883D01*
G01X573393Y381992D02*
X573163Y382147D01*
X572895Y382250D01*
X572588D01*
X572243Y382095D01*
X571975Y381837D01*
X571783Y381527D01*
X571630Y381010D01*
X571592Y380545D01*
X571668Y380080D01*
X571783Y379770D01*
X572013Y379460D01*
X572282Y379253D01*
X572550Y379150D01*
X572818D01*
X573087Y379253D01*
X573317Y379408D01*
X573508Y379615D01*
G01X574807D02*
X575037Y379357D01*
X575305Y379202D01*
X575650Y379150D01*
X575995Y379253D01*
X576263Y379460D01*
X576455Y379822D01*
X576493Y380235D01*
X576417Y380648D01*
X576225Y380907D01*
X575957Y381113D01*
X575688Y381165D01*
X575420Y381113D01*
X575075Y380907D01*
X575190Y382250D01*
X576225D01*
G01X570233Y389150D02*
Y392250D01*
X571192D01*
X571498Y392095D01*
X571690Y391888D01*
X571767Y391475D01*
X571690Y391062D01*
X571460Y390803D01*
X571192Y390648D01*
X570233D01*
G01X571192D02*
X571767Y389150D01*
G01X574100D02*
Y392250D01*
X573640Y391630D01*
G01Y389150D02*
X574560D01*
G01X576357Y389615D02*
X576587Y389357D01*
X576855Y389202D01*
X577200Y389150D01*
X577545Y389253D01*
X577813Y389460D01*
X578005Y389822D01*
X578043Y390235D01*
X577967Y390648D01*
X577775Y390907D01*
X577507Y391113D01*
X577238Y391165D01*
X576970Y391113D01*
X576625Y390907D01*
X576740Y392250D01*
X577775D01*
G01X570233Y374150D02*
Y377250D01*
X571192D01*
X571498Y377095D01*
X571690Y376888D01*
X571767Y376475D01*
X571690Y376062D01*
X571460Y375803D01*
X571192Y375648D01*
X570233D01*
G01X571192D02*
X571767Y374150D01*
G01X574560D02*
Y377250D01*
X573142Y375028D01*
X575058D01*
G01X576472Y375442D02*
X576740Y375803D01*
X576970Y376010D01*
X577277Y376113D01*
X577545Y376010D01*
X577737Y375803D01*
X577890Y375493D01*
X577928Y375132D01*
X577890Y374822D01*
X577737Y374512D01*
X577507Y374253D01*
X577238Y374150D01*
X576932Y374253D01*
X576663Y374563D01*
X576510Y375028D01*
X576472Y375545D01*
X576548Y376217D01*
X576663Y376578D01*
X576855Y376940D01*
X577123Y377198D01*
X577392Y377250D01*
X577660Y377147D01*
X577852Y376888D01*
G01X571343Y405292D02*
X571113Y405447D01*
X570845Y405550D01*
X570538D01*
X570193Y405395D01*
X569925Y405137D01*
X569733Y404827D01*
X569580Y404310D01*
X569542Y403845D01*
X569618Y403380D01*
X569733Y403070D01*
X569963Y402760D01*
X570232Y402553D01*
X570500Y402450D01*
X570768D01*
X571037Y402553D01*
X571267Y402708D01*
X571458Y402915D01*
G01X579480Y405169D02*
X579250Y405324D01*
X578982Y405427D01*
X578675D01*
X578330Y405272D01*
X578062Y405014D01*
X577870Y404704D01*
X577717Y404187D01*
X577679Y403722D01*
X577755Y403257D01*
X577870Y402947D01*
X578100Y402637D01*
X578369Y402430D01*
X578637Y402327D01*
X578905D01*
X579174Y402430D01*
X579404Y402585D01*
X579595Y402792D01*
G01X580487Y406884D02*
X577387D01*
Y407650D01*
X577542Y407957D01*
X577749Y408187D01*
X578059Y408379D01*
X578420Y408532D01*
X578937Y408570D01*
X579454Y408532D01*
X579815Y408379D01*
X580125Y408187D01*
X580332Y407957D01*
X580487Y407650D01*
Y406884D01*
G01X580074Y410022D02*
X580332Y410329D01*
X580487Y410674D01*
Y410980D01*
X580332Y411287D01*
X580074Y411517D01*
X579712Y411632D01*
X579350Y411555D01*
X579040Y411364D01*
X578834Y411019D01*
X578730Y410559D01*
X578524Y410290D01*
X578162Y410175D01*
X577800Y410252D01*
X577542Y410444D01*
X577387Y410712D01*
Y410980D01*
X577490Y411249D01*
X577749Y411479D01*
G01X580022Y413084D02*
X580280Y413314D01*
X580435Y413582D01*
X580487Y413927D01*
X580384Y414272D01*
X580177Y414540D01*
X579815Y414732D01*
X579402Y414770D01*
X578989Y414694D01*
X578730Y414502D01*
X578524Y414234D01*
X578472Y413965D01*
X578524Y413697D01*
X578730Y413352D01*
X577387Y413467D01*
Y414502D01*
G01X568968Y415327D02*
X569926Y418427D01*
X570884Y415327D01*
G01X570539Y416412D02*
X569313D01*
G01X580542Y415450D02*
X581500Y418550D01*
X582458Y415450D01*
G01X582113Y416535D02*
X580887D01*
G01X584343Y422792D02*
X584113Y422947D01*
X583845Y423050D01*
X583538D01*
X583193Y422895D01*
X582925Y422637D01*
X582733Y422327D01*
X582580Y421810D01*
X582542Y421345D01*
X582618Y420880D01*
X582733Y420570D01*
X582963Y420260D01*
X583232Y420053D01*
X583500Y419950D01*
X583768D01*
X584037Y420053D01*
X584267Y420208D01*
X584458Y420415D01*
G01X580487Y420663D02*
X577387D01*
Y421429D01*
X577542Y421736D01*
X577749Y421966D01*
X578059Y422158D01*
X578420Y422311D01*
X578937Y422349D01*
X579454Y422311D01*
X579815Y422158D01*
X580125Y421966D01*
X580332Y421736D01*
X580487Y421429D01*
Y420663D01*
G01X580074Y423801D02*
X580332Y424108D01*
X580487Y424453D01*
Y424759D01*
X580332Y425066D01*
X580074Y425296D01*
X579712Y425411D01*
X579350Y425334D01*
X579040Y425143D01*
X578834Y424798D01*
X578730Y424338D01*
X578524Y424069D01*
X578162Y423954D01*
X577800Y424031D01*
X577542Y424223D01*
X577387Y424491D01*
Y424759D01*
X577490Y425028D01*
X577749Y425258D01*
G01X580487Y428166D02*
X577387D01*
X579609Y426748D01*
Y428664D01*
G01X571843Y422292D02*
X571613Y422447D01*
X571345Y422550D01*
X571038D01*
X570693Y422395D01*
X570425Y422137D01*
X570233Y421827D01*
X570080Y421310D01*
X570042Y420845D01*
X570118Y420380D01*
X570233Y420070D01*
X570463Y419760D01*
X570732Y419553D01*
X571000Y419450D01*
X571268D01*
X571537Y419553D01*
X571767Y419708D01*
X571958Y419915D01*
G01X577853Y429905D02*
X578811Y433005D01*
X579769Y429905D01*
G01X579424Y430990D02*
X578198D01*
G01X589583Y94950D02*
Y98050D01*
X590542D01*
X590848Y97895D01*
X591040Y97688D01*
X591117Y97275D01*
X591040Y96862D01*
X590810Y96603D01*
X590542Y96448D01*
X589583D01*
G01X590542D02*
X591117Y94950D01*
G01X593910D02*
Y98050D01*
X592492Y95828D01*
X594408D01*
G01X595822Y97533D02*
X596052Y97843D01*
X596320Y97998D01*
X596627Y98050D01*
X597010Y97947D01*
X597278Y97688D01*
X597355Y97378D01*
X597317Y97068D01*
X597163Y96810D01*
X596397Y96293D01*
X596052Y95932D01*
X595822Y95415D01*
X595745Y94950D01*
X597355D01*
G01X598807Y95570D02*
X599037Y95208D01*
X599343Y95002D01*
X599688Y94950D01*
X599995Y95002D01*
X600302Y95260D01*
X600493Y95570D01*
X600532Y95880D01*
X600455Y96242D01*
X600187Y96500D01*
X599918Y96603D01*
X599573D01*
G01X599918D02*
X600148Y96758D01*
X600340Y97017D01*
X600417Y97327D01*
X600340Y97637D01*
X600148Y97895D01*
X599803Y98050D01*
X599458Y97998D01*
X599113Y97792D01*
G01X589083Y106450D02*
Y109550D01*
X590042D01*
X590348Y109395D01*
X590540Y109188D01*
X590617Y108775D01*
X590540Y108362D01*
X590310Y108103D01*
X590042Y107948D01*
X589083D01*
G01X590042D02*
X590617Y106450D01*
G01X593410D02*
Y109550D01*
X591992Y107328D01*
X593908D01*
G01X596050Y109550D02*
X595743Y109447D01*
X595513Y109188D01*
X595360Y108878D01*
X595245Y108465D01*
X595207Y108000D01*
X595245Y107535D01*
X595360Y107122D01*
X595513Y106812D01*
X595743Y106553D01*
X596050Y106450D01*
X596357Y106553D01*
X596587Y106812D01*
X596740Y107122D01*
X596855Y107535D01*
X596893Y108000D01*
X596855Y108465D01*
X596740Y108878D01*
X596587Y109188D01*
X596357Y109447D01*
X596050Y109550D01*
G01X599073Y106450D02*
X599150Y107122D01*
X599265Y107690D01*
X599418Y108207D01*
X599610Y108775D01*
X599917Y109550D01*
X598383D01*
G01X589133Y111450D02*
Y114550D01*
X590092D01*
X590398Y114395D01*
X590590Y114188D01*
X590667Y113775D01*
X590590Y113362D01*
X590360Y113103D01*
X590092Y112948D01*
X589133D01*
G01X590092D02*
X590667Y111450D01*
G01X592272Y114033D02*
X592502Y114343D01*
X592770Y114498D01*
X593077Y114550D01*
X593460Y114447D01*
X593728Y114188D01*
X593805Y113878D01*
X593767Y113568D01*
X593613Y113310D01*
X592847Y112793D01*
X592502Y112432D01*
X592272Y111915D01*
X592195Y111450D01*
X593805D01*
G01X596100Y114550D02*
X595793Y114447D01*
X595563Y114188D01*
X595410Y113878D01*
X595295Y113465D01*
X595257Y113000D01*
X595295Y112535D01*
X595410Y112122D01*
X595563Y111812D01*
X595793Y111553D01*
X596100Y111450D01*
X596407Y111553D01*
X596637Y111812D01*
X596790Y112122D01*
X596905Y112535D01*
X596943Y113000D01*
X596905Y113465D01*
X596790Y113878D01*
X596637Y114188D01*
X596407Y114447D01*
X596100Y114550D01*
G01X589633Y100950D02*
Y104050D01*
X590592D01*
X590898Y103895D01*
X591090Y103688D01*
X591167Y103275D01*
X591090Y102862D01*
X590860Y102603D01*
X590592Y102448D01*
X589633D01*
G01X590592D02*
X591167Y100950D01*
G01X592772Y103533D02*
X593002Y103843D01*
X593270Y103998D01*
X593577Y104050D01*
X593960Y103947D01*
X594228Y103688D01*
X594305Y103378D01*
X594267Y103068D01*
X594113Y102810D01*
X593347Y102293D01*
X593002Y101932D01*
X592772Y101415D01*
X592695Y100950D01*
X594305D01*
G01X596600D02*
Y104050D01*
X596140Y103430D01*
G01Y100950D02*
X597060D01*
G01X592950Y117950D02*
Y121050D01*
X592490Y120430D01*
G01Y117950D02*
X593410D01*
G01X595322Y120533D02*
X595552Y120843D01*
X595820Y120998D01*
X596127Y121050D01*
X596510Y120947D01*
X596778Y120688D01*
X596855Y120378D01*
X596817Y120068D01*
X596663Y119810D01*
X595897Y119293D01*
X595552Y118932D01*
X595322Y118415D01*
X595245Y117950D01*
X596855D01*
G01X593452Y189098D02*
X590352D01*
Y190057D01*
X590507Y190363D01*
X590714Y190555D01*
X591127Y190632D01*
X591540Y190555D01*
X591799Y190325D01*
X591954Y190057D01*
Y189098D01*
G01Y190057D02*
X593452Y190632D01*
G01X592160Y192237D02*
X591799Y192505D01*
X591592Y192735D01*
X591489Y193042D01*
X591592Y193310D01*
X591799Y193502D01*
X592109Y193655D01*
X592470Y193693D01*
X592780Y193655D01*
X593090Y193502D01*
X593349Y193272D01*
X593452Y193003D01*
X593349Y192697D01*
X593039Y192428D01*
X592574Y192275D01*
X592057Y192237D01*
X591385Y192313D01*
X591024Y192428D01*
X590662Y192620D01*
X590404Y192888D01*
X590352Y193157D01*
X590455Y193425D01*
X590714Y193617D01*
G01X592160Y195337D02*
X591799Y195605D01*
X591592Y195835D01*
X591489Y196142D01*
X591592Y196410D01*
X591799Y196602D01*
X592109Y196755D01*
X592470Y196793D01*
X592780Y196755D01*
X593090Y196602D01*
X593349Y196372D01*
X593452Y196103D01*
X593349Y195797D01*
X593039Y195528D01*
X592574Y195375D01*
X592057Y195337D01*
X591385Y195413D01*
X591024Y195528D01*
X590662Y195720D01*
X590404Y195988D01*
X590352Y196257D01*
X590455Y196525D01*
X590714Y196717D01*
G01X598452Y189098D02*
X595352D01*
Y190057D01*
X595507Y190363D01*
X595714Y190555D01*
X596127Y190632D01*
X596540Y190555D01*
X596799Y190325D01*
X596954Y190057D01*
Y189098D01*
G01Y190057D02*
X598452Y190632D01*
G01X597160Y192237D02*
X596799Y192505D01*
X596592Y192735D01*
X596489Y193042D01*
X596592Y193310D01*
X596799Y193502D01*
X597109Y193655D01*
X597470Y193693D01*
X597780Y193655D01*
X598090Y193502D01*
X598349Y193272D01*
X598452Y193003D01*
X598349Y192697D01*
X598039Y192428D01*
X597574Y192275D01*
X597057Y192237D01*
X596385Y192313D01*
X596024Y192428D01*
X595662Y192620D01*
X595404Y192888D01*
X595352Y193157D01*
X595455Y193425D01*
X595714Y193617D01*
G01X598452Y196065D02*
X598400Y196333D01*
X598245Y196640D01*
X597987Y196832D01*
X597625Y196908D01*
X597264Y196832D01*
X596954Y196602D01*
X596799Y196257D01*
Y195873D01*
X596695Y195643D01*
X596437Y195452D01*
X596075Y195375D01*
X595714Y195490D01*
X595455Y195758D01*
X595352Y196065D01*
X595455Y196372D01*
X595714Y196640D01*
X596075Y196755D01*
X596437Y196678D01*
X596695Y196487D01*
X596799Y196257D01*
Y195873D01*
X596954Y195528D01*
X597264Y195298D01*
X597625Y195222D01*
X597987Y195298D01*
X598245Y195490D01*
X598400Y195797D01*
X598452Y196065D01*
G01X603050Y188083D02*
X599950D01*
Y189042D01*
X600105Y189348D01*
X600312Y189540D01*
X600725Y189617D01*
X601138Y189540D01*
X601397Y189310D01*
X601552Y189042D01*
Y188083D01*
G01Y189042D02*
X603050Y189617D01*
G01X600467Y191222D02*
X600157Y191452D01*
X600002Y191720D01*
X599950Y192027D01*
X600053Y192410D01*
X600312Y192678D01*
X600622Y192755D01*
X600932Y192717D01*
X601190Y192563D01*
X601707Y191797D01*
X602068Y191452D01*
X602585Y191222D01*
X603050Y191145D01*
Y192755D01*
G01X602688Y194398D02*
X602947Y194667D01*
X603050Y194973D01*
X602947Y195280D01*
X602637Y195548D01*
X602172Y195740D01*
X601707Y195817D01*
X601138D01*
X600673Y195740D01*
X600260Y195548D01*
X600053Y195318D01*
X599950Y195050D01*
X600053Y194743D01*
X600260Y194513D01*
X600570Y194360D01*
X600983Y194283D01*
X601345Y194360D01*
X601707Y194552D01*
X601913Y194782D01*
X601965Y195050D01*
X601862Y195357D01*
X601603Y195587D01*
X601138Y195817D01*
G01X602688Y197498D02*
X602947Y197767D01*
X603050Y198073D01*
X602947Y198380D01*
X602637Y198648D01*
X602172Y198840D01*
X601707Y198917D01*
X601138D01*
X600673Y198840D01*
X600260Y198648D01*
X600053Y198418D01*
X599950Y198150D01*
X600053Y197843D01*
X600260Y197613D01*
X600570Y197460D01*
X600983Y197383D01*
X601345Y197460D01*
X601707Y197652D01*
X601913Y197882D01*
X601965Y198150D01*
X601862Y198457D01*
X601603Y198687D01*
X601138Y198917D01*
G01X595772Y186033D02*
X596002Y186343D01*
X596270Y186498D01*
X596577Y186550D01*
X596960Y186447D01*
X597228Y186188D01*
X597305Y185878D01*
X597267Y185568D01*
X597113Y185310D01*
X596347Y184793D01*
X596002Y184432D01*
X595772Y183915D01*
X595695Y183450D01*
X597305D01*
G01X595057Y210550D02*
Y208328D01*
X595210Y207863D01*
X595517Y207553D01*
X595900Y207450D01*
X596283Y207553D01*
X596590Y207863D01*
X596743Y208328D01*
Y210550D01*
G01X598272Y210033D02*
X598502Y210343D01*
X598770Y210498D01*
X599077Y210550D01*
X599460Y210447D01*
X599728Y210188D01*
X599805Y209878D01*
X599767Y209568D01*
X599613Y209310D01*
X598847Y208793D01*
X598502Y208432D01*
X598272Y207915D01*
X598195Y207450D01*
X599805D01*
G01X602023D02*
X602100Y208122D01*
X602215Y208690D01*
X602368Y209207D01*
X602560Y209775D01*
X602867Y210550D01*
X601333D01*
G01X593000Y216450D02*
X593268Y216502D01*
X593575Y216657D01*
X593767Y216915D01*
X593843Y217277D01*
X593767Y217638D01*
X593537Y217948D01*
X593192Y218103D01*
X592808D01*
X592578Y218207D01*
X592387Y218465D01*
X592310Y218827D01*
X592425Y219188D01*
X592693Y219447D01*
X593000Y219550D01*
X593307Y219447D01*
X593575Y219188D01*
X593690Y218827D01*
X593613Y218465D01*
X593422Y218207D01*
X593192Y218103D01*
X592808D01*
X592463Y217948D01*
X592233Y217638D01*
X592157Y217277D01*
X592233Y216915D01*
X592425Y216657D01*
X592732Y216502D01*
X593000Y216450D01*
G01X601193Y228292D02*
X600963Y228447D01*
X600695Y228550D01*
X600388D01*
X600043Y228395D01*
X599775Y228137D01*
X599583Y227827D01*
X599430Y227310D01*
X599392Y226845D01*
X599468Y226380D01*
X599583Y226070D01*
X599813Y225760D01*
X600082Y225553D01*
X600350Y225450D01*
X600618D01*
X600887Y225553D01*
X601117Y225708D01*
X601308Y225915D01*
G01X602722Y228033D02*
X602952Y228343D01*
X603220Y228498D01*
X603527Y228550D01*
X603910Y228447D01*
X604178Y228188D01*
X604255Y227878D01*
X604217Y227568D01*
X604063Y227310D01*
X603297Y226793D01*
X602952Y226432D01*
X602722Y225915D01*
X602645Y225450D01*
X604255D01*
G01X606473D02*
X606550Y226122D01*
X606665Y226690D01*
X606818Y227207D01*
X607010Y227775D01*
X607317Y228550D01*
X605783D01*
G01X608807Y225915D02*
X609037Y225657D01*
X609305Y225502D01*
X609650Y225450D01*
X609995Y225553D01*
X610263Y225760D01*
X610455Y226122D01*
X610493Y226535D01*
X610417Y226948D01*
X610225Y227207D01*
X609957Y227413D01*
X609688Y227465D01*
X609420Y227413D01*
X609075Y227207D01*
X609190Y228550D01*
X610225D01*
G01X601193Y223792D02*
X600963Y223947D01*
X600695Y224050D01*
X600388D01*
X600043Y223895D01*
X599775Y223637D01*
X599583Y223327D01*
X599430Y222810D01*
X599392Y222345D01*
X599468Y221880D01*
X599583Y221570D01*
X599813Y221260D01*
X600082Y221053D01*
X600350Y220950D01*
X600618D01*
X600887Y221053D01*
X601117Y221208D01*
X601308Y221415D01*
G01X602722Y223533D02*
X602952Y223843D01*
X603220Y223998D01*
X603527Y224050D01*
X603910Y223947D01*
X604178Y223688D01*
X604255Y223378D01*
X604217Y223068D01*
X604063Y222810D01*
X603297Y222293D01*
X602952Y221932D01*
X602722Y221415D01*
X602645Y220950D01*
X604255D01*
G01X606473D02*
X606550Y221622D01*
X606665Y222190D01*
X606818Y222707D01*
X607010Y223275D01*
X607317Y224050D01*
X605783D01*
G01X610110Y220950D02*
Y224050D01*
X608692Y221828D01*
X610608D01*
G01X586636Y222350D02*
Y225450D01*
X587595D01*
X587901Y225295D01*
X588093Y225088D01*
X588170Y224675D01*
X588093Y224262D01*
X587863Y224003D01*
X587595Y223848D01*
X586636D01*
G01X587595D02*
X588170Y222350D01*
G01X589775Y224933D02*
X590005Y225243D01*
X590273Y225398D01*
X590580Y225450D01*
X590963Y225347D01*
X591231Y225088D01*
X591308Y224778D01*
X591270Y224468D01*
X591116Y224210D01*
X590350Y223693D01*
X590005Y223332D01*
X589775Y222815D01*
X589698Y222350D01*
X591308D01*
G01X592951Y222712D02*
X593220Y222453D01*
X593526Y222350D01*
X593833Y222453D01*
X594101Y222763D01*
X594293Y223228D01*
X594370Y223693D01*
Y224262D01*
X594293Y224727D01*
X594101Y225140D01*
X593871Y225347D01*
X593603Y225450D01*
X593296Y225347D01*
X593066Y225140D01*
X592913Y224830D01*
X592836Y224417D01*
X592913Y224055D01*
X593105Y223693D01*
X593335Y223487D01*
X593603Y223435D01*
X593910Y223538D01*
X594140Y223797D01*
X594370Y224262D01*
G01X595975Y223642D02*
X596243Y224003D01*
X596473Y224210D01*
X596780Y224313D01*
X597048Y224210D01*
X597240Y224003D01*
X597393Y223693D01*
X597431Y223332D01*
X597393Y223022D01*
X597240Y222712D01*
X597010Y222453D01*
X596741Y222350D01*
X596435Y222453D01*
X596166Y222763D01*
X596013Y223228D01*
X595975Y223745D01*
X596051Y224417D01*
X596166Y224778D01*
X596358Y225140D01*
X596626Y225398D01*
X596895Y225450D01*
X597163Y225347D01*
X597355Y225088D01*
G01X586636Y226852D02*
Y229952D01*
X587595D01*
X587901Y229797D01*
X588093Y229590D01*
X588170Y229177D01*
X588093Y228764D01*
X587863Y228505D01*
X587595Y228350D01*
X586636D01*
G01X587595D02*
X588170Y226852D01*
G01X589775Y229435D02*
X590005Y229745D01*
X590273Y229900D01*
X590580Y229952D01*
X590963Y229849D01*
X591231Y229590D01*
X591308Y229280D01*
X591270Y228970D01*
X591116Y228712D01*
X590350Y228195D01*
X590005Y227834D01*
X589775Y227317D01*
X589698Y226852D01*
X591308D01*
G01X592951Y227214D02*
X593220Y226955D01*
X593526Y226852D01*
X593833Y226955D01*
X594101Y227265D01*
X594293Y227730D01*
X594370Y228195D01*
Y228764D01*
X594293Y229229D01*
X594101Y229642D01*
X593871Y229849D01*
X593603Y229952D01*
X593296Y229849D01*
X593066Y229642D01*
X592913Y229332D01*
X592836Y228919D01*
X592913Y228557D01*
X593105Y228195D01*
X593335Y227989D01*
X593603Y227937D01*
X593910Y228040D01*
X594140Y228299D01*
X594370Y228764D01*
G01X596626Y226852D02*
X596703Y227524D01*
X596818Y228092D01*
X596971Y228609D01*
X597163Y229177D01*
X597470Y229952D01*
X595936D01*
G01X586636Y231450D02*
Y234550D01*
X587595D01*
X587901Y234395D01*
X588093Y234188D01*
X588170Y233775D01*
X588093Y233362D01*
X587863Y233103D01*
X587595Y232948D01*
X586636D01*
G01X587595D02*
X588170Y231450D01*
G01X589775Y234033D02*
X590005Y234343D01*
X590273Y234498D01*
X590580Y234550D01*
X590963Y234447D01*
X591231Y234188D01*
X591308Y233878D01*
X591270Y233568D01*
X591116Y233310D01*
X590350Y232793D01*
X590005Y232432D01*
X589775Y231915D01*
X589698Y231450D01*
X591308D01*
G01X592951Y231812D02*
X593220Y231553D01*
X593526Y231450D01*
X593833Y231553D01*
X594101Y231863D01*
X594293Y232328D01*
X594370Y232793D01*
Y233362D01*
X594293Y233827D01*
X594101Y234240D01*
X593871Y234447D01*
X593603Y234550D01*
X593296Y234447D01*
X593066Y234240D01*
X592913Y233930D01*
X592836Y233517D01*
X592913Y233155D01*
X593105Y232793D01*
X593335Y232587D01*
X593603Y232535D01*
X593910Y232638D01*
X594140Y232897D01*
X594370Y233362D01*
G01X596703Y231450D02*
X596971Y231502D01*
X597278Y231657D01*
X597470Y231915D01*
X597546Y232277D01*
X597470Y232638D01*
X597240Y232948D01*
X596895Y233103D01*
X596511D01*
X596281Y233207D01*
X596090Y233465D01*
X596013Y233827D01*
X596128Y234188D01*
X596396Y234447D01*
X596703Y234550D01*
X597010Y234447D01*
X597278Y234188D01*
X597393Y233827D01*
X597316Y233465D01*
X597125Y233207D01*
X596895Y233103D01*
X596511D01*
X596166Y232948D01*
X595936Y232638D01*
X595860Y232277D01*
X595936Y231915D01*
X596128Y231657D01*
X596435Y231502D01*
X596703Y231450D01*
G01X602133Y234466D02*
Y231366D01*
X603667D01*
G01X606000D02*
Y234466D01*
X605540Y233846D01*
G01Y231366D02*
X606460D01*
G01X609023D02*
X609100Y232038D01*
X609215Y232606D01*
X609368Y233123D01*
X609560Y233691D01*
X609867Y234466D01*
X608333D01*
G01X591433Y240591D02*
Y237491D01*
G01X590551Y240591D02*
X592315D01*
G01X593766Y237491D02*
Y240591D01*
X594686D01*
X594993Y240436D01*
X595223Y240074D01*
X595300Y239661D01*
X595223Y239248D01*
X595031Y238938D01*
X594686Y238783D01*
X593766D01*
G01X596905Y240074D02*
X597135Y240384D01*
X597403Y240539D01*
X597710Y240591D01*
X598093Y240488D01*
X598361Y240229D01*
X598438Y239919D01*
X598400Y239609D01*
X598246Y239351D01*
X597480Y238834D01*
X597135Y238473D01*
X596905Y237956D01*
X596828Y237491D01*
X598438D01*
G01X600005Y238783D02*
X600273Y239144D01*
X600503Y239351D01*
X600810Y239454D01*
X601078Y239351D01*
X601270Y239144D01*
X601423Y238834D01*
X601461Y238473D01*
X601423Y238163D01*
X601270Y237853D01*
X601040Y237594D01*
X600771Y237491D01*
X600465Y237594D01*
X600196Y237904D01*
X600043Y238369D01*
X600005Y238886D01*
X600081Y239558D01*
X600196Y239919D01*
X600388Y240281D01*
X600656Y240539D01*
X600925Y240591D01*
X601193Y240488D01*
X601385Y240229D01*
G01X592272Y261533D02*
X592502Y261843D01*
X592770Y261998D01*
X593077Y262050D01*
X593460Y261947D01*
X593728Y261688D01*
X593805Y261378D01*
X593767Y261068D01*
X593613Y260810D01*
X592847Y260293D01*
X592502Y259932D01*
X592272Y259415D01*
X592195Y258950D01*
X593805D01*
G01X589950Y300500D02*
Y303600D01*
X589490Y302980D01*
G01Y300500D02*
X590410D01*
G01X593050Y303600D02*
X592743Y303497D01*
X592513Y303238D01*
X592360Y302928D01*
X592245Y302515D01*
X592207Y302050D01*
X592245Y301585D01*
X592360Y301172D01*
X592513Y300862D01*
X592743Y300603D01*
X593050Y300500D01*
X593357Y300603D01*
X593587Y300862D01*
X593740Y301172D01*
X593855Y301585D01*
X593893Y302050D01*
X593855Y302515D01*
X593740Y302928D01*
X593587Y303238D01*
X593357Y303497D01*
X593050Y303600D01*
G01X587841Y323337D02*
X588109Y323698D01*
X588339Y323905D01*
X588646Y324008D01*
X588914Y323905D01*
X589106Y323698D01*
X589259Y323388D01*
X589297Y323027D01*
X589259Y322717D01*
X589106Y322407D01*
X588876Y322148D01*
X588607Y322045D01*
X588301Y322148D01*
X588032Y322458D01*
X587879Y322923D01*
X587841Y323440D01*
X587917Y324112D01*
X588032Y324473D01*
X588224Y324835D01*
X588492Y325093D01*
X588761Y325145D01*
X589029Y325042D01*
X589221Y324783D01*
G01X590020Y379791D02*
Y382891D01*
X588602Y380669D01*
X590518D01*
G01X591266Y405334D02*
X588166D01*
Y406100D01*
X588321Y406407D01*
X588528Y406637D01*
X588838Y406829D01*
X589199Y406982D01*
X589716Y407020D01*
X590233Y406982D01*
X590594Y406829D01*
X590904Y406637D01*
X591111Y406407D01*
X591266Y406100D01*
Y405334D01*
G01X590853Y408472D02*
X591111Y408779D01*
X591266Y409124D01*
Y409430D01*
X591111Y409737D01*
X590853Y409967D01*
X590491Y410082D01*
X590129Y410005D01*
X589819Y409814D01*
X589613Y409469D01*
X589509Y409009D01*
X589303Y408740D01*
X588941Y408625D01*
X588579Y408702D01*
X588321Y408894D01*
X588166Y409162D01*
Y409430D01*
X588269Y409699D01*
X588528Y409929D01*
G01X591266Y412377D02*
X588166D01*
X588786Y411917D01*
G01X591266D02*
Y412837D01*
G01X590904Y414825D02*
X591163Y415094D01*
X591266Y415400D01*
X591163Y415707D01*
X590853Y415975D01*
X590388Y416167D01*
X589923Y416244D01*
X589354D01*
X588889Y416167D01*
X588476Y415975D01*
X588269Y415745D01*
X588166Y415477D01*
X588269Y415170D01*
X588476Y414940D01*
X588786Y414787D01*
X589199Y414710D01*
X589561Y414787D01*
X589923Y414979D01*
X590129Y415209D01*
X590181Y415477D01*
X590078Y415784D01*
X589819Y416014D01*
X589354Y416244D01*
G01X594843Y404792D02*
X594613Y404947D01*
X594345Y405050D01*
X594038D01*
X593693Y404895D01*
X593425Y404637D01*
X593233Y404327D01*
X593080Y403810D01*
X593042Y403345D01*
X593118Y402880D01*
X593233Y402570D01*
X593463Y402260D01*
X593732Y402053D01*
X594000Y401950D01*
X594268D01*
X594537Y402053D01*
X594767Y402208D01*
X594958Y402415D01*
G01X604050Y406007D02*
X600950D01*
Y406773D01*
X601105Y407080D01*
X601312Y407310D01*
X601622Y407502D01*
X601983Y407655D01*
X602500Y407693D01*
X603017Y407655D01*
X603378Y407502D01*
X603688Y407310D01*
X603895Y407080D01*
X604050Y406773D01*
Y406007D01*
G01X603637Y409145D02*
X603895Y409452D01*
X604050Y409797D01*
Y410103D01*
X603895Y410410D01*
X603637Y410640D01*
X603275Y410755D01*
X602913Y410678D01*
X602603Y410487D01*
X602397Y410142D01*
X602293Y409682D01*
X602087Y409413D01*
X601725Y409298D01*
X601363Y409375D01*
X601105Y409567D01*
X600950Y409835D01*
Y410103D01*
X601053Y410372D01*
X601312Y410602D01*
G01X601467Y412322D02*
X601157Y412552D01*
X601002Y412820D01*
X600950Y413127D01*
X601053Y413510D01*
X601312Y413778D01*
X601622Y413855D01*
X601932Y413817D01*
X602190Y413663D01*
X602707Y412897D01*
X603068Y412552D01*
X603585Y412322D01*
X604050Y412245D01*
Y413855D01*
G01X600950Y416150D02*
X601053Y415843D01*
X601312Y415613D01*
X601622Y415460D01*
X602035Y415345D01*
X602500Y415307D01*
X602965Y415345D01*
X603378Y415460D01*
X603688Y415613D01*
X603947Y415843D01*
X604050Y416150D01*
X603947Y416457D01*
X603688Y416687D01*
X603378Y416840D01*
X602965Y416955D01*
X602500Y416993D01*
X602035Y416955D01*
X601622Y416840D01*
X601312Y416687D01*
X601053Y416457D01*
X600950Y416150D01*
G01X603843Y403292D02*
X603613Y403447D01*
X603345Y403550D01*
X603038D01*
X602693Y403395D01*
X602425Y403137D01*
X602233Y402827D01*
X602080Y402310D01*
X602042Y401845D01*
X602118Y401380D01*
X602233Y401070D01*
X602463Y400760D01*
X602732Y400553D01*
X603000Y400450D01*
X603268D01*
X603537Y400553D01*
X603767Y400708D01*
X603958Y400915D01*
G01X604050Y419507D02*
X600950D01*
Y420273D01*
X601105Y420580D01*
X601312Y420810D01*
X601622Y421002D01*
X601983Y421155D01*
X602500Y421193D01*
X603017Y421155D01*
X603378Y421002D01*
X603688Y420810D01*
X603895Y420580D01*
X604050Y420273D01*
Y419507D01*
G01X603637Y422645D02*
X603895Y422952D01*
X604050Y423297D01*
Y423603D01*
X603895Y423910D01*
X603637Y424140D01*
X603275Y424255D01*
X602913Y424178D01*
X602603Y423987D01*
X602397Y423642D01*
X602293Y423182D01*
X602087Y422913D01*
X601725Y422798D01*
X601363Y422875D01*
X601105Y423067D01*
X600950Y423335D01*
Y423603D01*
X601053Y423872D01*
X601312Y424102D01*
G01X604050Y426550D02*
X600950D01*
X601570Y426090D01*
G01X604050D02*
Y427010D01*
G01X600950Y429650D02*
X601053Y429343D01*
X601312Y429113D01*
X601622Y428960D01*
X602035Y428845D01*
X602500Y428807D01*
X602965Y428845D01*
X603378Y428960D01*
X603688Y429113D01*
X603947Y429343D01*
X604050Y429650D01*
X603947Y429957D01*
X603688Y430187D01*
X603378Y430340D01*
X602965Y430455D01*
X602500Y430493D01*
X602035Y430455D01*
X601622Y430340D01*
X601312Y430187D01*
X601053Y429957D01*
X600950Y429650D01*
G01X591581Y417569D02*
X588481Y418527D01*
X591581Y419485D01*
G01X590496Y419140D02*
Y417914D01*
G01X597542Y413450D02*
X598500Y416550D01*
X599458Y413450D01*
G01X599113Y414535D02*
X597887D01*
G01X601042Y432450D02*
X602000Y435550D01*
X602958Y432450D01*
G01X602613Y433535D02*
X601387D01*
G01X610560Y98200D02*
Y101300D01*
X609142Y99078D01*
X611058D01*
G01X613557Y106050D02*
Y103828D01*
X613710Y103363D01*
X614017Y103053D01*
X614400Y102950D01*
X614783Y103053D01*
X615090Y103363D01*
X615243Y103828D01*
Y106050D01*
G01X616657Y103570D02*
X616887Y103208D01*
X617193Y103002D01*
X617538Y102950D01*
X617845Y103002D01*
X618152Y103260D01*
X618343Y103570D01*
X618382Y103880D01*
X618305Y104242D01*
X618037Y104500D01*
X617768Y104603D01*
X617423D01*
G01X617768D02*
X617998Y104758D01*
X618190Y105017D01*
X618267Y105327D01*
X618190Y105637D01*
X617998Y105895D01*
X617653Y106050D01*
X617308Y105998D01*
X616963Y105792D01*
G01X619872Y104242D02*
X620140Y104603D01*
X620370Y104810D01*
X620677Y104913D01*
X620945Y104810D01*
X621137Y104603D01*
X621290Y104293D01*
X621328Y103932D01*
X621290Y103622D01*
X621137Y103312D01*
X620907Y103053D01*
X620638Y102950D01*
X620332Y103053D01*
X620063Y103363D01*
X619910Y103828D01*
X619872Y104345D01*
X619948Y105017D01*
X620063Y105378D01*
X620255Y105740D01*
X620523Y105998D01*
X620792Y106050D01*
X621060Y105947D01*
X621252Y105688D01*
G01X618450Y117450D02*
Y120550D01*
X617990Y119930D01*
G01Y117450D02*
X618910D01*
G01X621550D02*
Y120550D01*
X621090Y119930D01*
G01Y117450D02*
X622010D01*
G01X608452Y189098D02*
X605352D01*
Y190057D01*
X605507Y190363D01*
X605714Y190555D01*
X606127Y190632D01*
X606540Y190555D01*
X606799Y190325D01*
X606954Y190057D01*
Y189098D01*
G01Y190057D02*
X608452Y190632D01*
G01X607160Y192237D02*
X606799Y192505D01*
X606592Y192735D01*
X606489Y193042D01*
X606592Y193310D01*
X606799Y193502D01*
X607109Y193655D01*
X607470Y193693D01*
X607780Y193655D01*
X608090Y193502D01*
X608349Y193272D01*
X608452Y193003D01*
X608349Y192697D01*
X608039Y192428D01*
X607574Y192275D01*
X607057Y192237D01*
X606385Y192313D01*
X606024Y192428D01*
X605662Y192620D01*
X605404Y192888D01*
X605352Y193157D01*
X605455Y193425D01*
X605714Y193617D01*
G01X608452Y195988D02*
X607780Y196065D01*
X607212Y196180D01*
X606695Y196333D01*
X606127Y196525D01*
X605352Y196832D01*
Y195298D01*
G01X606960Y199450D02*
Y202550D01*
X605542Y200328D01*
X607458D01*
G01X618500Y184450D02*
Y187550D01*
X618040Y186930D01*
G01Y184450D02*
X618960D01*
G01X603657Y215915D02*
X603887Y215657D01*
X604155Y215502D01*
X604500Y215450D01*
X604845Y215553D01*
X605113Y215760D01*
X605305Y216122D01*
X605343Y216535D01*
X605267Y216948D01*
X605075Y217207D01*
X604807Y217413D01*
X604538Y217465D01*
X604270Y217413D01*
X603925Y217207D01*
X604040Y218550D01*
X605075D01*
G01X612808Y227643D02*
X612653Y227413D01*
X612550Y227145D01*
Y226838D01*
X612705Y226493D01*
X612963Y226225D01*
X613273Y226033D01*
X613790Y225880D01*
X614255Y225842D01*
X614720Y225918D01*
X615030Y226033D01*
X615340Y226263D01*
X615547Y226532D01*
X615650Y226800D01*
Y227068D01*
X615547Y227337D01*
X615392Y227567D01*
X615185Y227758D01*
G01X615650Y230360D02*
X612550D01*
X614772Y228942D01*
Y230858D01*
G01X612550Y233000D02*
X612653Y232693D01*
X612912Y232463D01*
X613222Y232310D01*
X613635Y232195D01*
X614100Y232157D01*
X614565Y232195D01*
X614978Y232310D01*
X615288Y232463D01*
X615547Y232693D01*
X615650Y233000D01*
X615547Y233307D01*
X615288Y233537D01*
X614978Y233690D01*
X614565Y233805D01*
X614100Y233843D01*
X613635Y233805D01*
X613222Y233690D01*
X612912Y233537D01*
X612653Y233307D01*
X612550Y233000D01*
G01X613030Y277633D02*
X613340Y277825D01*
X613547Y278055D01*
X613650Y278323D01*
X613547Y278630D01*
X613340Y278860D01*
X613030Y279090D01*
X612617Y279167D01*
X610550D01*
G01X613650Y281500D02*
X610550D01*
X611170Y281040D01*
G01X613650D02*
Y281960D01*
G01X610550Y284600D02*
X610653Y284293D01*
X610912Y284063D01*
X611222Y283910D01*
X611635Y283795D01*
X612100Y283757D01*
X612565Y283795D01*
X612978Y283910D01*
X613288Y284063D01*
X613547Y284293D01*
X613650Y284600D01*
X613547Y284907D01*
X613288Y285137D01*
X612978Y285290D01*
X612565Y285405D01*
X612100Y285443D01*
X611635Y285405D01*
X611222Y285290D01*
X610912Y285137D01*
X610653Y284907D01*
X610550Y284600D01*
G01X604981Y322175D02*
X605211Y321813D01*
X605517Y321607D01*
X605862Y321555D01*
X606169Y321607D01*
X606476Y321865D01*
X606667Y322175D01*
X606706Y322485D01*
X606629Y322847D01*
X606361Y323105D01*
X606092Y323208D01*
X605747D01*
G01X606092D02*
X606322Y323363D01*
X606514Y323622D01*
X606591Y323932D01*
X606514Y324242D01*
X606322Y324500D01*
X605977Y324655D01*
X605632Y324603D01*
X605287Y324397D01*
G01X612967Y348667D02*
X609867D01*
Y349587D01*
X610022Y349894D01*
X610384Y350124D01*
X610797Y350201D01*
X611210Y350124D01*
X611520Y349932D01*
X611675Y349587D01*
Y348667D01*
G01X612347Y351691D02*
X612709Y351921D01*
X612915Y352227D01*
X612967Y352572D01*
X612915Y352879D01*
X612657Y353186D01*
X612347Y353377D01*
X612037Y353416D01*
X611675Y353339D01*
X611417Y353071D01*
X611314Y352802D01*
Y352457D01*
G01Y352802D02*
X611159Y353032D01*
X610900Y353224D01*
X610590Y353301D01*
X610280Y353224D01*
X610022Y353032D01*
X609867Y352687D01*
X609919Y352342D01*
X610125Y351997D01*
G01X607182Y379178D02*
Y382278D01*
X606722Y381658D01*
G01Y379178D02*
X607642D01*
G01X620343Y404792D02*
X620113Y404947D01*
X619845Y405050D01*
X619538D01*
X619193Y404895D01*
X618925Y404637D01*
X618733Y404327D01*
X618580Y403810D01*
X618542Y403345D01*
X618618Y402880D01*
X618733Y402570D01*
X618963Y402260D01*
X619232Y402053D01*
X619500Y401950D01*
X619768D01*
X620037Y402053D01*
X620267Y402208D01*
X620458Y402415D01*
G01X616050Y405507D02*
X612950D01*
Y406273D01*
X613105Y406580D01*
X613312Y406810D01*
X613622Y407002D01*
X613983Y407155D01*
X614500Y407193D01*
X615017Y407155D01*
X615378Y407002D01*
X615688Y406810D01*
X615895Y406580D01*
X616050Y406273D01*
Y405507D01*
G01X615637Y408645D02*
X615895Y408952D01*
X616050Y409297D01*
Y409603D01*
X615895Y409910D01*
X615637Y410140D01*
X615275Y410255D01*
X614913Y410178D01*
X614603Y409987D01*
X614397Y409642D01*
X614293Y409182D01*
X614087Y408913D01*
X613725Y408798D01*
X613363Y408875D01*
X613105Y409067D01*
X612950Y409335D01*
Y409603D01*
X613053Y409872D01*
X613312Y410102D01*
G01X616050Y412550D02*
X612950D01*
X613570Y412090D01*
G01X616050D02*
Y413010D01*
G01X613467Y414922D02*
X613157Y415152D01*
X613002Y415420D01*
X612950Y415727D01*
X613053Y416110D01*
X613312Y416378D01*
X613622Y416455D01*
X613932Y416417D01*
X614190Y416263D01*
X614707Y415497D01*
X615068Y415152D01*
X615585Y414922D01*
X616050Y414845D01*
Y416455D01*
G01X607343Y422792D02*
X607113Y422947D01*
X606845Y423050D01*
X606538D01*
X606193Y422895D01*
X605925Y422637D01*
X605733Y422327D01*
X605580Y421810D01*
X605542Y421345D01*
X605618Y420880D01*
X605733Y420570D01*
X605963Y420260D01*
X606232Y420053D01*
X606500Y419950D01*
X606768D01*
X607037Y420053D01*
X607267Y420208D01*
X607458Y420415D01*
G01X619843Y421292D02*
X619613Y421447D01*
X619345Y421550D01*
X619038D01*
X618693Y421395D01*
X618425Y421137D01*
X618233Y420827D01*
X618080Y420310D01*
X618042Y419845D01*
X618118Y419380D01*
X618233Y419070D01*
X618463Y418760D01*
X618732Y418553D01*
X619000Y418450D01*
X619268D01*
X619537Y418553D01*
X619767Y418708D01*
X619958Y418915D01*
G01X616050Y419507D02*
X612950D01*
Y420273D01*
X613105Y420580D01*
X613312Y420810D01*
X613622Y421002D01*
X613983Y421155D01*
X614500Y421193D01*
X615017Y421155D01*
X615378Y421002D01*
X615688Y420810D01*
X615895Y420580D01*
X616050Y420273D01*
Y419507D01*
G01X615637Y422645D02*
X615895Y422952D01*
X616050Y423297D01*
Y423603D01*
X615895Y423910D01*
X615637Y424140D01*
X615275Y424255D01*
X614913Y424178D01*
X614603Y423987D01*
X614397Y423642D01*
X614293Y423182D01*
X614087Y422913D01*
X613725Y422798D01*
X613363Y422875D01*
X613105Y423067D01*
X612950Y423335D01*
Y423603D01*
X613053Y423872D01*
X613312Y424102D01*
G01X616050Y426550D02*
X612950D01*
X613570Y426090D01*
G01X616050D02*
Y427010D01*
G01Y429650D02*
X612950D01*
X613570Y429190D01*
G01X616050D02*
Y430110D01*
G01X610042Y412950D02*
X611000Y416050D01*
X611958Y412950D01*
G01X611613Y414035D02*
X610387D01*
G01X614042Y431950D02*
X615000Y435050D01*
X615958Y431950D01*
G01X615613Y433035D02*
X614387D01*
G01X634392Y63804D02*
Y66904D01*
X635389Y64321D01*
X636386Y66904D01*
Y63804D01*
G01X639256D02*
X637722D01*
Y66904D01*
X639256D01*
G01X638642Y65406D02*
X637722D01*
G01X641589Y63804D02*
Y66904D01*
X641129Y66284D01*
G01Y63804D02*
X642049D01*
G01X643961Y66387D02*
X644191Y66697D01*
X644459Y66852D01*
X644766Y66904D01*
X645149Y66801D01*
X645417Y66542D01*
X645494Y66232D01*
X645456Y65922D01*
X645302Y65664D01*
X644536Y65147D01*
X644191Y64786D01*
X643961Y64269D01*
X643884Y63804D01*
X645494D01*
G01X636193Y114792D02*
X635963Y114947D01*
X635695Y115050D01*
X635388D01*
X635043Y114895D01*
X634775Y114637D01*
X634583Y114327D01*
X634430Y113810D01*
X634392Y113345D01*
X634468Y112880D01*
X634583Y112570D01*
X634813Y112260D01*
X635082Y112053D01*
X635350Y111950D01*
X635618D01*
X635887Y112053D01*
X636117Y112208D01*
X636308Y112415D01*
G01X637607Y112570D02*
X637837Y112208D01*
X638143Y112002D01*
X638488Y111950D01*
X638795Y112002D01*
X639102Y112260D01*
X639293Y112570D01*
X639332Y112880D01*
X639255Y113242D01*
X638987Y113500D01*
X638718Y113603D01*
X638373D01*
G01X638718D02*
X638948Y113758D01*
X639140Y114017D01*
X639217Y114327D01*
X639140Y114637D01*
X638948Y114895D01*
X638603Y115050D01*
X638258Y114998D01*
X637913Y114792D01*
G01X641550Y115050D02*
X641243Y114947D01*
X641013Y114688D01*
X640860Y114378D01*
X640745Y113965D01*
X640707Y113500D01*
X640745Y113035D01*
X640860Y112622D01*
X641013Y112312D01*
X641243Y112053D01*
X641550Y111950D01*
X641857Y112053D01*
X642087Y112312D01*
X642240Y112622D01*
X642355Y113035D01*
X642393Y113500D01*
X642355Y113965D01*
X642240Y114378D01*
X642087Y114688D01*
X641857Y114947D01*
X641550Y115050D01*
G01X643807Y112415D02*
X644037Y112157D01*
X644305Y112002D01*
X644650Y111950D01*
X644995Y112053D01*
X645263Y112260D01*
X645455Y112622D01*
X645493Y113035D01*
X645417Y113448D01*
X645225Y113707D01*
X644957Y113913D01*
X644688Y113965D01*
X644420Y113913D01*
X644075Y113707D01*
X644190Y115050D01*
X645225D01*
G01X634583Y95982D02*
Y99082D01*
X635542D01*
X635848Y98927D01*
X636040Y98720D01*
X636117Y98307D01*
X636040Y97894D01*
X635810Y97635D01*
X635542Y97480D01*
X634583D01*
G01X635542D02*
X636117Y95982D01*
G01X638910D02*
Y99082D01*
X637492Y96860D01*
X639408D01*
G01X641550Y95982D02*
Y99082D01*
X641090Y98462D01*
G01Y95982D02*
X642010D01*
G01X644650Y99082D02*
X644343Y98979D01*
X644113Y98720D01*
X643960Y98410D01*
X643845Y97997D01*
X643807Y97532D01*
X643845Y97067D01*
X643960Y96654D01*
X644113Y96344D01*
X644343Y96085D01*
X644650Y95982D01*
X644957Y96085D01*
X645187Y96344D01*
X645340Y96654D01*
X645455Y97067D01*
X645493Y97532D01*
X645455Y97997D01*
X645340Y98410D01*
X645187Y98720D01*
X644957Y98979D01*
X644650Y99082D01*
G01X634583Y100450D02*
Y103550D01*
X635542D01*
X635848Y103395D01*
X636040Y103188D01*
X636117Y102775D01*
X636040Y102362D01*
X635810Y102103D01*
X635542Y101948D01*
X634583D01*
G01X635542D02*
X636117Y100450D01*
G01X638910D02*
Y103550D01*
X637492Y101328D01*
X639408D01*
G01X641550Y100450D02*
Y103550D01*
X641090Y102930D01*
G01Y100450D02*
X642010D01*
G01X645110D02*
Y103550D01*
X643692Y101328D01*
X645608D01*
G01X634583Y106450D02*
Y109550D01*
X635542D01*
X635848Y109395D01*
X636040Y109188D01*
X636117Y108775D01*
X636040Y108362D01*
X635810Y108103D01*
X635542Y107948D01*
X634583D01*
G01X635542D02*
X636117Y106450D01*
G01X638910D02*
Y109550D01*
X637492Y107328D01*
X639408D01*
G01X641550Y106450D02*
Y109550D01*
X641090Y108930D01*
G01Y106450D02*
X642010D01*
G01X643998Y106812D02*
X644267Y106553D01*
X644573Y106450D01*
X644880Y106553D01*
X645148Y106863D01*
X645340Y107328D01*
X645417Y107793D01*
Y108362D01*
X645340Y108827D01*
X645148Y109240D01*
X644918Y109447D01*
X644650Y109550D01*
X644343Y109447D01*
X644113Y109240D01*
X643960Y108930D01*
X643883Y108517D01*
X643960Y108155D01*
X644152Y107793D01*
X644382Y107587D01*
X644650Y107535D01*
X644957Y107638D01*
X645187Y107897D01*
X645417Y108362D01*
G01X626015Y106845D02*
X626283Y106897D01*
X626590Y107052D01*
X626782Y107310D01*
X626858Y107672D01*
X626782Y108033D01*
X626552Y108343D01*
X626207Y108498D01*
X625823D01*
X625593Y108602D01*
X625402Y108860D01*
X625325Y109222D01*
X625440Y109583D01*
X625708Y109842D01*
X626015Y109945D01*
X626322Y109842D01*
X626590Y109583D01*
X626705Y109222D01*
X626628Y108860D01*
X626437Y108602D01*
X626207Y108498D01*
X625823D01*
X625478Y108343D01*
X625248Y108033D01*
X625172Y107672D01*
X625248Y107310D01*
X625440Y107052D01*
X625747Y106897D01*
X626015Y106845D01*
G01X625172Y99310D02*
X625402Y99052D01*
X625670Y98897D01*
X626015Y98845D01*
X626360Y98948D01*
X626628Y99155D01*
X626820Y99517D01*
X626858Y99930D01*
X626782Y100343D01*
X626590Y100602D01*
X626322Y100808D01*
X626053Y100860D01*
X625785Y100808D01*
X625440Y100602D01*
X625555Y101945D01*
X626590D01*
G01X623683Y150570D02*
X623875Y150260D01*
X624105Y150053D01*
X624373Y149950D01*
X624680Y150053D01*
X624910Y150260D01*
X625140Y150570D01*
X625217Y150983D01*
Y153050D01*
G01X626707Y150415D02*
X626937Y150157D01*
X627205Y150002D01*
X627550Y149950D01*
X627895Y150053D01*
X628163Y150260D01*
X628355Y150622D01*
X628393Y151035D01*
X628317Y151448D01*
X628125Y151707D01*
X627857Y151913D01*
X627588Y151965D01*
X627320Y151913D01*
X626975Y151707D01*
X627090Y153050D01*
X628125D01*
G01X637034Y197103D02*
Y197870D01*
X637964D01*
X638274Y197640D01*
X638481Y197371D01*
X638584Y196988D01*
X638481Y196605D01*
X638274Y196336D01*
X637964Y196106D01*
X637602Y195953D01*
X637189Y195876D01*
X636827D01*
X636517Y195953D01*
X636156Y196106D01*
X635846Y196336D01*
X635639Y196566D01*
X635484Y196873D01*
Y197141D01*
X635587Y197448D01*
X635794Y197678D01*
G01X638584Y199168D02*
X635484D01*
G01Y200778D02*
X638584D01*
G01X637034D02*
Y199168D01*
G01X638584Y203073D02*
X635484D01*
X636104Y202613D01*
G01X638584D02*
Y203533D01*
G01X627608Y196917D02*
X627453Y196687D01*
X627350Y196419D01*
Y196112D01*
X627505Y195767D01*
X627763Y195499D01*
X628073Y195307D01*
X628590Y195154D01*
X629055Y195116D01*
X629520Y195192D01*
X629830Y195307D01*
X630140Y195537D01*
X630347Y195806D01*
X630450Y196074D01*
Y196342D01*
X630347Y196611D01*
X630192Y196841D01*
X629985Y197032D01*
G01X629158Y198446D02*
X628797Y198714D01*
X628590Y198944D01*
X628487Y199251D01*
X628590Y199519D01*
X628797Y199711D01*
X629107Y199864D01*
X629468Y199902D01*
X629778Y199864D01*
X630088Y199711D01*
X630347Y199481D01*
X630450Y199212D01*
X630347Y198906D01*
X630037Y198637D01*
X629572Y198484D01*
X629055Y198446D01*
X628383Y198522D01*
X628022Y198637D01*
X627660Y198829D01*
X627402Y199097D01*
X627350Y199366D01*
X627453Y199634D01*
X627712Y199826D01*
G01X629830Y201431D02*
X630192Y201661D01*
X630398Y201967D01*
X630450Y202312D01*
X630398Y202619D01*
X630140Y202926D01*
X629830Y203117D01*
X629520Y203156D01*
X629158Y203079D01*
X628900Y202811D01*
X628797Y202542D01*
Y202197D01*
G01Y202542D02*
X628642Y202772D01*
X628383Y202964D01*
X628073Y203041D01*
X627763Y202964D01*
X627505Y202772D01*
X627350Y202427D01*
X627402Y202082D01*
X627608Y201737D01*
G01X621208Y198117D02*
X621053Y197887D01*
X620950Y197619D01*
Y197312D01*
X621105Y196967D01*
X621363Y196699D01*
X621673Y196507D01*
X622190Y196354D01*
X622655Y196316D01*
X623120Y196392D01*
X623430Y196507D01*
X623740Y196737D01*
X623947Y197006D01*
X624050Y197274D01*
Y197542D01*
X623947Y197811D01*
X623792Y198041D01*
X623585Y198232D01*
G01X622758Y199646D02*
X622397Y199914D01*
X622190Y200144D01*
X622087Y200451D01*
X622190Y200719D01*
X622397Y200911D01*
X622707Y201064D01*
X623068Y201102D01*
X623378Y201064D01*
X623688Y200911D01*
X623947Y200681D01*
X624050Y200412D01*
X623947Y200106D01*
X623637Y199837D01*
X623172Y199684D01*
X622655Y199646D01*
X621983Y199722D01*
X621622Y199837D01*
X621260Y200029D01*
X621002Y200297D01*
X620950Y200566D01*
X621053Y200834D01*
X621312Y201026D01*
G01X624050Y203474D02*
X620950D01*
X621570Y203014D01*
G01X624050D02*
Y203934D01*
G01X637550Y205500D02*
X634450D01*
X635070Y205040D01*
G01X637550D02*
Y205960D01*
G01X637256Y215812D02*
X637514Y216042D01*
X637669Y216310D01*
X637721Y216655D01*
X637618Y217000D01*
X637411Y217268D01*
X637049Y217460D01*
X636636Y217498D01*
X636223Y217422D01*
X635964Y217230D01*
X635758Y216962D01*
X635706Y216693D01*
X635758Y216425D01*
X635964Y216080D01*
X634621Y216195D01*
Y217230D01*
G01X629961Y216326D02*
X630229Y216687D01*
X630459Y216894D01*
X630766Y216997D01*
X631034Y216894D01*
X631226Y216687D01*
X631379Y216377D01*
X631417Y216016D01*
X631379Y215706D01*
X631226Y215396D01*
X630996Y215137D01*
X630727Y215034D01*
X630421Y215137D01*
X630152Y215447D01*
X629999Y215912D01*
X629961Y216429D01*
X630037Y217101D01*
X630152Y217462D01*
X630344Y217824D01*
X630612Y218082D01*
X630881Y218134D01*
X631149Y218031D01*
X631341Y217772D01*
G01X623549Y214834D02*
Y217934D01*
X622131Y215712D01*
X624047D01*
G01X637500Y220630D02*
Y221397D01*
X638430D01*
X638740Y221167D01*
X638947Y220898D01*
X639050Y220515D01*
X638947Y220132D01*
X638740Y219863D01*
X638430Y219633D01*
X638068Y219480D01*
X637655Y219403D01*
X637293D01*
X636983Y219480D01*
X636622Y219633D01*
X636312Y219863D01*
X636105Y220093D01*
X635950Y220400D01*
Y220668D01*
X636053Y220975D01*
X636260Y221205D01*
G01X639050Y222695D02*
X635950D01*
G01Y224305D02*
X639050D01*
G01X637500D02*
Y222695D01*
G01X636467Y225872D02*
X636157Y226102D01*
X636002Y226370D01*
X635950Y226677D01*
X636053Y227060D01*
X636312Y227328D01*
X636622Y227405D01*
X636932Y227367D01*
X637190Y227213D01*
X637707Y226447D01*
X638068Y226102D01*
X638585Y225872D01*
X639050Y225795D01*
Y227405D01*
G01X621657Y234994D02*
X621887Y234632D01*
X622193Y234426D01*
X622538Y234374D01*
X622845Y234426D01*
X623152Y234684D01*
X623343Y234994D01*
X623382Y235304D01*
X623305Y235666D01*
X623037Y235924D01*
X622768Y236027D01*
X622423D01*
G01X622768D02*
X622998Y236182D01*
X623190Y236441D01*
X623267Y236751D01*
X623190Y237061D01*
X622998Y237319D01*
X622653Y237474D01*
X622308Y237422D01*
X621963Y237216D01*
G01X625439Y223441D02*
X627661D01*
X628126Y223594D01*
X628436Y223901D01*
X628539Y224284D01*
X628436Y224667D01*
X628126Y224974D01*
X627661Y225127D01*
X625439D01*
G01X628177Y226732D02*
X628436Y227001D01*
X628539Y227307D01*
X628436Y227614D01*
X628126Y227882D01*
X627661Y228074D01*
X627196Y228151D01*
X626627D01*
X626162Y228074D01*
X625749Y227882D01*
X625542Y227652D01*
X625439Y227384D01*
X625542Y227077D01*
X625749Y226847D01*
X626059Y226694D01*
X626472Y226617D01*
X626834Y226694D01*
X627196Y226886D01*
X627402Y227116D01*
X627454Y227384D01*
X627351Y227691D01*
X627092Y227921D01*
X626627Y228151D01*
G01X632000Y258950D02*
Y262050D01*
X631540Y261430D01*
G01Y258950D02*
X632460D01*
G01X631348Y300812D02*
X631617Y300553D01*
X631923Y300450D01*
X632230Y300553D01*
X632498Y300863D01*
X632690Y301328D01*
X632767Y301793D01*
Y302362D01*
X632690Y302827D01*
X632498Y303240D01*
X632268Y303447D01*
X632000Y303550D01*
X631693Y303447D01*
X631463Y303240D01*
X631310Y302930D01*
X631233Y302517D01*
X631310Y302155D01*
X631502Y301793D01*
X631732Y301587D01*
X632000Y301535D01*
X632307Y301638D01*
X632537Y301897D01*
X632767Y302362D01*
G01X634392Y416285D02*
Y419385D01*
X635389Y416802D01*
X636386Y419385D01*
Y416285D01*
G01X639256D02*
X637722D01*
Y419385D01*
X639256D01*
G01X638642Y417887D02*
X637722D01*
G01X641589Y416285D02*
Y419385D01*
X641129Y418765D01*
G01Y416285D02*
X642049D01*
G01X644689D02*
Y419385D01*
X644229Y418765D01*
G01Y416285D02*
X645149D01*
G01X653950Y187504D02*
Y188271D01*
X654880D01*
X655190Y188041D01*
X655397Y187772D01*
X655500Y187389D01*
X655397Y187006D01*
X655190Y186737D01*
X654880Y186507D01*
X654518Y186354D01*
X654105Y186277D01*
X653743D01*
X653433Y186354D01*
X653072Y186507D01*
X652762Y186737D01*
X652555Y186967D01*
X652400Y187274D01*
Y187542D01*
X652503Y187849D01*
X652710Y188079D01*
G01X655500Y189569D02*
X652400D01*
G01Y191179D02*
X655500D01*
G01X653950D02*
Y189569D01*
G01X654880Y192631D02*
X655242Y192861D01*
X655448Y193167D01*
X655500Y193512D01*
X655448Y193819D01*
X655190Y194126D01*
X654880Y194317D01*
X654570Y194356D01*
X654208Y194279D01*
X653950Y194011D01*
X653847Y193742D01*
Y193397D01*
G01Y193742D02*
X653692Y193972D01*
X653433Y194164D01*
X653123Y194241D01*
X652813Y194164D01*
X652555Y193972D01*
X652400Y193627D01*
X652452Y193282D01*
X652658Y192937D01*
G01X647197Y207157D02*
X647507Y207349D01*
X647714Y207579D01*
X647817Y207847D01*
X647714Y208154D01*
X647507Y208384D01*
X647197Y208614D01*
X646784Y208691D01*
X644717D01*
G01X647817Y211024D02*
X644717D01*
X645337Y210564D01*
G01X647817D02*
Y211484D01*
G01Y214124D02*
X644717D01*
X645337Y213664D01*
G01X647817D02*
Y214584D01*
G01X653450Y229004D02*
Y229771D01*
X654380D01*
X654690Y229541D01*
X654897Y229272D01*
X655000Y228889D01*
X654897Y228506D01*
X654690Y228237D01*
X654380Y228007D01*
X654018Y227854D01*
X653605Y227777D01*
X653243D01*
X652933Y227854D01*
X652572Y228007D01*
X652262Y228237D01*
X652055Y228467D01*
X651900Y228774D01*
Y229042D01*
X652003Y229349D01*
X652210Y229579D01*
G01X655000Y231069D02*
X651900D01*
G01Y232679D02*
X655000D01*
G01X653450D02*
Y231069D01*
G01X655000Y235434D02*
X651900D01*
X654122Y234016D01*
Y235932D01*
G01X657316Y206209D02*
Y206976D01*
X658246D01*
X658556Y206746D01*
X658763Y206477D01*
X658866Y206094D01*
X658763Y205711D01*
X658556Y205442D01*
X658246Y205212D01*
X657884Y205059D01*
X657471Y204982D01*
X657109D01*
X656799Y205059D01*
X656438Y205212D01*
X656128Y205442D01*
X655921Y205672D01*
X655766Y205979D01*
Y206247D01*
X655869Y206554D01*
X656076Y206784D01*
G01X658866Y209079D02*
X655766D01*
X656386Y208619D01*
G01X658866D02*
Y209539D01*
G01X657243Y214229D02*
Y214996D01*
X658173D01*
X658483Y214766D01*
X658690Y214497D01*
X658793Y214114D01*
X658690Y213731D01*
X658483Y213462D01*
X658173Y213232D01*
X657811Y213079D01*
X657398Y213002D01*
X657036D01*
X656726Y213079D01*
X656365Y213232D01*
X656055Y213462D01*
X655848Y213692D01*
X655693Y213999D01*
Y214267D01*
X655796Y214574D01*
X656003Y214804D01*
G01X656210Y216371D02*
X655900Y216601D01*
X655745Y216869D01*
X655693Y217176D01*
X655796Y217559D01*
X656055Y217827D01*
X656365Y217904D01*
X656675Y217866D01*
X656933Y217712D01*
X657450Y216946D01*
X657811Y216601D01*
X658328Y216371D01*
X658793Y216294D01*
Y217904D01*
M02*
